G04 ================== begin FILE IDENTIFICATION RECORD ==================*
G04 Layout Name:  D:/<user>/Wistron_project/16317-1/gbr/16317-1.brd*
G04 Film Name:    16317-1_X_Y*
G04 File Format:  Gerber RS274X*
G04 File Origin:  Cadence Allegro 16.5-S056*
G04 Origin Date:  Fri Jun 09 15:52:29 2017*
G04 *
G04 Layer:  BOARD GEOMETRY/PANEL_DRAWING*
G04 *
G04 Offset:    (0.00 0.00)*
G04 Mirror:    No*
G04 Mode:      Positive*
G04 Rotation:  0*
G04 FullContactRelief:  No*
G04 UndefLineWidth:     6.00*
G04 ================== end FILE IDENTIFICATION RECORD ====================*
%FSLAX35Y35*MOIN*%
%IR0*IPPOS*OFA0.00000B0.00000*MIA0B0*SFA1.00000B1.00000*%
%ADD10C,.006*%
G75*
%LPD*%
G75*
G54D10*
G01X-417922Y-264869D02*
X-417209Y-266010D01*
X-416354Y-266770D01*
X-415356Y-267150D01*
X-414215Y-266770D01*
X-413359Y-266010D01*
X-412504Y-264869D01*
X-412219Y-263348D01*
Y-255743D01*
G01X-416782Y-39861D02*
X-413360D01*
G01X-415071D02*
Y-51268D01*
G01X-416782D02*
X-413360D01*
G01X-418065Y164424D02*
Y175831D01*
G01X-412076D02*
Y164424D01*
G01Y170127D02*
X-418065D01*
G01X-414215Y386009D02*
X-411363D01*
Y382587D01*
X-412219Y381446D01*
X-413217Y380686D01*
X-414643Y380306D01*
X-416069Y380686D01*
X-417067Y381446D01*
X-417922Y382587D01*
X-418493Y383918D01*
X-418778Y385439D01*
Y386770D01*
X-418493Y387910D01*
X-417922Y389242D01*
X-417067Y390382D01*
X-416211Y391142D01*
X-415071Y391713D01*
X-414072D01*
X-412932Y391333D01*
X-412076Y390572D01*
G01X-418158Y596378D02*
Y607785D01*
X-412739D01*
G01X-414736Y602272D02*
X-418158D01*
G01X-412219Y812449D02*
X-417922D01*
Y823856D01*
X-412219D01*
G01X-414500Y818343D02*
X-417922D01*
G01X-418207Y1028141D02*
Y1039548D01*
X-415356D01*
X-414215Y1038977D01*
X-413359Y1038217D01*
X-412646Y1037077D01*
X-412076Y1035745D01*
X-411934Y1033844D01*
X-412076Y1031943D01*
X-412646Y1030612D01*
X-413359Y1029472D01*
X-414215Y1028711D01*
X-415356Y1028141D01*
X-418207D01*
G01X-411934Y1254669D02*
X-412789Y1255240D01*
X-413787Y1255620D01*
X-414928D01*
X-416211Y1255049D01*
X-417209Y1254099D01*
X-417922Y1252958D01*
X-418493Y1251057D01*
X-418635Y1249346D01*
X-418350Y1247635D01*
X-417922Y1246494D01*
X-417067Y1245353D01*
X-416069Y1244593D01*
X-415071Y1244213D01*
X-414072D01*
X-413074Y1244593D01*
X-412219Y1245163D01*
X-411506Y1245924D01*
G01X-413930Y1465989D02*
X-413359Y1466559D01*
X-412932Y1467509D01*
X-412646Y1468841D01*
X-412932Y1469981D01*
X-413502Y1470741D01*
X-414500Y1471312D01*
X-418350D01*
Y1459905D01*
X-413645D01*
X-412646Y1460665D01*
X-412076Y1461806D01*
X-411791Y1463137D01*
X-412076Y1464468D01*
X-412932Y1465608D01*
X-413930Y1465989D01*
X-418350D01*
G01X-418635Y1675787D02*
X-415071Y1687194D01*
X-411506Y1675787D01*
G01X-412789Y1679779D02*
X-417352D01*
G01X-288193Y-384560D02*
Y-373153D01*
X-289904Y-375434D01*
G01Y-384560D02*
X-286482D01*
G01X-288193Y1793196D02*
Y1804603D01*
X-289904Y1802322D01*
G01Y1793196D02*
X-286482D01*
G01X-104443Y3937D02*
X-105231Y3675D01*
X-105821Y3018D01*
X-106215Y2231D01*
X-106510Y1181D01*
X-106609Y0D01*
X-106510Y-1181D01*
X-106215Y-2231D01*
X-105821Y-3019D01*
X-105231Y-3675D01*
X-104443Y-3937D01*
X-103656Y-3675D01*
X-103065Y-3019D01*
X-102671Y-2231D01*
X-102376Y-1181D01*
X-102277Y0D01*
X-102376Y1181D01*
X-102671Y2231D01*
X-103065Y3018D01*
X-103656Y3675D01*
X-104443Y3937D01*
G01X-96568Y-4199D02*
X-96765Y-4068D01*
Y-3806D01*
X-96568Y-3675D01*
X-96371Y-3806D01*
Y-4068D01*
X-96568Y-4199D01*
G01X-88693Y3937D02*
X-89481Y3675D01*
X-90071Y3018D01*
X-90465Y2231D01*
X-90760Y1181D01*
X-90859Y0D01*
X-90760Y-1181D01*
X-90465Y-2231D01*
X-90071Y-3019D01*
X-89481Y-3675D01*
X-88693Y-3937D01*
X-87906Y-3675D01*
X-87315Y-3019D01*
X-86921Y-2231D01*
X-86626Y-1181D01*
X-86527Y0D01*
X-86626Y1181D01*
X-86921Y2231D01*
X-87315Y3018D01*
X-87906Y3675D01*
X-88693Y3937D01*
G01X-80818D02*
X-81606Y3675D01*
X-82196Y3018D01*
X-82590Y2231D01*
X-82885Y1181D01*
X-82984Y0D01*
X-82885Y-1181D01*
X-82590Y-2231D01*
X-82196Y-3019D01*
X-81606Y-3675D01*
X-80818Y-3937D01*
X-80031Y-3675D01*
X-79440Y-3019D01*
X-79046Y-2231D01*
X-78751Y-1181D01*
X-78652Y0D01*
X-78751Y1181D01*
X-79046Y2231D01*
X-79440Y3018D01*
X-80031Y3675D01*
X-80818Y3937D01*
G01X-121963Y1517323D02*
X-121372Y1516404D01*
X-120585Y1515879D01*
X-119698Y1515748D01*
X-118911Y1515879D01*
X-118124Y1516535D01*
X-117631Y1517323D01*
X-117533Y1518110D01*
X-117730Y1519029D01*
X-118419Y1519685D01*
X-119108Y1519948D01*
X-119994D01*
G01X-119108D02*
X-118517Y1520341D01*
X-118025Y1520997D01*
X-117828Y1521785D01*
X-118025Y1522572D01*
X-118517Y1523228D01*
X-119403Y1523622D01*
X-120289Y1523491D01*
X-121175Y1522966D01*
G01X-111922Y1515748D02*
X-111233Y1515879D01*
X-110446Y1516273D01*
X-109953Y1516929D01*
X-109756Y1517848D01*
X-109953Y1518766D01*
X-110544Y1519554D01*
X-111430Y1519948D01*
X-112414D01*
X-113005Y1520210D01*
X-113497Y1520866D01*
X-113694Y1521785D01*
X-113398Y1522703D01*
X-112710Y1523360D01*
X-111922Y1523622D01*
X-111135Y1523360D01*
X-110446Y1522703D01*
X-110150Y1521785D01*
X-110347Y1520866D01*
X-110839Y1520210D01*
X-111430Y1519948D01*
X-112414D01*
X-113300Y1519554D01*
X-113891Y1518766D01*
X-114088Y1517848D01*
X-113891Y1516929D01*
X-113398Y1516273D01*
X-112611Y1515879D01*
X-111922Y1515748D01*
G01X-105917Y1519029D02*
X-105228Y1519948D01*
X-104638Y1520472D01*
X-103850Y1520735D01*
X-103161Y1520472D01*
X-102669Y1519948D01*
X-102275Y1519160D01*
X-102177Y1518241D01*
X-102275Y1517454D01*
X-102669Y1516666D01*
X-103260Y1516010D01*
X-103948Y1515748D01*
X-104736Y1516010D01*
X-105425Y1516798D01*
X-105819Y1517979D01*
X-105917Y1519291D01*
X-105720Y1520997D01*
X-105425Y1521916D01*
X-104933Y1522835D01*
X-104244Y1523491D01*
X-103555Y1523622D01*
X-102866Y1523360D01*
X-102374Y1522703D01*
G01X-96172Y1515486D02*
X-96369Y1515617D01*
Y1515879D01*
X-96172Y1516010D01*
X-95975Y1515879D01*
Y1515617D01*
X-96172Y1515486D01*
G01X-88297Y1523622D02*
X-89085Y1523360D01*
X-89675Y1522703D01*
X-90069Y1521916D01*
X-90364Y1520866D01*
X-90463Y1519685D01*
X-90364Y1518504D01*
X-90069Y1517454D01*
X-89675Y1516666D01*
X-89085Y1516010D01*
X-88297Y1515748D01*
X-87510Y1516010D01*
X-86919Y1516666D01*
X-86525Y1517454D01*
X-86230Y1518504D01*
X-86131Y1519685D01*
X-86230Y1520866D01*
X-86525Y1521916D01*
X-86919Y1522703D01*
X-87510Y1523360D01*
X-88297Y1523622D01*
G01X-80422D02*
X-81210Y1523360D01*
X-81800Y1522703D01*
X-82194Y1521916D01*
X-82489Y1520866D01*
X-82588Y1519685D01*
X-82489Y1518504D01*
X-82194Y1517454D01*
X-81800Y1516666D01*
X-81210Y1516010D01*
X-80422Y1515748D01*
X-79635Y1516010D01*
X-79044Y1516666D01*
X-78650Y1517454D01*
X-78355Y1518504D01*
X-78256Y1519685D01*
X-78355Y1520866D01*
X-78650Y1521916D01*
X-79044Y1522703D01*
X-79635Y1523360D01*
X-80422Y1523622D01*
G01X-73126Y-375054D02*
X-72270Y-373914D01*
X-71272Y-373343D01*
X-70131Y-373153D01*
X-68705Y-373533D01*
X-67707Y-374484D01*
X-67422Y-375624D01*
X-67565Y-376765D01*
X-68135Y-377716D01*
X-70987Y-379617D01*
X-72270Y-380948D01*
X-73126Y-382849D01*
X-73411Y-384560D01*
X-67422D01*
G01X-3937Y1607117D02*
X-3675Y1606329D01*
X-3018Y1605739D01*
X-2231Y1605345D01*
X-1181Y1605050D01*
X0Y1604951D01*
X1181Y1605050D01*
X2231Y1605345D01*
X3019Y1605739D01*
X3675Y1606329D01*
X3937Y1607117D01*
X3675Y1607904D01*
X3019Y1608495D01*
X2231Y1608889D01*
X1181Y1609184D01*
X0Y1609283D01*
X-1181Y1609184D01*
X-2231Y1608889D01*
X-3018Y1608495D01*
X-3675Y1607904D01*
X-3937Y1607117D01*
G01X4199Y1614992D02*
X4068Y1614795D01*
X3806D01*
X3675Y1614992D01*
X3806Y1615189D01*
X4068D01*
X4199Y1614992D01*
G01X-3937Y1622867D02*
X-3675Y1622079D01*
X-3018Y1621489D01*
X-2231Y1621095D01*
X-1181Y1620800D01*
X0Y1620701D01*
X1181Y1620800D01*
X2231Y1621095D01*
X3019Y1621489D01*
X3675Y1622079D01*
X3937Y1622867D01*
X3675Y1623654D01*
X3019Y1624245D01*
X2231Y1624639D01*
X1181Y1624934D01*
X0Y1625033D01*
X-1181Y1624934D01*
X-2231Y1624639D01*
X-3018Y1624245D01*
X-3675Y1623654D01*
X-3937Y1622867D01*
G01Y1630742D02*
X-3675Y1629954D01*
X-3018Y1629364D01*
X-2231Y1628970D01*
X-1181Y1628675D01*
X0Y1628576D01*
X1181Y1628675D01*
X2231Y1628970D01*
X3019Y1629364D01*
X3675Y1629954D01*
X3937Y1630742D01*
X3675Y1631529D01*
X3019Y1632120D01*
X2231Y1632514D01*
X1181Y1632809D01*
X0Y1632908D01*
X-1181Y1632809D01*
X-2231Y1632514D01*
X-3018Y1632120D01*
X-3675Y1631529D01*
X-3937Y1630742D01*
G01X-73126Y1802702D02*
X-72270Y1803842D01*
X-71272Y1804413D01*
X-70131Y1804603D01*
X-68705Y1804223D01*
X-67707Y1803272D01*
X-67422Y1802132D01*
X-67565Y1800991D01*
X-68135Y1800040D01*
X-70987Y1798139D01*
X-72270Y1796808D01*
X-73126Y1794907D01*
X-73411Y1793196D01*
X-67422D01*
G01X146116Y-382279D02*
X146971Y-383610D01*
X148112Y-384370D01*
X149395Y-384560D01*
X150536Y-384370D01*
X151677Y-383420D01*
X152389Y-382279D01*
X152532Y-381138D01*
X152247Y-379807D01*
X151249Y-378857D01*
X150251Y-378476D01*
X148967D01*
G01X150251D02*
X151106Y-377906D01*
X151819Y-376956D01*
X152104Y-375815D01*
X151819Y-374674D01*
X151106Y-373724D01*
X149823Y-373153D01*
X148540Y-373343D01*
X147256Y-374104D01*
G01X146116Y1795477D02*
X146971Y1794146D01*
X148112Y1793386D01*
X149395Y1793196D01*
X150536Y1793386D01*
X151677Y1794336D01*
X152389Y1795477D01*
X152532Y1796618D01*
X152247Y1797949D01*
X151249Y1798899D01*
X150251Y1799280D01*
X148967D01*
G01X150251D02*
X151106Y1799850D01*
X151819Y1800800D01*
X152104Y1801941D01*
X151819Y1803082D01*
X151106Y1804032D01*
X149823Y1804603D01*
X148540Y1804413D01*
X147256Y1803652D01*
G01X370633Y-384560D02*
Y-373153D01*
X365357Y-381328D01*
X372486D01*
G01X370633Y1793196D02*
Y1804603D01*
X365357Y1796428D01*
X372486D01*
G01X585455Y-382849D02*
X586310Y-383800D01*
X587308Y-384370D01*
X588591Y-384560D01*
X589875Y-384180D01*
X590873Y-383420D01*
X591586Y-382089D01*
X591728Y-380568D01*
X591443Y-379047D01*
X590730Y-378096D01*
X589732Y-377336D01*
X588734Y-377146D01*
X587736Y-377336D01*
X586453Y-378096D01*
X586880Y-373153D01*
X590730D01*
G01X585455Y1794907D02*
X586310Y1793956D01*
X587308Y1793386D01*
X588591Y1793196D01*
X589875Y1793576D01*
X590873Y1794336D01*
X591586Y1795667D01*
X591728Y1797188D01*
X591443Y1798709D01*
X590730Y1799660D01*
X589732Y1800420D01*
X588734Y1800610D01*
X587736Y1800420D01*
X586453Y1799660D01*
X586880Y1804603D01*
X590730D01*
G01X805551Y-379807D02*
X806549Y-378476D01*
X807405Y-377716D01*
X808546Y-377336D01*
X809544Y-377716D01*
X810257Y-378476D01*
X810827Y-379617D01*
X810970Y-380948D01*
X810827Y-382089D01*
X810257Y-383229D01*
X809401Y-384180D01*
X808403Y-384560D01*
X807262Y-384180D01*
X806264Y-383039D01*
X805694Y-381328D01*
X805551Y-379427D01*
X805836Y-376956D01*
X806264Y-375624D01*
X806977Y-374294D01*
X807975Y-373343D01*
X808973Y-373153D01*
X809972Y-373533D01*
X810685Y-374484D01*
G01X805551Y1797949D02*
X806549Y1799280D01*
X807405Y1800040D01*
X808546Y1800420D01*
X809544Y1800040D01*
X810257Y1799280D01*
X810827Y1798139D01*
X810970Y1796808D01*
X810827Y1795667D01*
X810257Y1794527D01*
X809401Y1793576D01*
X808403Y1793196D01*
X807262Y1793576D01*
X806264Y1794717D01*
X805694Y1796428D01*
X805551Y1798329D01*
X805836Y1800800D01*
X806264Y1802132D01*
X806977Y1803462D01*
X807975Y1804413D01*
X808973Y1804603D01*
X809972Y1804223D01*
X810685Y1803272D01*
G01X1027644Y-384560D02*
X1027929Y-382089D01*
X1028357Y-379997D01*
X1028928Y-378096D01*
X1029641Y-376005D01*
X1030781Y-373153D01*
X1025078D01*
G01X1027644Y1793196D02*
X1027929Y1795667D01*
X1028357Y1797759D01*
X1028928Y1799660D01*
X1029641Y1801751D01*
X1030781Y1804603D01*
X1025078D01*
G01X1062824Y888219D02*
Y872619D01*
G01X1058339Y888219D02*
X1067309D01*
G01X1247599Y-384560D02*
X1248598Y-384370D01*
X1249738Y-383800D01*
X1250451Y-382849D01*
X1250736Y-381518D01*
X1250451Y-380188D01*
X1249596Y-379047D01*
X1248312Y-378476D01*
X1246887D01*
X1246031Y-378096D01*
X1245318Y-377146D01*
X1245033Y-375815D01*
X1245461Y-374484D01*
X1246459Y-373533D01*
X1247599Y-373153D01*
X1248740Y-373533D01*
X1249738Y-374484D01*
X1250166Y-375815D01*
X1249881Y-377146D01*
X1249168Y-378096D01*
X1248312Y-378476D01*
X1246887D01*
X1245603Y-379047D01*
X1244748Y-380188D01*
X1244463Y-381518D01*
X1244748Y-382849D01*
X1245461Y-383800D01*
X1246601Y-384370D01*
X1247599Y-384560D01*
G01Y1793196D02*
X1248598Y1793386D01*
X1249738Y1793956D01*
X1250451Y1794907D01*
X1250736Y1796238D01*
X1250451Y1797568D01*
X1249596Y1798709D01*
X1248312Y1799280D01*
X1246887D01*
X1246031Y1799660D01*
X1245318Y1800610D01*
X1245033Y1801941D01*
X1245461Y1803272D01*
X1246459Y1804223D01*
X1247599Y1804603D01*
X1248740Y1804223D01*
X1249738Y1803272D01*
X1250166Y1801941D01*
X1249881Y1800610D01*
X1249168Y1799660D01*
X1248312Y1799280D01*
X1246887D01*
X1245603Y1798709D01*
X1244748Y1797568D01*
X1244463Y1796238D01*
X1244748Y1794907D01*
X1245461Y1793956D01*
X1246601Y1793386D01*
X1247599Y1793196D01*
G01X1464844Y-383229D02*
X1465843Y-384180D01*
X1466983Y-384560D01*
X1468124Y-384180D01*
X1469122Y-383039D01*
X1469835Y-381328D01*
X1470120Y-379617D01*
Y-377526D01*
X1469835Y-375815D01*
X1469122Y-374294D01*
X1468267Y-373533D01*
X1467268Y-373153D01*
X1466128Y-373533D01*
X1465272Y-374294D01*
X1464702Y-375434D01*
X1464417Y-376956D01*
X1464702Y-378286D01*
X1465415Y-379617D01*
X1466270Y-380378D01*
X1467268Y-380568D01*
X1468409Y-380188D01*
X1469265Y-379237D01*
X1470120Y-377526D01*
G01X1464844Y1794527D02*
X1465843Y1793576D01*
X1466983Y1793196D01*
X1468124Y1793576D01*
X1469122Y1794717D01*
X1469835Y1796428D01*
X1470120Y1798139D01*
Y1800230D01*
X1469835Y1801941D01*
X1469122Y1803462D01*
X1468267Y1804223D01*
X1467268Y1804603D01*
X1466128Y1804223D01*
X1465272Y1803462D01*
X1464702Y1802322D01*
X1464417Y1800800D01*
X1464702Y1799470D01*
X1465415Y1798139D01*
X1466270Y1797378D01*
X1467268Y1797188D01*
X1468409Y1797568D01*
X1469265Y1798519D01*
X1470120Y1800230D01*
G01X1684286Y-384560D02*
Y-373153D01*
X1682575Y-375434D01*
G01Y-384560D02*
X1685997D01*
G01X1695693Y-373153D02*
X1694553Y-373533D01*
X1693697Y-374484D01*
X1693127Y-375624D01*
X1692699Y-377146D01*
X1692557Y-378857D01*
X1692699Y-380568D01*
X1693127Y-382089D01*
X1693697Y-383229D01*
X1694553Y-384180D01*
X1695693Y-384560D01*
X1696834Y-384180D01*
X1697690Y-383229D01*
X1698260Y-382089D01*
X1698688Y-380568D01*
X1698830Y-378857D01*
X1698688Y-377146D01*
X1698260Y-375624D01*
X1697690Y-374484D01*
X1696834Y-373533D01*
X1695693Y-373153D01*
G01X1684286Y1793196D02*
Y1804603D01*
X1682575Y1802322D01*
G01Y1793196D02*
X1685997D01*
G01X1695693Y1804603D02*
X1694553Y1804223D01*
X1693697Y1803272D01*
X1693127Y1802132D01*
X1692699Y1800610D01*
X1692557Y1798899D01*
X1692699Y1797188D01*
X1693127Y1795667D01*
X1693697Y1794527D01*
X1694553Y1793576D01*
X1695693Y1793196D01*
X1696834Y1793576D01*
X1697690Y1794527D01*
X1698260Y1795667D01*
X1698688Y1797188D01*
X1698830Y1798899D01*
X1698688Y1800610D01*
X1698260Y1802132D01*
X1697690Y1803272D01*
X1696834Y1804223D01*
X1695693Y1804603D01*
G01X1754008Y-268353D02*
X1752508Y-267353D01*
X1750758Y-266686D01*
X1748758D01*
X1746508Y-267686D01*
X1744758Y-269353D01*
X1743508Y-271353D01*
X1742508Y-274686D01*
X1742258Y-277686D01*
X1742758Y-280686D01*
X1743508Y-282686D01*
X1745008Y-284686D01*
X1746758Y-286019D01*
X1748508Y-286686D01*
X1750258D01*
X1752008Y-286019D01*
X1753508Y-285020D01*
X1754758Y-283687D01*
G01X1765008Y-286686D02*
Y-273353D01*
G01Y-276019D02*
X1766258Y-274686D01*
X1767508Y-273686D01*
X1769258Y-273353D01*
X1770508Y-273686D01*
X1772008Y-274686D01*
G01X1784758Y-277686D02*
X1792758D01*
X1792008Y-275353D01*
X1790758Y-274020D01*
X1789008Y-273353D01*
X1787258Y-273686D01*
X1785758Y-274686D01*
X1784758Y-277020D01*
X1784258Y-279020D01*
Y-281019D01*
X1784758Y-283020D01*
X1786008Y-285020D01*
X1787508Y-286353D01*
X1789258Y-286686D01*
X1791008Y-286019D01*
X1792758Y-284020D01*
G01X1813008Y-286686D02*
Y-273353D01*
G01Y-275686D02*
X1812008Y-274353D01*
X1810508Y-273686D01*
X1808758Y-273353D01*
X1807008Y-274020D01*
X1805508Y-275353D01*
X1804508Y-277353D01*
X1804008Y-280020D01*
X1804508Y-282686D01*
X1805508Y-284686D01*
X1807008Y-286019D01*
X1808758Y-286686D01*
X1810508Y-286353D01*
X1812008Y-285353D01*
X1813008Y-284020D01*
G01X1828508Y-266686D02*
Y-286686D01*
G01X1825008Y-273353D02*
X1832008D01*
G01X1844758Y-277686D02*
X1852758D01*
X1852008Y-275353D01*
X1850758Y-274020D01*
X1849008Y-273353D01*
X1847258Y-273686D01*
X1845758Y-274686D01*
X1844758Y-277020D01*
X1844258Y-279020D01*
Y-281019D01*
X1844758Y-283020D01*
X1846008Y-285020D01*
X1847508Y-286353D01*
X1849258Y-286686D01*
X1851008Y-286019D01*
X1852758Y-284020D01*
G01X1873008Y-266686D02*
Y-286686D01*
G01Y-283687D02*
X1872008Y-285353D01*
X1870508Y-286353D01*
X1868758Y-286686D01*
X1866758Y-286019D01*
X1865258Y-284353D01*
X1864258Y-282353D01*
X1864008Y-280020D01*
X1864258Y-277686D01*
X1865258Y-275686D01*
X1866758Y-274020D01*
X1868758Y-273353D01*
X1870508Y-273686D01*
X1871758Y-274353D01*
X1873008Y-275686D01*
G01X1739556Y-217778D02*
X1745806Y-237778D01*
X1752056Y-217778D01*
G01X1762056Y-228778D02*
X1770056D01*
X1769306Y-226445D01*
X1768056Y-225112D01*
X1766306Y-224445D01*
X1764556Y-224778D01*
X1763056Y-225778D01*
X1762056Y-228112D01*
X1761556Y-230112D01*
Y-232111D01*
X1762056Y-234112D01*
X1763306Y-236112D01*
X1764806Y-237445D01*
X1766556Y-237778D01*
X1768306Y-237111D01*
X1770056Y-235112D01*
G01X1782306Y-237778D02*
Y-224445D01*
G01Y-227111D02*
X1783556Y-225778D01*
X1784806Y-224778D01*
X1786556Y-224445D01*
X1787806Y-224778D01*
X1789306Y-225778D01*
G01X1802056Y-235445D02*
X1803306Y-236778D01*
X1805056Y-237778D01*
X1806556D01*
X1808056Y-237111D01*
X1809056Y-236112D01*
X1809556Y-234779D01*
X1809306Y-232778D01*
X1808306Y-231778D01*
X1803806Y-229778D01*
X1802806Y-227444D01*
X1803306Y-225778D01*
X1804306Y-224778D01*
X1805806Y-224445D01*
X1807306Y-224778D01*
X1808806Y-225778D01*
G01X1825806Y-224445D02*
Y-237778D01*
G01Y-219112D02*
X1825306Y-218778D01*
Y-218111D01*
X1825806Y-217778D01*
X1826306Y-218111D01*
Y-218778D01*
X1825806Y-219112D01*
G01X1845806Y-237778D02*
X1844306Y-237445D01*
X1842806Y-236112D01*
X1841806Y-233778D01*
X1841306Y-231112D01*
X1841806Y-228445D01*
X1842806Y-226111D01*
X1844306Y-224778D01*
X1845806Y-224445D01*
X1847306Y-224778D01*
X1848806Y-226111D01*
X1849806Y-228445D01*
X1850056Y-231112D01*
X1849806Y-233778D01*
X1848806Y-236112D01*
X1847306Y-237445D01*
X1845806Y-237778D01*
G01X1861556D02*
Y-224445D01*
G01Y-227778D02*
X1862556Y-226111D01*
X1864056Y-224778D01*
X1866056Y-224445D01*
X1867806Y-224778D01*
X1869306Y-226111D01*
X1870056Y-228445D01*
Y-237778D01*
G01X1743508Y-193765D02*
Y-173765D01*
X1749508D01*
X1751508Y-174765D01*
X1753008Y-177098D01*
X1753508Y-179765D01*
X1753008Y-182432D01*
X1751758Y-184432D01*
X1749508Y-185432D01*
X1743508D01*
G01X1774008Y-175432D02*
X1772508Y-174432D01*
X1770758Y-173765D01*
X1768758D01*
X1766508Y-174765D01*
X1764758Y-176432D01*
X1763508Y-178432D01*
X1762508Y-181765D01*
X1762258Y-184765D01*
X1762758Y-187765D01*
X1763508Y-189765D01*
X1765008Y-191765D01*
X1766758Y-193098D01*
X1768508Y-193765D01*
X1770258D01*
X1772008Y-193098D01*
X1773508Y-192099D01*
X1774758Y-190766D01*
G01X1790508Y-183098D02*
X1791508Y-182098D01*
X1792258Y-180432D01*
X1792758Y-178098D01*
X1792258Y-176098D01*
X1791258Y-174765D01*
X1789508Y-173765D01*
X1782758D01*
Y-193765D01*
X1791008D01*
X1792758Y-192432D01*
X1793758Y-190432D01*
X1794258Y-188098D01*
X1793758Y-185765D01*
X1792258Y-183765D01*
X1790508Y-183098D01*
X1782758D01*
G01X1822758Y-193765D02*
Y-173765D01*
X1834258Y-193765D01*
Y-173765D01*
G01X1848508Y-193765D02*
X1847008Y-193432D01*
X1845508Y-192099D01*
X1844508Y-189765D01*
X1844008Y-187099D01*
X1844508Y-184432D01*
X1845508Y-182098D01*
X1847008Y-180765D01*
X1848508Y-180432D01*
X1850008Y-180765D01*
X1851508Y-182098D01*
X1852508Y-184432D01*
X1852758Y-187099D01*
X1852508Y-189765D01*
X1851508Y-192099D01*
X1850008Y-193432D01*
X1848508Y-193765D01*
G01X1868508Y-194432D02*
X1868008Y-194098D01*
Y-193432D01*
X1868508Y-193098D01*
X1869008Y-193432D01*
Y-194098D01*
X1868508Y-194432D01*
G01X1751953Y-149552D02*
Y-124552D01*
X1760143Y-145385D01*
X1768333Y-124552D01*
Y-149552D01*
G01X1785343D02*
X1783453Y-149135D01*
X1781563Y-147469D01*
X1780303Y-144552D01*
X1779673Y-141219D01*
X1780303Y-137886D01*
X1781563Y-134969D01*
X1783453Y-133302D01*
X1785343Y-132886D01*
X1787233Y-133302D01*
X1789123Y-134969D01*
X1790383Y-137886D01*
X1790698Y-141219D01*
X1790383Y-144552D01*
X1789123Y-147469D01*
X1787233Y-149135D01*
X1785343Y-149552D01*
G01X1816213Y-124552D02*
Y-149552D01*
G01Y-145803D02*
X1814953Y-147886D01*
X1813063Y-149135D01*
X1810858Y-149552D01*
X1808338Y-148719D01*
X1806448Y-146636D01*
X1805188Y-144136D01*
X1804873Y-141219D01*
X1805188Y-138302D01*
X1806448Y-135802D01*
X1808338Y-133719D01*
X1810858Y-132886D01*
X1813063Y-133302D01*
X1814638Y-134136D01*
X1816213Y-135802D01*
G01X1831018Y-138302D02*
X1841098D01*
X1840153Y-135385D01*
X1838578Y-133719D01*
X1836373Y-132886D01*
X1834168Y-133302D01*
X1832278Y-134552D01*
X1831018Y-137469D01*
X1830388Y-139969D01*
Y-142469D01*
X1831018Y-144969D01*
X1832593Y-147469D01*
X1834483Y-149135D01*
X1836688Y-149552D01*
X1838893Y-148719D01*
X1841098Y-146219D01*
G01X1860943Y-149552D02*
Y-124552D01*
G01X1904713Y-384560D02*
Y-373153D01*
X1903002Y-375434D01*
G01Y-384560D02*
X1906424D01*
G01X1916120D02*
Y-373153D01*
X1914409Y-375434D01*
G01Y-384560D02*
X1917831D01*
G01X1904713Y1793196D02*
Y1804603D01*
X1903002Y1802322D01*
G01Y1793196D02*
X1906424D01*
G01X1916120D02*
Y1804603D01*
X1914409Y1802322D01*
G01Y1793196D02*
X1917831D01*
G01X1921687Y-318221D02*
X1926097Y-343221D01*
X1931137Y-318221D01*
X1936177Y-343221D01*
X1940587Y-318221D01*
G01X1956337Y-326555D02*
Y-343221D01*
G01Y-319888D02*
X1955707Y-319471D01*
Y-318638D01*
X1956337Y-318221D01*
X1956967Y-318638D01*
Y-319471D01*
X1956337Y-319888D01*
G01X1976812Y-340305D02*
X1978387Y-341971D01*
X1980592Y-343221D01*
X1982482D01*
X1984372Y-342388D01*
X1985632Y-341138D01*
X1986262Y-339472D01*
X1985947Y-336971D01*
X1984687Y-335721D01*
X1979017Y-333222D01*
X1977757Y-330304D01*
X1978387Y-328221D01*
X1979647Y-326971D01*
X1981537Y-326555D01*
X1983427Y-326971D01*
X1985317Y-328221D01*
G01X2006737Y-318221D02*
Y-343221D01*
G01X2002327Y-326555D02*
X2011147D01*
G01X2027527Y-343221D02*
Y-326555D01*
G01Y-329887D02*
X2029102Y-328221D01*
X2030677Y-326971D01*
X2032882Y-326555D01*
X2034457Y-326971D01*
X2036347Y-328221D01*
G01X2057137Y-343221D02*
X2055247Y-342804D01*
X2053357Y-341138D01*
X2052097Y-338221D01*
X2051467Y-334888D01*
X2052097Y-331555D01*
X2053357Y-328638D01*
X2055247Y-326971D01*
X2057137Y-326555D01*
X2059027Y-326971D01*
X2060917Y-328638D01*
X2062177Y-331555D01*
X2062492Y-334888D01*
X2062177Y-338221D01*
X2060917Y-341138D01*
X2059027Y-342804D01*
X2057137Y-343221D01*
G01X2076982D02*
Y-326555D01*
G01Y-330721D02*
X2078242Y-328638D01*
X2080132Y-326971D01*
X2082652Y-326555D01*
X2084857Y-326971D01*
X2086747Y-328638D01*
X2087692Y-331555D01*
Y-343221D01*
G01X2139667Y-320305D02*
X2137777Y-319054D01*
X2135572Y-318221D01*
X2133052D01*
X2130217Y-319471D01*
X2128012Y-321554D01*
X2126437Y-324055D01*
X2125177Y-328221D01*
X2124862Y-331971D01*
X2125492Y-335721D01*
X2126437Y-338221D01*
X2128327Y-340722D01*
X2130532Y-342388D01*
X2132737Y-343221D01*
X2134942D01*
X2137147Y-342388D01*
X2139037Y-341138D01*
X2140612Y-339472D01*
G01X2157937Y-343221D02*
X2156047Y-342804D01*
X2154157Y-341138D01*
X2152897Y-338221D01*
X2152267Y-334888D01*
X2152897Y-331555D01*
X2154157Y-328638D01*
X2156047Y-326971D01*
X2157937Y-326555D01*
X2159827Y-326971D01*
X2161717Y-328638D01*
X2162977Y-331555D01*
X2163292Y-334888D01*
X2162977Y-338221D01*
X2161717Y-341138D01*
X2159827Y-342804D01*
X2157937Y-343221D01*
G01X2178727D02*
Y-326555D01*
G01Y-329887D02*
X2180302Y-328221D01*
X2181877Y-326971D01*
X2184082Y-326555D01*
X2185657Y-326971D01*
X2187547Y-328221D01*
G01X2202667Y-351554D02*
Y-326555D01*
G01Y-330304D02*
X2204242Y-328221D01*
X2205817Y-326971D01*
X2208337Y-326555D01*
X2210542Y-326971D01*
X2212747Y-329054D01*
X2213692Y-331971D01*
X2214007Y-334888D01*
X2213692Y-337805D01*
X2212747Y-340722D01*
X2210857Y-342388D01*
X2208337Y-343221D01*
X2206132Y-342804D01*
X2203927Y-341555D01*
X2202667Y-339888D01*
G01X2233537Y-343221D02*
X2231647Y-342804D01*
X2229757Y-341138D01*
X2228497Y-338221D01*
X2227867Y-334888D01*
X2228497Y-331555D01*
X2229757Y-328638D01*
X2231647Y-326971D01*
X2233537Y-326555D01*
X2235427Y-326971D01*
X2237317Y-328638D01*
X2238577Y-331555D01*
X2238892Y-334888D01*
X2238577Y-338221D01*
X2237317Y-341138D01*
X2235427Y-342804D01*
X2233537Y-343221D01*
G01X2254327D02*
Y-326555D01*
G01Y-329887D02*
X2255902Y-328221D01*
X2257477Y-326971D01*
X2259682Y-326555D01*
X2261257Y-326971D01*
X2263147Y-328221D01*
G01X2289607Y-343221D02*
Y-326555D01*
G01Y-329471D02*
X2288347Y-327805D01*
X2286457Y-326971D01*
X2284252Y-326555D01*
X2282047Y-327388D01*
X2280157Y-329054D01*
X2278897Y-331555D01*
X2278267Y-334888D01*
X2278897Y-338221D01*
X2280157Y-340722D01*
X2282047Y-342388D01*
X2284252Y-343221D01*
X2286457Y-342804D01*
X2288347Y-341555D01*
X2289607Y-339888D01*
G01X2309137Y-318221D02*
Y-343221D01*
G01X2304727Y-326555D02*
X2313547D01*
G01X2334337D02*
Y-343221D01*
G01Y-319888D02*
X2333707Y-319471D01*
Y-318638D01*
X2334337Y-318221D01*
X2334967Y-318638D01*
Y-319471D01*
X2334337Y-319888D01*
G01X2359537Y-343221D02*
X2357647Y-342804D01*
X2355757Y-341138D01*
X2354497Y-338221D01*
X2353867Y-334888D01*
X2354497Y-331555D01*
X2355757Y-328638D01*
X2357647Y-326971D01*
X2359537Y-326555D01*
X2361427Y-326971D01*
X2363317Y-328638D01*
X2364577Y-331555D01*
X2364892Y-334888D01*
X2364577Y-338221D01*
X2363317Y-341138D01*
X2361427Y-342804D01*
X2359537Y-343221D01*
G01X2379382D02*
Y-326555D01*
G01Y-330721D02*
X2380642Y-328638D01*
X2382532Y-326971D01*
X2385052Y-326555D01*
X2387257Y-326971D01*
X2389147Y-328638D01*
X2390092Y-331555D01*
Y-343221D01*
G01X1944712Y-264711D02*
X1950962Y-284711D01*
X1957212Y-264711D01*
G01X1970962Y-271378D02*
Y-284711D01*
G01Y-266045D02*
X1970462Y-265711D01*
Y-265044D01*
X1970962Y-264711D01*
X1971462Y-265044D01*
Y-265711D01*
X1970962Y-266045D01*
G01X1990962Y-284711D02*
Y-264711D01*
G01X2007212Y-275711D02*
X2015212D01*
X2014462Y-273378D01*
X2013212Y-272045D01*
X2011462Y-271378D01*
X2009712Y-271711D01*
X2008212Y-272711D01*
X2007212Y-275045D01*
X2006712Y-277045D01*
Y-279044D01*
X2007212Y-281045D01*
X2008462Y-283045D01*
X2009962Y-284378D01*
X2011712Y-284711D01*
X2013462Y-284044D01*
X2015212Y-282045D01*
G01X2035462Y-284711D02*
Y-271378D01*
G01Y-273711D02*
X2034462Y-272378D01*
X2032962Y-271711D01*
X2031212Y-271378D01*
X2029462Y-272045D01*
X2027962Y-273378D01*
X2026962Y-275378D01*
X2026462Y-278045D01*
X2026962Y-280711D01*
X2027962Y-282711D01*
X2029462Y-284044D01*
X2031212Y-284711D01*
X2032962Y-284378D01*
X2034462Y-283378D01*
X2035462Y-282045D01*
G01X2046712Y-284711D02*
Y-271378D01*
G01Y-274711D02*
X2047712Y-273044D01*
X2049212Y-271711D01*
X2051212Y-271378D01*
X2052962Y-271711D01*
X2054462Y-273044D01*
X2055212Y-275378D01*
Y-284711D01*
G01X2085962Y-264711D02*
Y-284711D01*
X2095962D01*
G01X2110962Y-271378D02*
Y-284711D01*
G01Y-266045D02*
X2110462Y-265711D01*
Y-265044D01*
X2110962Y-264711D01*
X2111462Y-265044D01*
Y-265711D01*
X2110962Y-266045D01*
G01X1965489Y-240006D02*
X1967489Y-241672D01*
X1969739Y-242672D01*
X1971739D01*
X1973739Y-241672D01*
X1975239Y-240006D01*
X1975989Y-237672D01*
X1975489Y-235339D01*
X1974239Y-233339D01*
X1971989Y-232005D01*
X1968989Y-231339D01*
X1967239Y-230006D01*
X1966489Y-227672D01*
X1966989Y-225339D01*
X1968239Y-223672D01*
X1969989Y-222672D01*
X1971739D01*
X1973489Y-223339D01*
X1974989Y-225005D01*
G01X1985239Y-242672D02*
Y-222672D01*
X1990239D01*
X1992239Y-223672D01*
X1993739Y-225005D01*
X1994989Y-227005D01*
X1995989Y-229339D01*
X1996239Y-232672D01*
X1995989Y-236006D01*
X1994989Y-238339D01*
X1993739Y-240339D01*
X1992239Y-241672D01*
X1990239Y-242672D01*
X1985239D01*
G01X1956709Y-191790D02*
Y-171790D01*
X1953709Y-175790D01*
G01Y-191790D02*
X1959709D01*
G01X1971959Y-183457D02*
X1973709Y-181123D01*
X1975209Y-179790D01*
X1977209Y-179124D01*
X1978959Y-179790D01*
X1980209Y-181123D01*
X1981209Y-183123D01*
X1981459Y-185457D01*
X1981209Y-187457D01*
X1980209Y-189457D01*
X1978709Y-191123D01*
X1976959Y-191790D01*
X1974959Y-191123D01*
X1973209Y-189124D01*
X1972209Y-186123D01*
X1971959Y-182790D01*
X1972459Y-178457D01*
X1973209Y-176123D01*
X1974459Y-173790D01*
X1976209Y-172123D01*
X1977959Y-171790D01*
X1979709Y-172457D01*
X1980959Y-174123D01*
G01X1991209Y-187790D02*
X1992709Y-190124D01*
X1994709Y-191457D01*
X1996959Y-191790D01*
X1998959Y-191457D01*
X2000959Y-189790D01*
X2002209Y-187790D01*
X2002459Y-185790D01*
X2001959Y-183457D01*
X2000209Y-181790D01*
X1998459Y-181123D01*
X1996209D01*
G01X1998459D02*
X1999959Y-180123D01*
X2001209Y-178457D01*
X2001709Y-176457D01*
X2001209Y-174457D01*
X1999959Y-172790D01*
X1997709Y-171790D01*
X1995459Y-172123D01*
X1993209Y-173457D01*
G01X2016709Y-191790D02*
Y-171790D01*
X2013709Y-175790D01*
G01Y-191790D02*
X2019709D01*
G01X2036209D02*
X2036709Y-187457D01*
X2037459Y-183790D01*
X2038459Y-180457D01*
X2039709Y-176790D01*
X2041709Y-171790D01*
X2031709D01*
G01X1949028Y-132511D02*
X1950288Y-131262D01*
X1951233Y-129179D01*
X1951863Y-126261D01*
X1951233Y-123762D01*
X1949973Y-122095D01*
X1947768Y-120845D01*
X1939263D01*
Y-145845D01*
X1949658D01*
X1951863Y-144179D01*
X1953123Y-141678D01*
X1953753Y-138762D01*
X1953123Y-135846D01*
X1951233Y-133345D01*
X1949028Y-132511D01*
X1939263D01*
G01X1967298Y-145845D02*
Y-129179D01*
G01Y-132511D02*
X1968873Y-130845D01*
X1970448Y-129595D01*
X1972653Y-129179D01*
X1974228Y-129595D01*
X1976118Y-130845D01*
G01X1990293Y-153345D02*
X1992183Y-154178D01*
X1994703Y-153345D01*
X1996278Y-151679D01*
X1997538Y-149595D01*
X1999428Y-142929D01*
X2003523Y-129179D01*
G01X1993443D02*
X1999428Y-142929D01*
G01X2027148Y-131262D02*
X2024943Y-129595D01*
X2023053Y-129179D01*
X2020533Y-130012D01*
X2018643Y-131678D01*
X2017383Y-134595D01*
X2017068Y-137512D01*
X2017383Y-140429D01*
X2018643Y-142929D01*
X2020533Y-145012D01*
X2023053Y-145845D01*
X2025258Y-145012D01*
X2027148Y-143346D01*
G01X2042583Y-134595D02*
X2052663D01*
X2051718Y-131678D01*
X2050143Y-130012D01*
X2047938Y-129179D01*
X2045733Y-129595D01*
X2043843Y-130845D01*
X2042583Y-133762D01*
X2041953Y-136262D01*
Y-138762D01*
X2042583Y-141262D01*
X2044158Y-143762D01*
X2046048Y-145428D01*
X2048253Y-145845D01*
X2050458Y-145012D01*
X2052663Y-142512D01*
G01X2104638Y-122929D02*
X2102748Y-121678D01*
X2100543Y-120845D01*
X2098023D01*
X2095188Y-122095D01*
X2092983Y-124178D01*
X2091408Y-126679D01*
X2090148Y-130845D01*
X2089833Y-134595D01*
X2090463Y-138345D01*
X2091408Y-140845D01*
X2093298Y-143346D01*
X2095503Y-145012D01*
X2097708Y-145845D01*
X2099913D01*
X2102118Y-145012D01*
X2104008Y-143762D01*
X2105583Y-142096D01*
G01X2128578Y-145845D02*
Y-129179D01*
G01Y-132095D02*
X2127318Y-130429D01*
X2125428Y-129595D01*
X2123223Y-129179D01*
X2121018Y-130012D01*
X2119128Y-131678D01*
X2117868Y-134179D01*
X2117238Y-137512D01*
X2117868Y-140845D01*
X2119128Y-143346D01*
X2121018Y-145012D01*
X2123223Y-145845D01*
X2125428Y-145428D01*
X2127318Y-144179D01*
X2128578Y-142512D01*
G01X2142753Y-145845D02*
Y-129179D01*
G01Y-133345D02*
X2144013Y-131262D01*
X2145903Y-129595D01*
X2148423Y-129179D01*
X2150628Y-129595D01*
X2152518Y-131262D01*
X2153463Y-134179D01*
Y-145845D01*
G01X2166693Y-153345D02*
X2168583Y-154178D01*
X2171103Y-153345D01*
X2172678Y-151679D01*
X2173938Y-149595D01*
X2175828Y-142929D01*
X2179923Y-129179D01*
G01X2169843D02*
X2175828Y-142929D01*
G01X2198508Y-145845D02*
X2196618Y-145428D01*
X2194728Y-143762D01*
X2193468Y-140845D01*
X2192838Y-137512D01*
X2193468Y-134179D01*
X2194728Y-131262D01*
X2196618Y-129595D01*
X2198508Y-129179D01*
X2200398Y-129595D01*
X2202288Y-131262D01*
X2203548Y-134179D01*
X2203863Y-137512D01*
X2203548Y-140845D01*
X2202288Y-143762D01*
X2200398Y-145428D01*
X2198508Y-145845D01*
G01X2218353D02*
Y-129179D01*
G01Y-133345D02*
X2219613Y-131262D01*
X2221503Y-129595D01*
X2224023Y-129179D01*
X2226228Y-129595D01*
X2228118Y-131262D01*
X2229063Y-134179D01*
Y-145845D01*
G01X2267808D02*
Y-120845D01*
X2275683D01*
X2278203Y-122095D01*
X2279778Y-123762D01*
X2280408Y-127095D01*
X2279778Y-130429D01*
X2277888Y-132511D01*
X2275683Y-133762D01*
X2267808D01*
G01X2275683D02*
X2280408Y-145845D01*
G01X2299308Y-146678D02*
X2298678Y-146262D01*
Y-145428D01*
X2299308Y-145012D01*
X2299938Y-145428D01*
Y-146262D01*
X2299308Y-146678D01*
G01X2317578Y-145845D02*
Y-120845D01*
X2323878D01*
X2326398Y-122095D01*
X2328288Y-123762D01*
X2329863Y-126261D01*
X2331123Y-129179D01*
X2331438Y-133345D01*
X2331123Y-137512D01*
X2329863Y-140429D01*
X2328288Y-142929D01*
X2326398Y-144595D01*
X2323878Y-145845D01*
X2317578D01*
G01X2343408D02*
Y-120845D01*
X2350968D01*
X2353488Y-122095D01*
X2355378Y-125012D01*
X2356008Y-128345D01*
X2355378Y-131678D01*
X2353803Y-134179D01*
X2350968Y-135429D01*
X2343408D01*
G01X2377428Y-132511D02*
X2378688Y-131262D01*
X2379633Y-129179D01*
X2380263Y-126261D01*
X2379633Y-123762D01*
X2378373Y-122095D01*
X2376168Y-120845D01*
X2367663D01*
Y-145845D01*
X2378058D01*
X2380263Y-144179D01*
X2381523Y-141678D01*
X2382153Y-138762D01*
X2381523Y-135846D01*
X2379633Y-133345D01*
X2377428Y-132511D01*
X2367663D01*
G01X1938780Y1608298D02*
X1930906D01*
X1936549Y1604656D01*
Y1609578D01*
G01X1937862Y1613319D02*
X1938518Y1614008D01*
X1938780Y1614795D01*
X1938518Y1615583D01*
X1937730Y1616272D01*
X1936549Y1616764D01*
X1935368Y1616961D01*
X1933924D01*
X1932743Y1616764D01*
X1931693Y1616272D01*
X1931168Y1615681D01*
X1930906Y1614992D01*
X1931168Y1614204D01*
X1931693Y1613614D01*
X1932481Y1613220D01*
X1933531Y1613023D01*
X1934449Y1613220D01*
X1935368Y1613712D01*
X1935893Y1614303D01*
X1936024Y1614992D01*
X1935762Y1615779D01*
X1935106Y1616370D01*
X1933924Y1616961D01*
G01X1938780Y1622867D02*
X1930906D01*
X1932481Y1621686D01*
G01X1938780D02*
Y1624048D01*
G01X1939042Y1630742D02*
X1938911Y1630545D01*
X1938649D01*
X1938518Y1630742D01*
X1938649Y1630939D01*
X1938911D01*
X1939042Y1630742D01*
G01X1938780Y1639798D02*
X1930906D01*
X1936549Y1636156D01*
Y1641078D01*
G01X1937599Y1644326D02*
X1938255Y1644917D01*
X1938649Y1645606D01*
X1938780Y1646492D01*
X1938518Y1647378D01*
X1937993Y1648067D01*
X1937074Y1648559D01*
X1936024Y1648658D01*
X1934974Y1648461D01*
X1934318Y1647968D01*
X1933793Y1647279D01*
X1933662Y1646591D01*
X1933793Y1645901D01*
X1934318Y1645016D01*
X1930906Y1645311D01*
Y1647968D01*
G01X2122488Y-384560D02*
Y-373153D01*
X2120777Y-375434D01*
G01Y-384560D02*
X2124199D01*
G01X2131186Y-375054D02*
X2132042Y-373914D01*
X2133040Y-373343D01*
X2134181Y-373153D01*
X2135607Y-373533D01*
X2136605Y-374484D01*
X2136890Y-375624D01*
X2136747Y-376765D01*
X2136177Y-377716D01*
X2133325Y-379617D01*
X2132042Y-380948D01*
X2131186Y-382849D01*
X2130901Y-384560D01*
X2136890D01*
G01X2122488Y1793196D02*
Y1804603D01*
X2120777Y1802322D01*
G01Y1793196D02*
X2124199D01*
G01X2131186Y1802702D02*
X2132042Y1803842D01*
X2133040Y1804413D01*
X2134181Y1804603D01*
X2135607Y1804223D01*
X2136605Y1803272D01*
X2136890Y1802132D01*
X2136747Y1800991D01*
X2136177Y1800040D01*
X2133325Y1798139D01*
X2132042Y1796808D01*
X2131186Y1794907D01*
X2130901Y1793196D01*
X2136890D01*
G01X2269171Y-217978D02*
Y-237978D01*
G01X2263421Y-217978D02*
X2274921D01*
G01X2284921Y-237978D02*
Y-217978D01*
G01Y-227644D02*
X2286171Y-225978D01*
X2287421Y-224978D01*
X2289421Y-224645D01*
X2290921Y-224978D01*
X2292671Y-226311D01*
X2293421Y-228312D01*
Y-237978D01*
G01X2309171Y-224645D02*
Y-237978D01*
G01Y-219312D02*
X2308671Y-218978D01*
Y-218311D01*
X2309171Y-217978D01*
X2309671Y-218311D01*
Y-218978D01*
X2309171Y-219312D01*
G01X2333171Y-226311D02*
X2331421Y-224978D01*
X2329921Y-224645D01*
X2327921Y-225312D01*
X2326421Y-226645D01*
X2325421Y-228978D01*
X2325171Y-231312D01*
X2325421Y-233645D01*
X2326421Y-235645D01*
X2327921Y-237311D01*
X2329921Y-237978D01*
X2331671Y-237311D01*
X2333171Y-235978D01*
G01X2344921Y-237978D02*
Y-217978D01*
G01X2352921Y-224645D02*
X2344921Y-232311D01*
G01X2348171Y-229311D02*
X2353421Y-237978D01*
G01X2364921D02*
Y-224645D01*
G01Y-227978D02*
X2365921Y-226311D01*
X2367421Y-224978D01*
X2369421Y-224645D01*
X2371171Y-224978D01*
X2372671Y-226311D01*
X2373421Y-228645D01*
Y-237978D01*
G01X2385421Y-228978D02*
X2393421D01*
X2392671Y-226645D01*
X2391421Y-225312D01*
X2389671Y-224645D01*
X2387921Y-224978D01*
X2386421Y-225978D01*
X2385421Y-228312D01*
X2384921Y-230312D01*
Y-232311D01*
X2385421Y-234312D01*
X2386671Y-236312D01*
X2388171Y-237645D01*
X2389921Y-237978D01*
X2391671Y-237311D01*
X2393421Y-235312D01*
G01X2405421Y-235645D02*
X2406671Y-236978D01*
X2408421Y-237978D01*
X2409921D01*
X2411421Y-237311D01*
X2412421Y-236312D01*
X2412921Y-234979D01*
X2412671Y-232978D01*
X2411671Y-231978D01*
X2407171Y-229978D01*
X2406171Y-227644D01*
X2406671Y-225978D01*
X2407671Y-224978D01*
X2409171Y-224645D01*
X2410671Y-224978D01*
X2412171Y-225978D01*
G01X2425421Y-235645D02*
X2426671Y-236978D01*
X2428421Y-237978D01*
X2429921D01*
X2431421Y-237311D01*
X2432421Y-236312D01*
X2432921Y-234979D01*
X2432671Y-232978D01*
X2431671Y-231978D01*
X2427171Y-229978D01*
X2426171Y-227644D01*
X2426671Y-225978D01*
X2427671Y-224978D01*
X2429171Y-224645D01*
X2430671Y-224978D01*
X2432171Y-225978D01*
G01X2342158Y-384560D02*
Y-373153D01*
X2340447Y-375434D01*
G01Y-384560D02*
X2343869D01*
G01X2350429Y-382279D02*
X2351284Y-383610D01*
X2352425Y-384370D01*
X2353708Y-384560D01*
X2354849Y-384370D01*
X2355990Y-383420D01*
X2356702Y-382279D01*
X2356845Y-381138D01*
X2356560Y-379807D01*
X2355562Y-378857D01*
X2354564Y-378476D01*
X2353280D01*
G01X2354564D02*
X2355419Y-377906D01*
X2356132Y-376956D01*
X2356417Y-375815D01*
X2356132Y-374674D01*
X2355419Y-373724D01*
X2354136Y-373153D01*
X2352853Y-373343D01*
X2351569Y-374104D01*
G01X2306245Y-286686D02*
Y-266686D01*
X2311245D01*
X2313245Y-267686D01*
X2314745Y-269019D01*
X2315995Y-271019D01*
X2316995Y-273353D01*
X2317245Y-276686D01*
X2316995Y-280020D01*
X2315995Y-282353D01*
X2314745Y-284353D01*
X2313245Y-285686D01*
X2311245Y-286686D01*
X2306245D01*
G01X2336245D02*
Y-273353D01*
G01Y-275686D02*
X2335245Y-274353D01*
X2333745Y-273686D01*
X2331995Y-273353D01*
X2330245Y-274020D01*
X2328745Y-275353D01*
X2327745Y-277353D01*
X2327245Y-280020D01*
X2327745Y-282686D01*
X2328745Y-284686D01*
X2330245Y-286019D01*
X2331995Y-286686D01*
X2333745Y-286353D01*
X2335245Y-285353D01*
X2336245Y-284020D01*
G01X2351745Y-266686D02*
Y-286686D01*
G01X2348245Y-273353D02*
X2355245D01*
G01X2367995Y-277686D02*
X2375995D01*
X2375245Y-275353D01*
X2373995Y-274020D01*
X2372245Y-273353D01*
X2370495Y-273686D01*
X2368995Y-274686D01*
X2367995Y-277020D01*
X2367495Y-279020D01*
Y-281019D01*
X2367995Y-283020D01*
X2369245Y-285020D01*
X2370745Y-286353D01*
X2372495Y-286686D01*
X2374245Y-286019D01*
X2375995Y-284020D01*
G01X2342158Y1793196D02*
Y1804603D01*
X2340447Y1802322D01*
G01Y1793196D02*
X2343869D01*
G01X2350429Y1795477D02*
X2351284Y1794146D01*
X2352425Y1793386D01*
X2353708Y1793196D01*
X2354849Y1793386D01*
X2355990Y1794336D01*
X2356702Y1795477D01*
X2356845Y1796618D01*
X2356560Y1797949D01*
X2355562Y1798899D01*
X2354564Y1799280D01*
X2353280D01*
G01X2354564D02*
X2355419Y1799850D01*
X2356132Y1800800D01*
X2356417Y1801941D01*
X2356132Y1803082D01*
X2355419Y1804032D01*
X2354136Y1804603D01*
X2352853Y1804413D01*
X2351569Y1803652D01*
G01X2474414Y-268044D02*
X2475914Y-266045D01*
X2477664Y-265044D01*
X2479664Y-264711D01*
X2482164Y-265378D01*
X2483914Y-267044D01*
X2484414Y-269044D01*
X2484164Y-271045D01*
X2483164Y-272711D01*
X2478164Y-276044D01*
X2475914Y-278378D01*
X2474414Y-281712D01*
X2473914Y-284711D01*
X2484414D01*
G01X2499164Y-264711D02*
X2497164Y-265378D01*
X2495664Y-267044D01*
X2494664Y-269044D01*
X2493914Y-271711D01*
X2493664Y-274711D01*
X2493914Y-277711D01*
X2494664Y-280378D01*
X2495664Y-282378D01*
X2497164Y-284044D01*
X2499164Y-284711D01*
X2501164Y-284044D01*
X2502664Y-282378D01*
X2503664Y-280378D01*
X2504414Y-277711D01*
X2504664Y-274711D01*
X2504414Y-271711D01*
X2503664Y-269044D01*
X2502664Y-267044D01*
X2501164Y-265378D01*
X2499164Y-264711D01*
G01X2519164Y-284711D02*
Y-264711D01*
X2516164Y-268711D01*
G01Y-284711D02*
X2522164D01*
G01X2538664D02*
X2539164Y-280378D01*
X2539914Y-276711D01*
X2540914Y-273378D01*
X2542164Y-269711D01*
X2544164Y-264711D01*
X2534164D01*
G01X2555914Y-278045D02*
X2562414D01*
G01X2579164Y-264711D02*
X2577164Y-265378D01*
X2575664Y-267044D01*
X2574664Y-269044D01*
X2573914Y-271711D01*
X2573664Y-274711D01*
X2573914Y-277711D01*
X2574664Y-280378D01*
X2575664Y-282378D01*
X2577164Y-284044D01*
X2579164Y-284711D01*
X2581164Y-284044D01*
X2582664Y-282378D01*
X2583664Y-280378D01*
X2584414Y-277711D01*
X2584664Y-274711D01*
X2584414Y-271711D01*
X2583664Y-269044D01*
X2582664Y-267044D01*
X2581164Y-265378D01*
X2579164Y-264711D01*
G01X2593664Y-280711D02*
X2595164Y-283045D01*
X2597164Y-284378D01*
X2599414Y-284711D01*
X2601414Y-284378D01*
X2603414Y-282711D01*
X2604664Y-280711D01*
X2604914Y-278711D01*
X2604414Y-276378D01*
X2602664Y-274711D01*
X2600914Y-274044D01*
X2598664D01*
G01X2600914D02*
X2602414Y-273044D01*
X2603664Y-271378D01*
X2604164Y-269378D01*
X2603664Y-267378D01*
X2602414Y-265711D01*
X2600164Y-264711D01*
X2597914Y-265044D01*
X2595664Y-266378D01*
G01X2615914Y-278045D02*
X2622414D01*
G01X2639164Y-264711D02*
X2637164Y-265378D01*
X2635664Y-267044D01*
X2634664Y-269044D01*
X2633914Y-271711D01*
X2633664Y-274711D01*
X2633914Y-277711D01*
X2634664Y-280378D01*
X2635664Y-282378D01*
X2637164Y-284044D01*
X2639164Y-284711D01*
X2641164Y-284044D01*
X2642664Y-282378D01*
X2643664Y-280378D01*
X2644414Y-277711D01*
X2644664Y-274711D01*
X2644414Y-271711D01*
X2643664Y-269044D01*
X2642664Y-267044D01*
X2641164Y-265378D01*
X2639164Y-264711D01*
G01X2654414Y-268044D02*
X2655914Y-266045D01*
X2657664Y-265044D01*
X2659664Y-264711D01*
X2662164Y-265378D01*
X2663914Y-267044D01*
X2664414Y-269044D01*
X2664164Y-271045D01*
X2663164Y-272711D01*
X2658164Y-276044D01*
X2655914Y-278378D01*
X2654414Y-281712D01*
X2653914Y-284711D01*
X2664414D01*
G01X2482307Y-219336D02*
X2483807Y-217337D01*
X2485557Y-216336D01*
X2487557Y-216003D01*
X2490057Y-216670D01*
X2491807Y-218336D01*
X2492307Y-220336D01*
X2492057Y-222337D01*
X2491057Y-224003D01*
X2486057Y-227336D01*
X2483807Y-229670D01*
X2482307Y-233004D01*
X2481807Y-236003D01*
X2492307D01*
G01X2507057Y-236670D02*
X2506557Y-236336D01*
Y-235670D01*
X2507057Y-235336D01*
X2507557Y-235670D01*
Y-236336D01*
X2507057Y-236670D01*
G01X2521557Y-232003D02*
X2523057Y-234337D01*
X2525057Y-235670D01*
X2527307Y-236003D01*
X2529307Y-235670D01*
X2531307Y-234003D01*
X2532557Y-232003D01*
X2532807Y-230003D01*
X2532307Y-227670D01*
X2530557Y-226003D01*
X2528807Y-225336D01*
X2526557D01*
G01X2528807D02*
X2530307Y-224336D01*
X2531557Y-222670D01*
X2532057Y-220670D01*
X2531557Y-218670D01*
X2530307Y-217003D01*
X2528057Y-216003D01*
X2525807Y-216336D01*
X2523557Y-217670D01*
G01X2542307Y-227670D02*
X2544057Y-225336D01*
X2545557Y-224003D01*
X2547557Y-223337D01*
X2549307Y-224003D01*
X2550557Y-225336D01*
X2551557Y-227336D01*
X2551807Y-229670D01*
X2551557Y-231670D01*
X2550557Y-233670D01*
X2549057Y-235336D01*
X2547307Y-236003D01*
X2545307Y-235336D01*
X2543557Y-233337D01*
X2542557Y-230336D01*
X2542307Y-227003D01*
X2542807Y-222670D01*
X2543557Y-220336D01*
X2544807Y-218003D01*
X2546557Y-216336D01*
X2548307Y-216003D01*
X2550057Y-216670D01*
X2551307Y-218336D01*
G01X2559557Y-236003D02*
Y-222670D01*
G01Y-226337D02*
X2560307Y-224670D01*
X2561557Y-223337D01*
X2563307Y-222670D01*
X2565057Y-223337D01*
X2566307Y-224670D01*
X2567057Y-226337D01*
Y-236003D01*
G01Y-226337D02*
X2567807Y-224670D01*
X2569057Y-223337D01*
X2570807Y-222670D01*
X2572557Y-223337D01*
X2573807Y-224670D01*
X2574557Y-226670D01*
Y-236003D01*
G01X2579557D02*
Y-222670D01*
G01Y-226337D02*
X2580307Y-224670D01*
X2581557Y-223337D01*
X2583307Y-222670D01*
X2585057Y-223337D01*
X2586307Y-224670D01*
X2587057Y-226337D01*
Y-236003D01*
G01Y-226337D02*
X2587807Y-224670D01*
X2589057Y-223337D01*
X2590807Y-222670D01*
X2592557Y-223337D01*
X2593807Y-224670D01*
X2594557Y-226670D01*
Y-236003D01*
G01X2561827Y-384560D02*
Y-373153D01*
X2560116Y-375434D01*
G01Y-384560D02*
X2563538D01*
G01X2574946D02*
Y-373153D01*
X2569670Y-381328D01*
X2576799D01*
G01X2561827Y1793196D02*
Y1804603D01*
X2560116Y1802322D01*
G01Y1793196D02*
X2563538D01*
G01X2574946D02*
Y1804603D01*
X2569670Y1796428D01*
X2576799D01*
G01X2687558Y-264869D02*
X2688271Y-266010D01*
X2689126Y-266770D01*
X2690124Y-267150D01*
X2691265Y-266770D01*
X2692121Y-266010D01*
X2692976Y-264869D01*
X2693261Y-263348D01*
Y-255743D01*
G01X2688698Y-39861D02*
X2692120D01*
G01X2690409D02*
Y-51268D01*
G01X2688698D02*
X2692120D01*
G01X2687415Y164424D02*
Y175831D01*
G01X2693404D02*
Y164424D01*
G01Y170127D02*
X2687415D01*
G01X2691265Y386009D02*
X2694117D01*
Y382587D01*
X2693261Y381446D01*
X2692263Y380686D01*
X2690837Y380306D01*
X2689411Y380686D01*
X2688413Y381446D01*
X2687558Y382587D01*
X2686987Y383918D01*
X2686702Y385439D01*
Y386770D01*
X2686987Y387910D01*
X2687558Y389242D01*
X2688413Y390382D01*
X2689269Y391142D01*
X2690409Y391713D01*
X2691408D01*
X2692548Y391333D01*
X2693404Y390572D01*
G01X2687321Y596378D02*
Y607785D01*
X2692740D01*
G01X2690743Y602272D02*
X2687321D01*
G01X2693261Y812449D02*
X2687558D01*
Y823856D01*
X2693261D01*
G01X2690980Y818343D02*
X2687558D01*
G01X2687273Y1028141D02*
Y1039548D01*
X2690124D01*
X2691265Y1038977D01*
X2692121Y1038217D01*
X2692834Y1037077D01*
X2693404Y1035745D01*
X2693546Y1033844D01*
X2693404Y1031943D01*
X2692834Y1030612D01*
X2692121Y1029472D01*
X2691265Y1028711D01*
X2690124Y1028141D01*
X2687273D01*
G01X2693546Y1254669D02*
X2692691Y1255240D01*
X2691693Y1255620D01*
X2690552D01*
X2689269Y1255049D01*
X2688271Y1254099D01*
X2687558Y1252958D01*
X2686987Y1251057D01*
X2686845Y1249346D01*
X2687130Y1247635D01*
X2687558Y1246494D01*
X2688413Y1245353D01*
X2689411Y1244593D01*
X2690409Y1244213D01*
X2691408D01*
X2692406Y1244593D01*
X2693261Y1245163D01*
X2693974Y1245924D01*
G01X2691550Y1465989D02*
X2692121Y1466559D01*
X2692548Y1467509D01*
X2692834Y1468841D01*
X2692548Y1469981D01*
X2691978Y1470741D01*
X2690980Y1471312D01*
X2687130D01*
Y1459905D01*
X2691835D01*
X2692834Y1460665D01*
X2693404Y1461806D01*
X2693689Y1463137D01*
X2693404Y1464468D01*
X2692548Y1465608D01*
X2691550Y1465989D01*
X2687130D01*
G01X2686845Y1675787D02*
X2690409Y1687194D01*
X2693974Y1675787D01*
G01X2692691Y1679779D02*
X2688128D01*
G01X-425029Y-388347D02*
Y1808346D01*
G01X2699577Y-388347D02*
X-425029D01*
G01X-406092Y-369410D02*
Y1789409D01*
G01X2680640Y-369410D02*
X-406092D01*
G01X-425029Y-153528D02*
X-406092D01*
G01X-425029Y62354D02*
X-406092D01*
G01X-425029D02*
X-406092D01*
G01X-425029Y278236D02*
X-406092D01*
G01X-425029D02*
X-406092D01*
G01X-425029Y494118D02*
X-406092D01*
G01X-425029D02*
X-406092D01*
G01X-425029Y710000D02*
X-406092D01*
G01X-425029D02*
X-406092D01*
G01X-425029D02*
X-406092D01*
G01X-425029Y925881D02*
X-406092D01*
G01X-425029D02*
X-406092D01*
G01X-425029Y1141763D02*
X-406092D01*
G01X-425029D02*
X-406092D01*
G01X-425029Y1357645D02*
X-406092D01*
G01X-425029D02*
X-406092D01*
G01X-425029Y1573527D02*
X-406092D01*
G01X-425029Y1808346D02*
X2699577D01*
G01X-406092Y1789409D02*
X2680640D01*
G01X-180741Y-369410D02*
Y-388347D01*
G01Y1808346D02*
Y1789409D01*
G01X0Y0D02*
X-89325D01*
G01X3937D02*
X779528D01*
G01X0Y3937D02*
G03X3937Y0I3937J0D01*
G01X0Y1456693D02*
Y3937D01*
G01D02*
G03X3937Y0I3937J0D01*
G01D02*
X779528D01*
G01X0Y1456693D02*
Y3937D01*
G01X11811Y1519685D02*
X-89325D01*
G01X0Y1460630D02*
Y1603810D01*
G01X3937Y1460630D02*
G03X0Y1456693I0J-3937D01*
G01X7874Y1460630D02*
X3937D01*
G01D02*
G03X0Y1456693I0J-3937D01*
G01X3937Y1460630D02*
X7874D01*
G01X38928Y-369410D02*
Y-388347D01*
G01X103089Y93268D02*
X97165D01*
G01X103050Y93228D02*
X97165D01*
G01X103050Y91260D02*
X97165D01*
G01Y91220D02*
X103089D01*
G01Y90118D02*
X97165D01*
G01X103050Y90079D02*
X97165D01*
G01X103050Y88110D02*
X97165D01*
G01Y88071D02*
X103089D01*
G01Y86969D02*
X97165D01*
G01X103050Y86929D02*
X97165D01*
G01X103050Y84961D02*
X97165D01*
G01Y84921D02*
X103089D01*
G01Y83819D02*
X97165D01*
G01X103050Y83780D02*
X97165D01*
G01Y93228D02*
Y94409D01*
G01Y90079D02*
Y91260D01*
G01Y86929D02*
Y88110D01*
G01Y83780D02*
Y84961D01*
G01X103050Y103858D02*
X97165D01*
G01Y103819D02*
X103089D01*
G01Y102717D02*
X97165D01*
G01X103050Y102677D02*
X97165D01*
G01X103050Y100709D02*
X97165D01*
G01Y100669D02*
X103089D01*
G01Y99567D02*
X97165D01*
G01X103050Y99528D02*
X97165D01*
G01X103050Y97559D02*
X97165D01*
G01Y97520D02*
X103089D01*
G01Y96417D02*
X97165D01*
G01X103050Y96378D02*
X97165D01*
G01X103050Y94409D02*
X97165D01*
G01Y94370D02*
X103089D01*
G01X97165Y102677D02*
Y103858D01*
G01Y99528D02*
Y100709D01*
G01Y96378D02*
Y97559D01*
G01X71063Y260630D02*
G03X72244I591J0D01*
G01Y254331D02*
G03X71063I-591J0D01*
G01X69094D02*
G03X67913I-591J0D01*
G01Y260630D02*
G03X69094I590J0D01*
G01X71063D02*
G03X72244I591J0D01*
G01Y254331D02*
G03X71063I-591J0D01*
G01X69094D02*
G03X67913I-591J0D01*
G01Y260630D02*
G03X69094I590J0D01*
G01X67913D02*
X67126D01*
G01X67913D02*
X67126D01*
G01X71063D02*
X69094D01*
G01X71063D02*
X69094D01*
G01X73031D02*
X72244D01*
G01X73031D02*
X72244D01*
G01X73031Y259646D02*
X67126D01*
G01Y259449D02*
X73031D01*
G01X67126Y255512D02*
X73031D01*
G01Y255315D02*
X67126D01*
G01X72244Y254331D02*
X73031D01*
G01X72244D02*
X73031D01*
G01X69094D02*
X71063D01*
G01X69094D02*
X71063D01*
G01X67126D02*
X67913D01*
G01X67126D02*
X67913D01*
G01X73031D02*
Y260630D01*
G01Y254331D02*
Y260630D01*
G01X67126Y254331D02*
Y260630D01*
G01D02*
Y254331D01*
G01X103050Y556614D02*
X97165D01*
G01Y556575D02*
X103089D01*
G01Y555472D02*
X97165D01*
G01X103050Y555433D02*
X97165D01*
G01X103050Y553465D02*
X97165D01*
G01Y553425D02*
X103089D01*
G01Y552323D02*
X97165D01*
G01X103050Y552283D02*
X97165D01*
G01X103050Y550315D02*
X97165D01*
G01Y550276D02*
X103089D01*
G01Y549173D02*
X97165D01*
G01X103050Y549134D02*
X97165D01*
G01X103050Y547165D02*
X97165D01*
G01Y547126D02*
X103089D01*
G01Y546024D02*
X97165D01*
G01X103050Y545984D02*
X97165D01*
G01X103050Y544016D02*
X97165D01*
G01Y543976D02*
X103089D01*
G01Y542874D02*
X97165D01*
G01X103050Y542835D02*
X97165D01*
G01X103050Y540866D02*
X97165D01*
G01Y540827D02*
X103089D01*
G01Y539724D02*
X97165D01*
G01X103050Y539685D02*
X97165D01*
G01X103050Y537717D02*
X97165D01*
G01Y537677D02*
X103089D01*
G01Y536575D02*
X97165D01*
G01X103050Y536535D02*
X97165D01*
G01Y555433D02*
Y556614D01*
G01Y552283D02*
Y553465D01*
G01Y549134D02*
Y550315D01*
G01Y545984D02*
Y547165D01*
G01Y542835D02*
Y544016D01*
G01Y539685D02*
Y540866D01*
G01Y536535D02*
Y537717D01*
G01X71063Y713386D02*
G03X72244I591J0D01*
G01Y707087D02*
G03X71063I-591J0D01*
G01X69094D02*
G03X67913I-591J0D01*
G01Y713386D02*
G03X69094I590J0D01*
G01X71063D02*
G03X72244I591J0D01*
G01Y707087D02*
G03X71063I-591J0D01*
G01X69094D02*
G03X67913I-591J0D01*
G01Y713386D02*
G03X69094I590J0D01*
G01X67913D02*
X67126D01*
G01X67913D02*
X67126D01*
G01X71063D02*
X69094D01*
G01X71063D02*
X69094D01*
G01X73031D02*
X72244D01*
G01X73031D02*
X72244D01*
G01X73031Y712402D02*
X67126D01*
G01Y712205D02*
X73031D01*
G01X67126Y708268D02*
X73031D01*
G01Y708071D02*
X67126D01*
G01X72244Y707087D02*
X73031D01*
G01X72244D02*
X73031D01*
G01X69094D02*
X71063D01*
G01X69094D02*
X71063D01*
G01X67126D02*
X67913D01*
G01X67126D02*
X67913D01*
G01X73031D02*
Y713386D01*
G01Y707087D02*
Y713386D01*
G01X67126Y707087D02*
Y713386D01*
G01D02*
Y707087D01*
G01X103050Y1009370D02*
X97165D01*
G01Y1009331D02*
X103089D01*
G01Y1008228D02*
X97165D01*
G01X103050Y1008189D02*
X97165D01*
G01X103050Y1006220D02*
X97165D01*
G01Y1006181D02*
X103089D01*
G01Y1005079D02*
X97165D01*
G01X103050Y1005039D02*
X97165D01*
G01X103050Y1003071D02*
X97165D01*
G01Y1003031D02*
X103089D01*
G01Y1001929D02*
X97165D01*
G01X103050Y1001890D02*
X97165D01*
G01X103050Y999921D02*
X97165D01*
G01Y999882D02*
X103089D01*
G01Y998780D02*
X97165D01*
G01X103050Y998740D02*
X97165D01*
G01X103050Y996772D02*
X97165D01*
G01Y996732D02*
X103089D01*
G01Y995630D02*
X97165D01*
G01X103050Y995591D02*
X97165D01*
G01X103050Y993622D02*
X97165D01*
G01Y993583D02*
X103089D01*
G01Y992480D02*
X97165D01*
G01X103050Y992441D02*
X97165D01*
G01X103050Y990472D02*
X97165D01*
G01Y990433D02*
X103089D01*
G01Y989331D02*
X97165D01*
G01X103050Y989291D02*
X97165D01*
G01Y1008189D02*
Y1009370D01*
G01Y1005039D02*
Y1006220D01*
G01Y1001890D02*
Y1003071D01*
G01Y998740D02*
Y999921D01*
G01Y995591D02*
Y996772D01*
G01Y992441D02*
Y993622D01*
G01Y989291D02*
Y990472D01*
G01X7874Y1460630D02*
G03X11811Y1464567I0J3937D01*
G01Y1515748D02*
Y1464567D01*
G01X15748Y1519685D02*
G03X11811Y1515748I0J-3937D01*
G01X60039Y1519685D02*
X15748D01*
G01X63976Y1515748D02*
G03X60039Y1519685I-3937J0D01*
G01X63976Y1509055D02*
Y1515748D01*
G01Y1509055D02*
G03X67913Y1505118I3937J0D01*
G01X93504D02*
X67913D01*
G01X93504D02*
G03X97441Y1509055I0J3937D01*
G01Y1515748D02*
Y1509055D01*
G01X101378Y1519685D02*
G03X97441Y1515748I0J-3937D01*
G01X63976Y1509055D02*
G03X67913Y1505118I3937J0D01*
G01X93504D02*
G03X97441Y1509055I0J3937D01*
G01X7874Y1460630D02*
G03X11811Y1464567I0J3937D01*
G01X15748Y1519685D02*
G03X11811Y1515748I0J-3937D01*
G01X63976D02*
G03X60039Y1519685I-3937J0D01*
G01X101378D02*
G03X97441Y1515748I0J-3937D01*
G01X60039Y1519685D02*
X15748D01*
G01X67913Y1505118D02*
X93504D01*
G01X97441Y1515748D02*
Y1509055D01*
G01X63976Y1515748D02*
Y1509055D01*
G01X11811Y1515748D02*
Y1464567D01*
G01X38928Y1808346D02*
Y1789409D01*
G01X102145Y83774D02*
X102146Y83768D01*
G01X102144Y83778D02*
X102145Y83774D01*
G01X102143Y83780D02*
X102144Y83778D01*
G01X102145Y86924D02*
X102146Y86918D01*
G01X102144Y86928D02*
X102145Y86924D01*
G01X102143Y86929D02*
X102144Y86928D01*
G01X102145Y90074D02*
X102146Y90067D01*
G01X102144Y90078D02*
X102145Y90074D01*
G01X102143Y90079D02*
X102144Y90078D01*
G01X102145Y93223D02*
X102146Y93217D01*
G01X102144Y93227D02*
X102145Y93223D01*
G01X102143Y93228D02*
X102144Y93227D01*
G01X116516Y51975D02*
Y51982D01*
G01X116517Y51970D02*
X116516Y51975D01*
G01X116518Y51969D02*
X116517Y51970D01*
G01X116516Y56975D02*
Y56982D01*
G01X116517Y56970D02*
X116516Y56975D01*
G01X116518Y56969D02*
X116517Y56970D01*
G01X116516Y61975D02*
Y61982D01*
G01X116517Y61970D02*
X116516Y61975D01*
G01X116518Y61969D02*
X116517Y61970D01*
G01X116516Y66975D02*
Y66982D01*
G01X116517Y66970D02*
X116516Y66975D01*
G01X116518Y66969D02*
X116517Y66970D01*
G01X116516Y71975D02*
Y71982D01*
G01X116517Y71970D02*
X116516Y71975D01*
G01X116518Y71969D02*
X116517Y71970D01*
G01X116516Y76975D02*
Y76982D01*
G01X116517Y76970D02*
X116516Y76975D01*
G01X116518Y76969D02*
X116517Y76970D01*
G01X116516Y81975D02*
Y81982D01*
G01X116517Y81970D02*
X116516Y81975D01*
G01X116518Y81969D02*
X116517Y81970D01*
G01X102129Y86931D02*
X102143Y86929D01*
G01X102118Y86939D02*
X102129Y86931D01*
G01X102106Y86957D02*
X102118Y86939D01*
G01X102129Y90081D02*
X102143Y90079D01*
G01X102117Y90089D02*
X102129Y90081D01*
G01X102105Y90109D02*
X102117Y90089D01*
G01X103091Y83813D02*
Y83805D01*
G01X103090Y83817D02*
X103091Y83813D01*
G01X103089Y83819D02*
X103090Y83817D01*
G01X103091Y86963D02*
Y86955D01*
G01X103090Y86967D02*
X103091Y86963D01*
G01X103089Y86969D02*
X103090Y86967D01*
G01X103091Y90112D02*
Y90104D01*
G01X103090Y90117D02*
X103091Y90112D01*
G01X103089Y90118D02*
X103090Y90117D01*
G01X103091Y93262D02*
Y93254D01*
G01X103090Y93266D02*
X103091Y93262D01*
G01X103089Y93268D02*
X103090Y93266D01*
G01X102128Y83782D02*
X102143Y83780D01*
G01X102115Y83791D02*
X102128Y83782D01*
G01X102105Y83811D02*
X102115Y83791D01*
G01X103090Y84941D02*
X103091Y84935D01*
G01X103088Y84948D02*
X103090Y84941D01*
G01X103085Y84954D02*
X103088Y84948D01*
G01X103090Y88091D02*
X103091Y88084D01*
G01X103088Y88097D02*
X103090Y88091D01*
G01X103085Y88103D02*
X103088Y88097D01*
G01X103090Y91241D02*
X103091Y91234D01*
G01X103088Y91247D02*
X103090Y91241D01*
G01X103085Y91253D02*
X103088Y91247D01*
G01X103052Y83774D02*
Y83768D01*
G01X103050Y83778D02*
X103052Y83774D01*
G01X103050Y83780D02*
Y83778D01*
G01X103052Y86924D02*
Y86918D01*
G01X103050Y86928D02*
X103052Y86924D01*
G01X103050Y86929D02*
Y86928D01*
G01X103052Y90074D02*
Y90067D01*
G01X103050Y90077D02*
X103052Y90074D01*
G01X103050Y90079D02*
Y90077D01*
G01X103052Y93223D02*
Y93217D01*
G01X103050Y93227D02*
X103052Y93223D01*
G01X103050Y93228D02*
Y93227D01*
G01X115531Y52015D02*
Y52024D01*
G01X115532Y52009D02*
X115531Y52015D01*
G01X115533Y52008D02*
X115532Y52009D01*
G01X115531Y57015D02*
Y57024D01*
G01X115532Y57009D02*
X115531Y57015D01*
G01X115533Y57008D02*
X115532Y57009D01*
G01X115531Y62015D02*
Y62024D01*
G01X115532Y62009D02*
X115531Y62015D01*
G01X115533Y62008D02*
X115532Y62009D01*
G01X115531Y67015D02*
Y67024D01*
G01X115532Y67009D02*
X115531Y67015D01*
G01X115533Y67008D02*
X115532Y67009D01*
G01X115531Y72015D02*
Y72024D01*
G01X115532Y72009D02*
X115531Y72015D01*
G01X115533Y72008D02*
X115532Y72009D01*
G01X116508Y52152D02*
X116516Y52125D01*
G01X116498Y52178D02*
X116508Y52152D01*
G01X116487Y52205D02*
X116498Y52178D01*
G01X116508Y57152D02*
X116516Y57125D01*
G01X116498Y57178D02*
X116508Y57152D01*
G01X116487Y57205D02*
X116498Y57178D01*
G01X116508Y62152D02*
X116516Y62125D01*
G01X116498Y62178D02*
X116508Y62152D01*
G01X116487Y62205D02*
X116498Y62178D01*
G01X116508Y67152D02*
X116516Y67125D01*
G01X116498Y67178D02*
X116508Y67152D01*
G01X116487Y67205D02*
X116498Y67178D01*
G01X103059Y91259D02*
X103050Y91260D01*
G01X103068Y91256D02*
X103059Y91259D01*
G01X103076Y91250D02*
X103068Y91256D01*
G01X103059Y84959D02*
X103050Y84961D01*
G01X103068Y84956D02*
X103059Y84959D01*
G01X103076Y84951D02*
X103068Y84956D01*
G01X103059Y88109D02*
X103050Y88110D01*
G01X103068Y88106D02*
X103059Y88109D01*
G01X103076Y88100D02*
X103068Y88106D01*
G01X115531Y77015D02*
Y77024D01*
G01X115532Y77009D02*
X115531Y77015D01*
G01X115533Y77008D02*
X115532Y77009D01*
G01X115531Y82015D02*
Y82024D01*
G01X115532Y82009D02*
X115531Y82015D01*
G01X115533Y82008D02*
X115532Y82009D01*
G01X116508Y72152D02*
X116516Y72125D01*
G01X116498Y72178D02*
X116508Y72152D01*
G01X116487Y72205D02*
X116498Y72178D01*
G01X116508Y77152D02*
X116516Y77125D01*
G01X116498Y77178D02*
X116508Y77152D01*
G01X116487Y77205D02*
X116498Y77178D01*
G01X116508Y82152D02*
X116516Y82125D01*
G01X116498Y82178D02*
X116508Y82152D01*
G01X116487Y82205D02*
X116498Y82178D01*
G01X102124Y93233D02*
X102143Y93228D01*
G01X102111Y93246D02*
X102124Y93233D01*
G01X102104Y93263D02*
X102111Y93246D01*
G01X116498Y52003D02*
X116479Y52008D01*
G01X116513Y51988D02*
X116498Y52003D01*
G01X116518Y51969D02*
X116513Y51988D01*
G01X116498Y57003D02*
X116479Y57008D01*
G01X116513Y56988D02*
X116498Y57003D01*
G01X116518Y56969D02*
X116513Y56988D01*
G01X116498Y62003D02*
X116479Y62008D01*
G01X116513Y61988D02*
X116498Y62003D01*
G01X116518Y61969D02*
X116513Y61988D01*
G01X116498Y67003D02*
X116479Y67008D01*
G01X116513Y66988D02*
X116498Y67003D01*
G01X116518Y66969D02*
X116513Y66988D01*
G01X116498Y72003D02*
X116479Y72008D01*
G01X116513Y71988D02*
X116498Y72003D01*
G01X116518Y71969D02*
X116513Y71988D01*
G01X116498Y77003D02*
X116479Y77008D01*
G01X116513Y76988D02*
X116498Y77003D01*
G01X116518Y76969D02*
X116513Y76988D01*
G01X116498Y82003D02*
X116479Y82008D01*
G01X116513Y81988D02*
X116498Y82003D01*
G01X116518Y81969D02*
X116513Y81988D01*
G01X116483Y52106D02*
X116487Y52205D01*
G01X116477Y52034D02*
X116483Y52106D01*
G01X116479Y52008D02*
X116477Y52034D01*
G01X116483Y57106D02*
X116487Y57205D01*
G01X116477Y57034D02*
X116483Y57106D01*
G01X116479Y57008D02*
X116477Y57034D01*
G01X116483Y62106D02*
X116487Y62205D01*
G01X116477Y62034D02*
X116483Y62106D01*
G01X116479Y62008D02*
X116477Y62034D01*
G01X116483Y67106D02*
X116487Y67205D01*
G01X116477Y67034D02*
X116483Y67106D01*
G01X116479Y67008D02*
X116477Y67034D01*
G01X116483Y72106D02*
X116487Y72205D01*
G01X116477Y72034D02*
X116483Y72106D01*
G01X116479Y72008D02*
X116477Y72034D01*
G01X116483Y77106D02*
X116487Y77205D01*
G01X116477Y77034D02*
X116483Y77106D01*
G01X116479Y77008D02*
X116477Y77034D01*
G01X116483Y82106D02*
X116487Y82205D01*
G01X116477Y82034D02*
X116483Y82106D01*
G01X116479Y82008D02*
X116477Y82034D01*
G01X102106Y86959D02*
Y86955D01*
G01X102108Y86952D02*
X102106Y86959D01*
G01X102120Y86937D02*
X102108Y86952D01*
G01X102144Y86929D02*
X102120Y86937D01*
G01X102106Y90108D02*
Y90104D01*
G01X102108Y90102D02*
X102106Y90108D01*
G01X102119Y90087D02*
X102108Y90102D01*
G01X102144Y90079D02*
X102119Y90087D01*
G01X102106Y83809D02*
Y83806D01*
G01X102108Y83803D02*
X102106Y83809D01*
G01X102119Y83788D02*
X102108Y83803D01*
G01X102144Y83780D02*
X102119Y83788D01*
G01X116503Y51999D02*
X116514Y51984D01*
G01X116479Y52008D02*
X116503Y51999D01*
G01Y56999D02*
X116514Y56984D01*
G01X116479Y57008D02*
X116503Y56999D01*
G01Y61999D02*
X116514Y61984D01*
G01X116479Y62008D02*
X116503Y61999D01*
G01Y66999D02*
X116514Y66984D01*
G01X116479Y67008D02*
X116503Y66999D01*
G01Y71999D02*
X116514Y71984D01*
G01X116479Y72008D02*
X116503Y71999D01*
G01Y76999D02*
X116514Y76984D01*
G01X116479Y77008D02*
X116503Y76999D01*
G01Y81999D02*
X116514Y81984D01*
G01X116479Y82008D02*
X116503Y81999D01*
G01X102106Y93258D02*
Y93254D01*
G01X102108Y93252D02*
X102106Y93258D01*
G01X102118Y93238D02*
X102108Y93252D01*
G01X102141Y93228D02*
X102118Y93238D01*
G01X103083Y91242D02*
X103076Y91250D01*
G01X103088Y91231D02*
X103083Y91242D01*
G01X103089Y91220D02*
X103088Y91231D01*
G01X103083Y84943D02*
X103076Y84951D01*
G01X103088Y84932D02*
X103083Y84943D01*
G01X103089Y84921D02*
X103088Y84932D01*
G01X103083Y88092D02*
X103076Y88100D01*
G01X103088Y88082D02*
X103083Y88092D01*
G01X103089Y88071D02*
X103088Y88082D01*
G01X102146Y91444D02*
Y91457D01*
G01X102143Y91431D02*
X102146Y91444D01*
G01X102143Y91417D02*
Y91431D01*
G01X102146Y88294D02*
Y88307D01*
G01X102143Y88281D02*
X102146Y88294D01*
G01X102143Y88268D02*
Y88281D01*
G01X102146Y85145D02*
Y85157D01*
G01X102143Y85132D02*
X102146Y85145D01*
G01X102143Y85118D02*
Y85132D01*
G01X115532Y80628D02*
X115533Y80630D01*
G01X115531Y80622D02*
X115532Y80628D01*
G01X115531Y80614D02*
Y80622D01*
G01X115532Y75628D02*
X115533Y75630D01*
G01X115531Y75622D02*
X115532Y75628D01*
G01X115531Y75614D02*
Y75622D01*
G01X115532Y70628D02*
X115533Y70630D01*
G01X115531Y70622D02*
X115532Y70628D01*
G01X115531Y70614D02*
Y70622D01*
G01X115532Y65628D02*
X115533Y65630D01*
G01X115531Y65622D02*
X115532Y65628D01*
G01X115531Y65614D02*
Y65622D01*
G01X115532Y60628D02*
X115533Y60630D01*
G01X115531Y60622D02*
X115532Y60628D01*
G01X115531Y60614D02*
Y60622D01*
G01X115532Y55628D02*
X115533Y55630D01*
G01X115531Y55622D02*
X115532Y55628D01*
G01X115531Y55614D02*
Y55622D01*
G01X115532Y50628D02*
X115533Y50630D01*
G01X115531Y50622D02*
X115532Y50628D01*
G01X115531Y50614D02*
Y50622D01*
G01X102143Y93057D02*
X102142Y93070D01*
G01X102146Y93044D02*
X102143Y93057D01*
G01X102146Y93031D02*
Y93044D01*
G01X102143Y89907D02*
X102142Y89921D01*
G01X102146Y89894D02*
X102143Y89907D01*
G01X102146Y89882D02*
Y89894D01*
G01X102143Y86757D02*
X102142Y86771D01*
G01X102146Y86745D02*
X102143Y86757D01*
G01X102146Y86732D02*
Y86745D01*
G01X102143Y83608D02*
X102142Y83622D01*
G01X102146Y83595D02*
X102143Y83608D01*
G01X102146Y83583D02*
Y83595D01*
G01X103054Y91431D02*
X103055Y91417D01*
G01X103050Y91444D02*
X103054Y91431D01*
G01X103051Y91457D02*
X103050Y91444D01*
G01X103054Y88281D02*
X103055Y88268D01*
G01X103050Y88294D02*
X103054Y88281D01*
G01X103051Y88307D02*
X103050Y88294D01*
G01X103054Y85132D02*
X103055Y85118D01*
G01X103050Y85145D02*
X103054Y85132D01*
G01X103051Y85157D02*
X103050Y85145D01*
G01X102106Y90112D02*
Y90105D01*
G01X102105Y90117D02*
X102106Y90112D01*
G01X102105Y90109D02*
Y90117D01*
G01X103050Y93044D02*
X103051Y93031D01*
G01X103053Y93057D02*
X103050Y93044D01*
G01X103054Y93070D02*
X103053Y93057D01*
G01X103050Y89894D02*
X103051Y89882D01*
G01X103053Y89907D02*
X103050Y89894D01*
G01X103054Y89921D02*
X103053Y89907D01*
G01X103050Y86745D02*
X103051Y86732D01*
G01X103053Y86757D02*
X103050Y86745D01*
G01X103054Y86771D02*
X103053Y86757D01*
G01X103050Y83595D02*
X103051Y83583D01*
G01X103053Y83608D02*
X103050Y83595D01*
G01X103054Y83622D02*
X103053Y83608D01*
G01X102106Y83813D02*
Y83806D01*
G01X102105Y83817D02*
X102106Y83813D01*
G01X102105Y83811D02*
Y83817D01*
G01X103081Y84959D02*
X103085Y84954D01*
G01X103076Y84963D02*
X103081Y84959D01*
G01X103070Y84967D02*
X103076Y84963D01*
G01X103065Y84970D02*
X103070Y84967D01*
G01X103058Y84971D02*
X103065Y84970D01*
G01X103051Y84972D02*
X103058Y84971D01*
G01X103081Y88109D02*
X103085Y88103D01*
G01X103076Y88113D02*
X103081Y88109D01*
G01X103070Y88117D02*
X103076Y88113D01*
G01X103065Y88119D02*
X103070Y88117D01*
G01X103058Y88121D02*
X103065Y88119D01*
G01X103051Y88121D02*
X103058D01*
G01X103081Y91258D02*
X103085Y91253D01*
G01X103076Y91263D02*
X103081Y91258D01*
G01X103070Y91266D02*
X103076Y91263D01*
G01X103065Y91269D02*
X103070Y91266D01*
G01X103058Y91270D02*
X103065Y91269D01*
G01X103051Y91271D02*
X103058Y91270D01*
G01X102107Y83798D02*
X102106Y83805D01*
G01X102109Y83791D02*
X102107Y83798D01*
G01X102113Y83785D02*
X102109Y83791D01*
G01X102118Y83779D02*
X102113Y83785D01*
G01X102124Y83774D02*
X102118Y83779D01*
G01X102131Y83771D02*
X102124Y83774D01*
G01X102138Y83769D02*
X102131Y83771D01*
G01X102146Y83768D02*
X102138Y83769D01*
G01X102107Y86948D02*
X102106Y86955D01*
G01X102109Y86941D02*
X102107Y86948D01*
G01X102113Y86934D02*
X102109Y86941D01*
G01X102118Y86929D02*
X102113Y86934D01*
G01X102124Y86924D02*
X102118Y86929D01*
G01X102131Y86920D02*
X102124Y86924D01*
G01X102138Y86919D02*
X102131Y86920D01*
G01X102146Y86918D02*
X102138Y86919D01*
G01X102107Y90097D02*
X102106Y90104D01*
G01X102109Y90090D02*
X102107Y90097D01*
G01X102113Y90084D02*
X102109Y90090D01*
G01X102118Y90078D02*
X102113Y90084D01*
G01X102124Y90074D02*
X102118Y90078D01*
G01X102131Y90070D02*
X102124Y90074D01*
G01X102138Y90068D02*
X102131Y90070D01*
G01X102146Y90067D02*
X102138Y90068D01*
G01X102107Y93247D02*
X102106Y93254D01*
G01X102109Y93240D02*
X102107Y93247D01*
G01X102113Y93233D02*
X102109Y93240D01*
G01X102118Y93228D02*
X102113Y93233D01*
G01X102124Y93223D02*
X102118Y93228D01*
G01X102131Y93220D02*
X102124Y93223D01*
G01X102138Y93218D02*
X102131Y93220D01*
G01X102146Y93217D02*
X102138Y93218D01*
G01X103060Y84959D02*
X103070Y84955D01*
G01X103050Y84961D02*
X103060Y84959D01*
G01Y88109D02*
X103070Y88105D01*
G01X103050Y88110D02*
X103060Y88109D01*
G01Y91258D02*
X103070Y91254D01*
G01X103050Y91260D02*
X103060Y91258D01*
G01X102119Y91251D02*
X102143Y91260D01*
G01X102108Y91237D02*
X102119Y91251D01*
G01X102106Y91230D02*
X102108Y91237D01*
G01X102119Y88102D02*
X102143Y88110D01*
G01X102108Y88087D02*
X102119Y88102D01*
G01X102106Y88080D02*
X102108Y88087D01*
G01X102119Y84952D02*
X102143Y84961D01*
G01X102108Y84937D02*
X102119Y84952D01*
G01X102106Y84931D02*
X102108Y84937D01*
G01X101359Y86969D02*
X100925D01*
G01X101733D02*
X101359D01*
G01Y93268D02*
X100925D01*
G01X101733D02*
X101359D01*
G01X103068Y83772D02*
X103071Y83774D01*
G01X103065Y83770D02*
X103068Y83772D01*
G01X103062Y83770D02*
X103065D01*
G01X103058Y83769D02*
X103062Y83770D01*
G01X103055Y83769D02*
X103058D01*
G01X103051Y83768D02*
X103055Y83769D01*
G01X102129Y84968D02*
X102126Y84967D01*
G01X102132Y84969D02*
X102129Y84968D01*
G01X102135Y84970D02*
X102132Y84969D01*
G01X102139Y84971D02*
X102135Y84970D01*
G01X102142Y84972D02*
X102139Y84971D01*
G01X102146Y84972D02*
X102142D01*
G01X103068Y86921D02*
X103071Y86923D01*
G01X103065Y86920D02*
X103068Y86921D01*
G01X103062Y86919D02*
X103065Y86920D01*
G01X103058Y86919D02*
X103062D01*
G01X103055Y86918D02*
X103058Y86919D01*
G01X103051Y86918D02*
X103055D01*
G01X102129Y88118D02*
X102126Y88116D01*
G01X102132Y88119D02*
X102129Y88118D01*
G01X102135Y88120D02*
X102132Y88119D01*
G01X102139Y88121D02*
X102135Y88120D01*
G01X102142Y88121D02*
X102139D01*
G01X102146D02*
X102142D01*
G01X103068Y90071D02*
X103071Y90073D01*
G01X103065Y90070D02*
X103068Y90071D01*
G01X103062Y90069D02*
X103065Y90070D01*
G01X103058Y90068D02*
X103062Y90069D01*
G01X103055Y90068D02*
X103058D01*
G01X103051Y90067D02*
X103055Y90068D01*
G01X102129Y91267D02*
X102126Y91266D01*
G01X102132Y91269D02*
X102129Y91267D01*
G01X102135Y91270D02*
X102132Y91269D01*
G01X102139Y91270D02*
X102135D01*
G01X102142Y91271D02*
X102139Y91270D01*
G01X102146Y91271D02*
X102142D01*
G01X103068Y93220D02*
X103071Y93222D01*
G01X103065Y93219D02*
X103068Y93220D01*
G01X103062Y93219D02*
X103065D01*
G01X103058Y93218D02*
X103062Y93219D01*
G01X103055Y93217D02*
X103058Y93218D01*
G01X103051Y93217D02*
X103055D01*
G01X103091Y91227D02*
Y91234D01*
G01X103090Y91222D02*
X103091Y91227D01*
G01X103089Y91220D02*
X103090Y91222D01*
G01X103091Y88077D02*
Y88084D01*
G01X103090Y88072D02*
X103091Y88077D01*
G01X103089Y88071D02*
X103090Y88072D01*
G01X103091Y84928D02*
Y84935D01*
G01X103090Y84923D02*
X103091Y84928D01*
G01X103089Y84921D02*
X103090Y84923D01*
G01X102106Y93262D02*
Y93254D01*
G01X102105Y93266D02*
X102106Y93262D01*
G01X102104Y93263D02*
X102105Y93266D01*
G01X102106Y86963D02*
Y86955D01*
G01X102105Y86967D02*
X102106Y86963D01*
G01X102104Y86965D02*
X102105Y86967D01*
G01X102109Y84941D02*
X102104Y84921D01*
G01X102124Y84955D02*
X102109Y84941D01*
G01X102143Y84961D02*
X102124Y84955D01*
G01X102109Y88091D02*
X102104Y88071D01*
G01X102124Y88105D02*
X102109Y88091D01*
G01X102143Y88110D02*
X102124Y88105D01*
G01X102109Y91240D02*
X102104Y91220D01*
G01X102124Y91254D02*
X102109Y91240D01*
G01X102143Y91260D02*
X102124Y91254D01*
G01X103084Y83799D02*
X103089Y83819D01*
G01X103069Y83785D02*
X103084Y83799D01*
G01X103050Y83780D02*
X103069Y83785D01*
G01X103084Y86949D02*
X103089Y86969D01*
G01X103069Y86934D02*
X103084Y86949D01*
G01X103050Y86929D02*
X103069Y86934D01*
G01X103084Y90098D02*
X103089Y90118D01*
G01X103069Y90084D02*
X103084Y90098D01*
G01X103050Y90079D02*
X103069Y90084D01*
G01X103084Y93248D02*
X103089Y93268D01*
G01X103069Y93233D02*
X103084Y93248D01*
G01X103050Y93228D02*
X103069Y93233D01*
G01X103051Y91265D02*
Y91271D01*
G01X103050Y91261D02*
X103051Y91265D01*
G01X103050Y91260D02*
Y91261D01*
G01X103051Y88115D02*
Y88121D01*
G01X103050Y88111D02*
X103051Y88115D01*
G01X103050Y88110D02*
Y88111D01*
G01X103051Y84966D02*
Y84972D01*
G01X103050Y84962D02*
X103051Y84966D01*
G01X103050Y84961D02*
Y84962D01*
G01X116516Y80622D02*
Y80613D01*
G01X116517Y80628D02*
X116516Y80622D01*
G01X116519Y80630D02*
X116517Y80628D01*
G01X116516Y75622D02*
Y75613D01*
G01X116517Y75628D02*
X116516Y75622D01*
G01X116519Y75630D02*
X116517Y75628D01*
G01X116516Y70622D02*
Y70613D01*
G01X116517Y70628D02*
X116516Y70622D01*
G01X116519Y70630D02*
X116517Y70628D01*
G01X116516Y65622D02*
Y65613D01*
G01X116517Y65628D02*
X116516Y65622D01*
G01X116519Y65630D02*
X116517Y65628D01*
G01X116516Y60622D02*
Y60613D01*
G01X116517Y60628D02*
X116516Y60622D01*
G01X116519Y60630D02*
X116517Y60628D01*
G01X116516Y55622D02*
Y55613D01*
G01X116517Y55628D02*
X116516Y55622D01*
G01X116519Y55630D02*
X116517Y55628D01*
G01X116516Y50622D02*
Y50613D01*
G01X116517Y50628D02*
X116516Y50622D01*
G01X116519Y50630D02*
X116517Y50628D01*
G01X102106Y91226D02*
Y91234D01*
G01X102105Y91222D02*
X102106Y91226D01*
G01X102104Y91220D02*
X102105Y91222D01*
G01X102106Y88077D02*
Y88084D01*
G01X102105Y88072D02*
X102106Y88077D01*
G01X102104Y88071D02*
X102105Y88072D01*
G01X102106Y84927D02*
Y84935D01*
G01X102105Y84923D02*
X102106Y84927D01*
G01X102104Y84921D02*
X102105Y84923D01*
G01X103088Y93242D02*
X103091Y93254D01*
G01X103081Y93230D02*
X103088Y93242D01*
G01X103071Y93222D02*
X103081Y93230D01*
G01X103088Y90092D02*
X103091Y90104D01*
G01X103081Y90081D02*
X103088Y90092D01*
G01X103071Y90073D02*
X103081Y90081D01*
G01X103088Y86943D02*
X103091Y86955D01*
G01X103081Y86931D02*
X103088Y86943D01*
G01X103071Y86923D02*
X103081Y86931D01*
G01X103088Y83793D02*
X103091Y83805D01*
G01X103081Y83781D02*
X103088Y83793D01*
G01X103071Y83774D02*
X103081Y83781D01*
G01X102145Y91265D02*
Y91271D01*
G01Y91261D02*
Y91265D01*
G01X102143Y91260D02*
X102145Y91261D01*
G01Y88115D02*
Y88121D01*
G01Y88111D02*
Y88115D01*
G01X102143Y88110D02*
X102145Y88111D01*
G01Y84965D02*
Y84972D01*
G01Y84962D02*
Y84965D01*
G01X102143Y84961D02*
X102145Y84962D01*
G01X102107Y91240D02*
X102106Y91234D01*
G01X102109Y91246D02*
X102107Y91240D01*
G01X102111Y91252D02*
X102109Y91246D01*
G01X102115Y91257D02*
X102111Y91252D01*
G01X102120Y91262D02*
X102115Y91257D01*
G01X102126Y91266D02*
X102120Y91262D01*
G01X102107Y88091D02*
X102106Y88084D01*
G01X102109Y88097D02*
X102107Y88091D01*
G01X102111Y88103D02*
X102109Y88097D01*
G01X102115Y88108D02*
X102111Y88103D01*
G01X102120Y88113D02*
X102115Y88108D01*
G01X102126Y88116D02*
X102120Y88113D01*
G01X102107Y84941D02*
X102106Y84935D01*
G01X102109Y84947D02*
X102107Y84941D01*
G01X102111Y84953D02*
X102109Y84947D01*
G01X102115Y84958D02*
X102111Y84953D01*
G01X102120Y84963D02*
X102115Y84958D01*
G01X102126Y84967D02*
X102120Y84963D01*
G01X103062Y93230D02*
X103050Y93228D01*
G01X103072Y93235D02*
X103062Y93230D01*
G01Y90081D02*
X103050Y90079D01*
G01X103072Y90085D02*
X103062Y90081D01*
G01Y86931D02*
X103050Y86929D01*
G01X103072Y86936D02*
X103062Y86931D01*
G01Y83781D02*
X103050Y83780D01*
G01X103072Y83786D02*
X103062Y83781D01*
G01X166240Y55118D02*
G03X180217I6988J0D01*
G01D02*
G03X166240I-6988J0D01*
G01X180217D02*
G03I-6989J0D01*
G01X107087Y25138D02*
G03X107677Y24547I590J-1D01*
G01X114370D02*
G03X114961Y25138I0J591D01*
G01X112205Y26319D02*
G03Y28287I0J984D01*
G01X109843D02*
G03Y26319I0J-984D01*
G01X112126Y39508D02*
G03I-1102J0D01*
G01X113583Y34232D02*
G03X114764Y35413I0J1181D01*
G01X107283D02*
G03X108465Y34232I1181J0D01*
G01X112598Y39508D02*
G03I-1574J0D01*
G01X100197Y25728D02*
G03X102165Y23760I1968J0D01*
G01X119882D02*
G03X121850Y25728I0J1968D01*
G01X106496Y47500D02*
X105315Y46319D01*
G01X103543Y44823D02*
X100197Y41476D01*
G01X113508Y42579D02*
X112205Y40610D01*
G01X107532Y34688D02*
X109843Y38917D01*
G01X102104Y93263D02*
X101993Y93268D01*
G01X102104Y86965D02*
X101993Y86969D01*
G01X102106Y93071D02*
X103091D01*
G01X102146Y93031D02*
X103051D01*
G01Y91457D02*
X102146D01*
G01X103091Y91417D02*
X102106D01*
G01Y89921D02*
X103091D01*
G01X102146Y89882D02*
X103051D01*
G01Y88307D02*
X102146D01*
G01X103091Y88268D02*
X102106D01*
G01Y86772D02*
X103091D01*
G01X102146Y86732D02*
X103051D01*
G01Y85157D02*
X102146D01*
G01X103091Y85118D02*
X102106D01*
G01X115945Y83957D02*
X112008D01*
G01X102106Y83622D02*
X103091D01*
G01X102146Y83583D02*
X103051D01*
G01X117126Y82776D02*
X113189D01*
G01X116516Y82500D02*
X115531D01*
G01X115533Y82008D02*
X120866D01*
G01Y81969D02*
X116518D01*
G01X103543Y81614D02*
X100197D01*
G01X120866Y80630D02*
X115533D01*
G01X115531Y80138D02*
X116516D01*
G01Y77500D02*
X115531D01*
G01X115533Y77008D02*
X120866D01*
G01Y76969D02*
X116518D01*
G01X120866Y75630D02*
X115533D01*
G01X115531Y75138D02*
X116516D01*
G01Y72500D02*
X115531D01*
G01X115533Y72008D02*
X120866D01*
G01Y71969D02*
X116518D01*
G01X120866Y70630D02*
X115533D01*
G01X115531Y70138D02*
X116516D01*
G01Y67500D02*
X115531D01*
G01X115533Y67008D02*
X120866D01*
G01Y66969D02*
X116518D01*
G01X120866Y65630D02*
X115533D01*
G01X115531Y65138D02*
X116516D01*
G01Y62500D02*
X115531D01*
G01X115533Y62008D02*
X120866D01*
G01Y61969D02*
X116518D01*
G01X120866Y60630D02*
X115533D01*
G01X115531Y60138D02*
X116516D01*
G01Y57500D02*
X115531D01*
G01X115533Y57008D02*
X120866D01*
G01Y56969D02*
X116518D01*
G01X120866Y55630D02*
X115533D01*
G01X115531Y55138D02*
X116516D01*
G01Y52500D02*
X115531D01*
G01X115533Y52008D02*
X120866D01*
G01Y51969D02*
X116518D01*
G01X120866Y50630D02*
X115533D01*
G01X115531Y50138D02*
X116516D01*
G01X112008Y47500D02*
X106496D01*
G01X113189Y46319D02*
X105315D01*
G01X118504Y44823D02*
X103543D01*
G01X114764Y43957D02*
X117913D01*
G01X107283D02*
X103543D01*
G01Y42579D02*
X117913D01*
G01X112205Y40610D02*
X109843D01*
G01X112205Y38917D02*
X109843D01*
G01X115531Y82204D02*
X116487Y82205D01*
G01X116516Y80434D02*
X115531Y80433D01*
G01Y77204D02*
X116487Y77205D01*
G01X116516Y75434D02*
X115531Y75433D01*
G01Y72204D02*
X116487Y72205D01*
G01X116516Y70434D02*
X115531Y70433D01*
G01Y67204D02*
X116487Y67205D01*
G01X116516Y65434D02*
X115531Y65433D01*
G01Y62204D02*
X116487Y62205D01*
G01X116516Y60434D02*
X115531Y60433D01*
G01Y57204D02*
X116487Y57205D01*
G01X116516Y55434D02*
X115531Y55433D01*
G01Y52204D02*
X116487Y52205D01*
G01X116516Y50434D02*
X115531Y50433D01*
G01X113583Y34232D02*
X108465D01*
G01X121850Y34193D02*
X100197D01*
G01X114961Y31240D02*
X107087D01*
G01Y29665D02*
X114961D01*
G01X112205Y28287D02*
X109843D01*
G01Y26319D02*
X112205D01*
G01X114370Y24547D02*
X107677D01*
G01X119882Y23760D02*
X102165D01*
G01X103090Y84923D02*
X103091Y84935D01*
G01X103090Y88073D02*
X103091Y88084D01*
G01X103090Y91222D02*
X103091Y91234D01*
G01X116516Y51982D02*
Y51991D01*
G01Y56982D02*
Y56991D01*
G01Y61982D02*
Y61991D01*
G01Y66982D02*
Y66991D01*
G01Y71982D02*
Y71991D01*
G01Y76982D02*
Y76991D01*
G01Y81982D02*
Y81991D01*
G01X121850Y25728D02*
Y41476D01*
G01X120866Y80630D02*
Y82008D01*
G01Y75630D02*
Y77008D01*
G01Y70630D02*
Y72008D01*
G01Y65630D02*
Y67008D01*
G01Y60630D02*
Y62008D01*
G01Y55630D02*
Y57008D01*
G01Y50630D02*
Y52008D01*
G01X118504Y182815D02*
Y44823D01*
G01X117913Y185059D02*
Y42579D01*
G01X117697Y52008D02*
Y50630D01*
G01Y57008D02*
Y55630D01*
G01Y62008D02*
Y60630D01*
G01Y67008D02*
Y65630D01*
G01Y72008D02*
Y70630D01*
G01Y77008D02*
Y75630D01*
G01Y82008D02*
Y80630D01*
G01X117126Y104862D02*
Y82776D01*
G01X116516Y56982D02*
Y57125D01*
G01Y51982D02*
Y52125D01*
G01Y66982D02*
Y67125D01*
G01Y61982D02*
Y62125D01*
G01Y76982D02*
Y77125D01*
G01Y71982D02*
Y72125D01*
G01Y81982D02*
Y82125D01*
G01Y80138D02*
Y82500D01*
G01Y75138D02*
Y77500D01*
G01Y70138D02*
Y72500D01*
G01Y65138D02*
Y67500D01*
G01Y60138D02*
Y62500D01*
G01Y55138D02*
Y57500D01*
G01Y50138D02*
Y52500D01*
G01X115945Y103681D02*
Y83957D01*
G01X115531Y52500D02*
Y50138D01*
G01Y57500D02*
Y55138D01*
G01Y62500D02*
Y60138D01*
G01Y67500D02*
Y65138D01*
G01Y72500D02*
Y70138D01*
G01Y77500D02*
Y75138D01*
G01Y82500D02*
Y80138D01*
G01X114961Y31240D02*
Y25138D01*
G01X114764Y43957D02*
Y35413D01*
G01X113189Y82776D02*
Y46319D01*
G01X112205Y40610D02*
Y38917D01*
G01X112008Y83957D02*
Y47500D01*
G01X109843Y38917D02*
Y40610D01*
G01X107283Y35413D02*
Y43957D01*
G01X107087Y31240D02*
Y25138D01*
G01X106496Y47500D02*
Y180138D01*
G01X105315Y46319D02*
Y181319D01*
G01X103543Y81614D02*
Y42579D01*
G01X103091Y93070D02*
Y94567D01*
G01Y89921D02*
Y91417D01*
G01Y86771D02*
Y88268D01*
G01Y83622D02*
Y85118D01*
G01X103051Y86918D02*
Y86771D01*
G01Y83768D02*
Y83621D01*
G01Y85119D02*
Y84972D01*
G01Y90067D02*
Y89920D01*
G01Y91418D02*
Y91271D01*
G01Y88268D02*
Y88121D01*
G01Y93217D02*
Y93070D01*
G01X102146D02*
Y93217D01*
G01Y89920D02*
Y90067D01*
G01Y91271D02*
Y91418D01*
G01Y88121D02*
Y88268D01*
G01Y86771D02*
Y86918D01*
G01Y83621D02*
Y83768D01*
G01Y84972D02*
Y85119D01*
G01X102106Y85118D02*
Y83622D01*
G01Y91417D02*
Y89921D01*
G01Y88268D02*
Y86772D01*
G01Y94567D02*
Y93071D01*
G01X100925Y88110D02*
Y86929D01*
G01Y84961D02*
Y83780D01*
G01Y91260D02*
Y90079D01*
G01Y94409D02*
Y93228D01*
G01X100591Y106024D02*
Y81614D01*
G01X100197D02*
Y106024D01*
G01Y41476D02*
Y25728D01*
G01X103091Y93254D02*
X103090Y93265D01*
G01X103091Y90105D02*
X103090Y90115D01*
G01X103091Y86955D02*
X103090Y86966D01*
G01X103091Y83806D02*
X103090Y83816D01*
G01X112205Y38917D02*
X114515Y34688D01*
G01X109843Y40610D02*
X108539Y42579D01*
G01X115945Y83957D02*
X117126Y82776D01*
G01X112008Y83957D02*
X113189Y82776D01*
G01X118504Y44823D02*
X121850Y41476D01*
G01X112008Y47500D02*
X113189Y46319D01*
G01X102145Y96373D02*
X102146Y96367D01*
G01X102144Y96377D02*
X102145Y96373D01*
G01X102143Y96378D02*
X102144Y96377D01*
G01X102145Y99522D02*
X102146Y99516D01*
G01X102144Y99526D02*
X102145Y99522D01*
G01X102143Y99528D02*
X102144Y99526D01*
G01X102145Y102672D02*
X102146Y102666D01*
G01X102144Y102676D02*
X102145Y102672D01*
G01X102143Y102677D02*
X102144Y102676D01*
G01X116516Y106975D02*
Y106982D01*
G01X116517Y106970D02*
X116516Y106975D01*
G01X116518Y106969D02*
X116517Y106970D01*
G01X116516Y111975D02*
Y111982D01*
G01X116517Y111970D02*
X116516Y111975D01*
G01X116518Y111969D02*
X116517Y111970D01*
G01X116516Y116975D02*
Y116982D01*
G01X116517Y116970D02*
X116516Y116975D01*
G01X116518Y116969D02*
X116517Y116970D01*
G01X116516Y121975D02*
Y121982D01*
G01X116517Y121970D02*
X116516Y121975D01*
G01X116518Y121969D02*
X116517Y121970D01*
G01X116516Y126975D02*
Y126982D01*
G01X116517Y126970D02*
X116516Y126975D01*
G01X116518Y126969D02*
X116517Y126970D01*
G01X116516Y131975D02*
Y131982D01*
G01X116517Y131970D02*
X116516Y131975D01*
G01X116518Y131969D02*
X116517Y131970D01*
G01X102129Y96380D02*
X102143Y96378D01*
G01X102117Y96388D02*
X102129Y96380D01*
G01X102106Y96406D02*
X102117Y96388D01*
G01X102129Y99530D02*
X102143Y99528D01*
G01X102117Y99538D02*
X102129Y99530D01*
G01X102105Y99558D02*
X102117Y99538D01*
G01X103091Y96411D02*
Y96404D01*
G01X103090Y96416D02*
X103091Y96411D01*
G01X103089Y96417D02*
X103090Y96416D01*
G01X103091Y99561D02*
Y99553D01*
G01X103090Y99565D02*
X103091Y99561D01*
G01X103089Y99567D02*
X103090Y99565D01*
G01X103091Y102711D02*
Y102703D01*
G01X103090Y102715D02*
X103091Y102711D01*
G01X103089Y102717D02*
X103090Y102715D01*
G01X102129Y102680D02*
X102143Y102677D01*
G01X102116Y102688D02*
X102129Y102680D01*
G01X102105Y102708D02*
X102116Y102688D01*
G01X103090Y94390D02*
X103091Y94383D01*
G01X103088Y94396D02*
X103090Y94390D01*
G01X103085Y94402D02*
X103088Y94396D01*
G01X103090Y97540D02*
X103091Y97533D01*
G01X103088Y97546D02*
X103090Y97540D01*
G01X103085Y97552D02*
X103088Y97546D01*
G01X103090Y100689D02*
X103091Y100683D01*
G01X103088Y100696D02*
X103090Y100689D01*
G01X103085Y100702D02*
X103088Y100696D01*
G01X103090Y103839D02*
X103091Y103832D01*
G01X103088Y103845D02*
X103090Y103839D01*
G01X103085Y103851D02*
X103088Y103845D01*
G01X103052Y96373D02*
Y96367D01*
G01X103050Y96376D02*
X103052Y96373D01*
G01X103050Y96378D02*
Y96376D01*
G01X103052Y102672D02*
Y102666D01*
G01X103050Y102676D02*
X103052Y102672D01*
G01X103050Y102677D02*
Y102676D01*
G01X103059Y94408D02*
X103050Y94409D01*
G01X103068Y94405D02*
X103059Y94408D01*
G01X103076Y94400D02*
X103068Y94405D01*
G01X103059Y97558D02*
X103050Y97559D01*
G01X103068Y97555D02*
X103059Y97558D01*
G01X103076Y97549D02*
X103068Y97555D01*
G01X103059Y100707D02*
X103050Y100709D01*
G01X103068Y100704D02*
X103059Y100707D01*
G01X103076Y100699D02*
X103068Y100704D01*
G01X103059Y103857D02*
X103050Y103858D01*
G01X103068Y103854D02*
X103059Y103857D01*
G01X103076Y103848D02*
X103068Y103854D01*
G01X116516Y136975D02*
Y136982D01*
G01X116517Y136970D02*
X116516Y136975D01*
G01X116518Y136969D02*
X116517Y136970D01*
G01X116516Y141975D02*
Y141982D01*
G01X116517Y141970D02*
X116516Y141975D01*
G01X116518Y141969D02*
X116517Y141970D01*
G01X116516Y146975D02*
Y146982D01*
G01X116517Y146970D02*
X116516Y146975D01*
G01X116518Y146969D02*
X116517Y146970D01*
G01X116516Y151975D02*
Y151982D01*
G01X116517Y151970D02*
X116516Y151975D01*
G01X116518Y151969D02*
X116517Y151970D01*
G01X116516Y156975D02*
Y156982D01*
G01X116517Y156970D02*
X116516Y156975D01*
G01X116518Y156969D02*
X116517Y156970D01*
G01X116516Y161975D02*
Y161982D01*
G01X116517Y161970D02*
X116516Y161975D01*
G01X116518Y161969D02*
X116517Y161970D01*
G01X116516Y166975D02*
Y166982D01*
G01X116517Y166970D02*
X116516Y166975D01*
G01X116518Y166969D02*
X116517Y166970D01*
G01X116516Y171975D02*
Y171982D01*
G01X116517Y171970D02*
X116516Y171975D01*
G01X116518Y171969D02*
X116517Y171970D01*
G01X116516Y176975D02*
Y176982D01*
G01X116517Y176970D02*
X116516Y176975D01*
G01X116518Y176969D02*
X116517Y176970D01*
G01X115531Y107015D02*
Y107024D01*
G01X115532Y107009D02*
X115531Y107015D01*
G01X115533Y107008D02*
X115532Y107009D01*
G01X115531Y112015D02*
Y112024D01*
G01X115532Y112009D02*
X115531Y112015D01*
G01X115533Y112008D02*
X115532Y112009D01*
G01X115531Y117015D02*
Y117024D01*
G01X115532Y117009D02*
X115531Y117015D01*
G01X115533Y117008D02*
X115532Y117009D01*
G01X115531Y122015D02*
Y122024D01*
G01X115532Y122009D02*
X115531Y122015D01*
G01X115533Y122008D02*
X115532Y122009D01*
G01X115531Y127015D02*
Y127024D01*
G01X115532Y127009D02*
X115531Y127015D01*
G01X115533Y127008D02*
X115532Y127009D01*
G01X115531Y132015D02*
Y132024D01*
G01X115532Y132009D02*
X115531Y132015D01*
G01X115533Y132008D02*
X115532Y132009D01*
G01X115531Y137015D02*
Y137024D01*
G01X115532Y137009D02*
X115531Y137015D01*
G01X115533Y137008D02*
X115532Y137009D01*
G01X115531Y142015D02*
Y142024D01*
G01X115532Y142009D02*
X115531Y142015D01*
G01X115533Y142008D02*
X115532Y142009D01*
G01X115531Y147015D02*
Y147024D01*
G01X115532Y147009D02*
X115531Y147015D01*
G01X115533Y147008D02*
X115532Y147009D01*
G01X115531Y152015D02*
Y152024D01*
G01X115532Y152009D02*
X115531Y152015D01*
G01X115533Y152008D02*
X115532Y152009D01*
G01X115531Y157015D02*
Y157024D01*
G01X115532Y157009D02*
X115531Y157015D01*
G01X115533Y157008D02*
X115532Y157009D01*
G01X115531Y162015D02*
Y162024D01*
G01X115532Y162009D02*
X115531Y162015D01*
G01X115533Y162008D02*
X115532Y162009D01*
G01X115531Y167015D02*
Y167024D01*
G01X115532Y167009D02*
X115531Y167015D01*
G01X115533Y167008D02*
X115532Y167009D01*
G01X115531Y172015D02*
Y172024D01*
G01X115532Y172009D02*
X115531Y172015D01*
G01X115533Y172008D02*
X115532Y172009D01*
G01X115531Y177015D02*
Y177024D01*
G01X115532Y177009D02*
X115531Y177015D01*
G01X115533Y177008D02*
X115532Y177009D01*
G01X116508Y107152D02*
X116516Y107125D01*
G01X116498Y107178D02*
X116508Y107152D01*
G01X116487Y107205D02*
X116498Y107178D01*
G01X116508Y112152D02*
X116516Y112125D01*
G01X116498Y112178D02*
X116508Y112152D01*
G01X116487Y112205D02*
X116498Y112178D01*
G01X116508Y117152D02*
X116516Y117125D01*
G01X116498Y117178D02*
X116508Y117152D01*
G01X116487Y117205D02*
X116498Y117178D01*
G01X116508Y122152D02*
X116516Y122125D01*
G01X116498Y122178D02*
X116508Y122152D01*
G01X116487Y122205D02*
X116498Y122178D01*
G01X116508Y127152D02*
X116516Y127125D01*
G01X116498Y127178D02*
X116508Y127152D01*
G01X116487Y127205D02*
X116498Y127178D01*
G01X116508Y132152D02*
X116516Y132125D01*
G01X116498Y132178D02*
X116508Y132152D01*
G01X116487Y132205D02*
X116498Y132178D01*
G01X116508Y137152D02*
X116516Y137125D01*
G01X116498Y137178D02*
X116508Y137152D01*
G01X116487Y137205D02*
X116498Y137178D01*
G01X116508Y142152D02*
X116516Y142125D01*
G01X116498Y142178D02*
X116508Y142152D01*
G01X116487Y142205D02*
X116498Y142178D01*
G01X116508Y147152D02*
X116516Y147125D01*
G01X116498Y147178D02*
X116508Y147152D01*
G01X116487Y147205D02*
X116498Y147178D01*
G01X116508Y152152D02*
X116516Y152125D01*
G01X116498Y152178D02*
X116508Y152152D01*
G01X116487Y152205D02*
X116498Y152178D01*
G01X116508Y157152D02*
X116516Y157125D01*
G01X116498Y157178D02*
X116508Y157152D01*
G01X116487Y157205D02*
X116498Y157178D01*
G01X116508Y162152D02*
X116516Y162125D01*
G01X116498Y162178D02*
X116508Y162152D01*
G01X116487Y162205D02*
X116498Y162178D01*
G01X116508Y167152D02*
X116516Y167125D01*
G01X116498Y167178D02*
X116508Y167152D01*
G01X116487Y167205D02*
X116498Y167178D01*
G01X116508Y172152D02*
X116516Y172125D01*
G01X116498Y172178D02*
X116508Y172152D01*
G01X116487Y172205D02*
X116498Y172178D01*
G01X116508Y177152D02*
X116516Y177125D01*
G01X116498Y177178D02*
X116508Y177152D01*
G01X116487Y177205D02*
X116498Y177178D01*
G01Y107003D02*
X116479Y107008D01*
G01X116513Y106988D02*
X116498Y107003D01*
G01X116518Y106969D02*
X116513Y106988D01*
G01X116498Y112003D02*
X116479Y112008D01*
G01X116513Y111988D02*
X116498Y112003D01*
G01X116518Y111969D02*
X116513Y111988D01*
G01X116498Y117003D02*
X116479Y117008D01*
G01X116513Y116988D02*
X116498Y117003D01*
G01X116518Y116969D02*
X116513Y116988D01*
G01X116498Y122003D02*
X116479Y122008D01*
G01X116513Y121988D02*
X116498Y122003D01*
G01X116518Y121969D02*
X116513Y121988D01*
G01X116498Y127003D02*
X116479Y127008D01*
G01X116513Y126988D02*
X116498Y127003D01*
G01X116518Y126969D02*
X116513Y126988D01*
G01X116498Y132003D02*
X116479Y132008D01*
G01X116513Y131988D02*
X116498Y132003D01*
G01X116518Y131969D02*
X116513Y131988D01*
G01X116498Y137003D02*
X116479Y137008D01*
G01X116513Y136988D02*
X116498Y137003D01*
G01X116518Y136969D02*
X116513Y136988D01*
G01X116498Y142003D02*
X116479Y142008D01*
G01X116513Y141988D02*
X116498Y142003D01*
G01X116518Y141969D02*
X116513Y141988D01*
G01X116498Y147003D02*
X116479Y147008D01*
G01X116513Y146988D02*
X116498Y147003D01*
G01X116518Y146969D02*
X116513Y146988D01*
G01X116498Y152003D02*
X116479Y152008D01*
G01X116513Y151988D02*
X116498Y152003D01*
G01X116518Y151969D02*
X116513Y151988D01*
G01X116498Y157003D02*
X116479Y157008D01*
G01X116513Y156988D02*
X116498Y157003D01*
G01X116518Y156969D02*
X116513Y156988D01*
G01X116498Y162003D02*
X116479Y162008D01*
G01X116513Y161988D02*
X116498Y162003D01*
G01X116518Y161969D02*
X116513Y161988D01*
G01X116498Y167003D02*
X116479Y167008D01*
G01X116513Y166988D02*
X116498Y167003D01*
G01X116518Y166969D02*
X116513Y166988D01*
G01X116483Y107106D02*
X116487Y107205D01*
G01X116477Y107034D02*
X116483Y107106D01*
G01X116479Y107008D02*
X116477Y107034D01*
G01X116483Y112106D02*
X116487Y112205D01*
G01X116477Y112034D02*
X116483Y112106D01*
G01X116479Y112008D02*
X116477Y112034D01*
G01X116483Y117106D02*
X116487Y117205D01*
G01X116477Y117034D02*
X116483Y117106D01*
G01X116479Y117008D02*
X116477Y117034D01*
G01X116483Y122106D02*
X116487Y122205D01*
G01X116477Y122034D02*
X116483Y122106D01*
G01X116479Y122008D02*
X116477Y122034D01*
G01X116483Y127106D02*
X116487Y127205D01*
G01X116477Y127034D02*
X116483Y127106D01*
G01X116479Y127008D02*
X116477Y127034D01*
G01X102106Y96407D02*
Y96404D01*
G01X102108Y96401D02*
X102106Y96407D01*
G01X102119Y96386D02*
X102108Y96401D01*
G01X102144Y96378D02*
X102119Y96386D01*
G01X102106Y99557D02*
Y99553D01*
G01X102108Y99551D02*
X102106Y99557D01*
G01X102119Y99536D02*
X102108Y99551D01*
G01X102144Y99528D02*
X102119Y99536D01*
G01X102106Y102707D02*
Y102703D01*
G01X102108Y102701D02*
X102106Y102707D01*
G01X102119Y102685D02*
X102108Y102701D01*
G01X102144Y102677D02*
X102119Y102685D01*
G01X116503Y106999D02*
X116514Y106984D01*
G01X116479Y107008D02*
X116503Y106999D01*
G01Y111999D02*
X116514Y111984D01*
G01X116479Y112008D02*
X116503Y111999D01*
G01X116498Y172003D02*
X116479Y172008D01*
G01X116513Y171988D02*
X116498Y172003D01*
G01X116518Y171969D02*
X116513Y171988D01*
G01X116498Y177003D02*
X116479Y177008D01*
G01X116513Y176988D02*
X116498Y177003D01*
G01X116518Y176969D02*
X116513Y176988D01*
G01X103083Y94391D02*
X103076Y94400D01*
G01X103088Y94381D02*
X103083Y94391D01*
G01X103089Y94370D02*
X103088Y94381D01*
G01X103083Y97541D02*
X103076Y97549D01*
G01X103088Y97531D02*
X103083Y97541D01*
G01X103089Y97520D02*
X103088Y97531D01*
G01X103083Y100691D02*
X103076Y100699D01*
G01X103088Y100680D02*
X103083Y100691D01*
G01X103089Y100669D02*
X103088Y100680D01*
G01X103083Y103840D02*
X103076Y103848D01*
G01X103088Y103830D02*
X103083Y103840D01*
G01X103089Y103819D02*
X103088Y103830D01*
G01X116483Y132106D02*
X116487Y132205D01*
G01X116477Y132034D02*
X116483Y132106D01*
G01X116479Y132008D02*
X116477Y132034D01*
G01X116483Y137106D02*
X116487Y137205D01*
G01X116477Y137034D02*
X116483Y137106D01*
G01X116479Y137008D02*
X116477Y137034D01*
G01X116483Y142106D02*
X116487Y142205D01*
G01X116477Y142034D02*
X116483Y142106D01*
G01X116479Y142008D02*
X116477Y142034D01*
G01X116483Y147106D02*
X116487Y147205D01*
G01X116477Y147034D02*
X116483Y147106D01*
G01X116479Y147008D02*
X116477Y147034D01*
G01X116483Y152106D02*
X116487Y152205D01*
G01X116477Y152034D02*
X116483Y152106D01*
G01X116479Y152008D02*
X116477Y152034D01*
G01X116483Y157106D02*
X116487Y157205D01*
G01X116477Y157034D02*
X116483Y157106D01*
G01X116479Y157008D02*
X116477Y157034D01*
G01X116483Y162106D02*
X116487Y162205D01*
G01X116477Y162034D02*
X116483Y162106D01*
G01X116479Y162008D02*
X116477Y162034D01*
G01X116483Y167106D02*
X116487Y167205D01*
G01X116477Y167034D02*
X116483Y167106D01*
G01X116479Y167008D02*
X116477Y167034D01*
G01X116483Y172106D02*
X116487Y172205D01*
G01X116477Y172034D02*
X116483Y172106D01*
G01X116479Y172008D02*
X116477Y172034D01*
G01X116483Y177106D02*
X116487Y177205D01*
G01X116477Y177034D02*
X116483Y177106D01*
G01X116479Y177008D02*
X116477Y177034D01*
G01X102106Y96411D02*
Y96404D01*
G01X102105Y96416D02*
X102106Y96411D01*
G01Y96406D02*
X102105Y96416D01*
G01X102146Y104043D02*
Y104055D01*
G01X102143Y104030D02*
X102146Y104043D01*
G01X102143Y104016D02*
Y104030D01*
G01X102146Y100893D02*
Y100906D01*
G01X102143Y100880D02*
X102146Y100893D01*
G01X102143Y100866D02*
Y100880D01*
G01X102146Y97743D02*
Y97756D01*
G01X102143Y97730D02*
X102146Y97743D01*
G01X102143Y97717D02*
Y97730D01*
G01X102146Y94594D02*
Y94606D01*
G01X102143Y94581D02*
X102146Y94594D01*
G01X102143Y94567D02*
Y94581D01*
G01X115532Y175628D02*
X115533Y175630D01*
G01X115531Y175622D02*
X115532Y175628D01*
G01X115531Y175614D02*
Y175622D01*
G01X115532Y170628D02*
X115533Y170630D01*
G01X115531Y170622D02*
X115532Y170628D01*
G01X115531Y170614D02*
Y170622D01*
G01X115532Y165628D02*
X115533Y165630D01*
G01X115531Y165622D02*
X115532Y165628D01*
G01X115531Y165614D02*
Y165622D01*
G01X115532Y160628D02*
X115533Y160630D01*
G01X115531Y160622D02*
X115532Y160628D01*
G01X115531Y160614D02*
Y160622D01*
G01X115532Y155628D02*
X115533Y155630D01*
G01X115531Y155622D02*
X115532Y155628D01*
G01X115531Y155614D02*
Y155622D01*
G01X115532Y150628D02*
X115533Y150630D01*
G01X115531Y150622D02*
X115532Y150628D01*
G01X115531Y150614D02*
Y150622D01*
G01X115532Y145628D02*
X115533Y145630D01*
G01X115531Y145622D02*
X115532Y145628D01*
G01X115531Y145614D02*
Y145622D01*
G01X115532Y140628D02*
X115533Y140630D01*
G01X115531Y140622D02*
X115532Y140628D01*
G01X115531Y140614D02*
Y140622D01*
G01X115532Y135628D02*
X115533Y135630D01*
G01X115531Y135622D02*
X115532Y135628D01*
G01X115531Y135614D02*
Y135622D01*
G01X115532Y130628D02*
X115533Y130630D01*
G01X115531Y130622D02*
X115532Y130628D01*
G01X115531Y130614D02*
Y130622D01*
G01X115532Y125628D02*
X115533Y125630D01*
G01X115531Y125622D02*
X115532Y125628D01*
G01X115531Y125614D02*
Y125622D01*
G01X115532Y120628D02*
X115533Y120630D01*
G01X115531Y120622D02*
X115532Y120628D01*
G01X115531Y120614D02*
Y120622D01*
G01X115532Y115628D02*
X115533Y115630D01*
G01X115531Y115622D02*
X115532Y115628D01*
G01X115531Y115614D02*
Y115622D01*
G01X115532Y110628D02*
X115533Y110630D01*
G01X115531Y110622D02*
X115532Y110628D01*
G01X115531Y110614D02*
Y110622D01*
G01X115532Y105628D02*
X115533Y105630D01*
G01X115531Y105622D02*
X115532Y105628D01*
G01X115531Y105614D02*
Y105622D01*
G01X102106Y102711D02*
Y102703D01*
G01X102105Y102715D02*
X102106Y102711D01*
G01X102105Y102707D02*
Y102715D01*
G01X102143Y102506D02*
X102142Y102519D01*
G01X102146Y102493D02*
X102143Y102506D01*
G01X102146Y102480D02*
Y102493D01*
G01X102143Y99356D02*
X102142Y99370D01*
G01X102146Y99343D02*
X102143Y99356D01*
G01X102146Y99331D02*
Y99343D01*
G01X102143Y96206D02*
X102142Y96220D01*
G01X102146Y96194D02*
X102143Y96206D01*
G01X102146Y96181D02*
Y96194D01*
G01X103054Y104030D02*
X103055Y104016D01*
G01X103050Y104043D02*
X103054Y104030D01*
G01X103051Y104055D02*
X103050Y104043D01*
G01X103054Y100880D02*
X103055Y100866D01*
G01X103050Y100893D02*
X103054Y100880D01*
G01X103051Y100906D02*
X103050Y100893D01*
G01X103054Y97730D02*
X103055Y97717D01*
G01X103050Y97743D02*
X103054Y97730D01*
G01X103051Y97756D02*
X103050Y97743D01*
G01X103054Y94581D02*
X103055Y94567D01*
G01X103050Y94594D02*
X103054Y94581D01*
G01X103051Y94606D02*
X103050Y94594D01*
G01X102106Y99561D02*
Y99554D01*
G01X102105Y99565D02*
X102106Y99561D01*
G01X102105Y99558D02*
Y99565D01*
G01X116503Y116999D02*
X116514Y116984D01*
G01X116479Y117008D02*
X116503Y116999D01*
G01Y121999D02*
X116514Y121984D01*
G01X116479Y122008D02*
X116503Y121999D01*
G01Y126999D02*
X116514Y126984D01*
G01X116479Y127008D02*
X116503Y126999D01*
G01Y131999D02*
X116514Y131984D01*
G01X116479Y132008D02*
X116503Y131999D01*
G01Y136999D02*
X116514Y136984D01*
G01X116479Y137008D02*
X116503Y136999D01*
G01Y141999D02*
X116514Y141984D01*
G01X116479Y142008D02*
X116503Y141999D01*
G01Y146999D02*
X116514Y146984D01*
G01X116479Y147008D02*
X116503Y146999D01*
G01Y151999D02*
X116514Y151984D01*
G01X116479Y152008D02*
X116503Y151999D01*
G01Y156999D02*
X116514Y156984D01*
G01X116479Y157008D02*
X116503Y156999D01*
G01Y161999D02*
X116514Y161984D01*
G01X116479Y162008D02*
X116503Y161999D01*
G01Y166999D02*
X116514Y166984D01*
G01X116479Y167008D02*
X116503Y166999D01*
G01X116514Y171984D02*
X116516Y171978D01*
G01X116503Y171999D02*
X116514Y171984D01*
G01X116479Y172008D02*
X116503Y171999D01*
G01Y176999D02*
X116514Y176984D01*
G01X116479Y177008D02*
X116503Y176999D01*
G01X103050Y102493D02*
X103051Y102480D01*
G01X103053Y102506D02*
X103050Y102493D01*
G01X103054Y102519D02*
X103053Y102506D01*
G01X103050Y99343D02*
X103051Y99331D01*
G01X103053Y99356D02*
X103050Y99343D01*
G01X103054Y99370D02*
X103053Y99356D01*
G01X103050Y96194D02*
X103051Y96181D01*
G01X103053Y96206D02*
X103050Y96194D01*
G01X103054Y96220D02*
X103053Y96206D01*
G01X103081Y94408D02*
X103085Y94402D01*
G01X103076Y94412D02*
X103081Y94408D01*
G01X103070Y94416D02*
X103076Y94412D01*
G01X103065Y94419D02*
X103070Y94416D01*
G01X103058Y94420D02*
X103065Y94419D01*
G01X103051Y94420D02*
X103058D01*
G01X103081Y97557D02*
X103085Y97552D01*
G01X103076Y97562D02*
X103081Y97557D01*
G01X103070Y97565D02*
X103076Y97562D01*
G01X103065Y97568D02*
X103070Y97565D01*
G01X103058Y97570D02*
X103065Y97568D01*
G01X103051Y97570D02*
X103058D01*
G01X103081Y100707D02*
X103085Y100702D01*
G01X103076Y100711D02*
X103081Y100707D01*
G01X103070Y100715D02*
X103076Y100711D01*
G01X103065Y100718D02*
X103070Y100715D01*
G01X103058Y100719D02*
X103065Y100718D01*
G01X103051Y100720D02*
X103058Y100719D01*
G01X102107Y96396D02*
X102106Y96404D01*
G01X102109Y96389D02*
X102107Y96396D01*
G01X102113Y96383D02*
X102109Y96389D01*
G01X102118Y96378D02*
X102113Y96383D01*
G01X102124Y96373D02*
X102118Y96378D01*
G01X102131Y96369D02*
X102124Y96373D01*
G01X102138Y96367D02*
X102131Y96369D01*
G01X102146Y96367D02*
X102138D01*
G01X102107Y99546D02*
X102106Y99553D01*
G01X102109Y99539D02*
X102107Y99546D01*
G01X102113Y99533D02*
X102109Y99539D01*
G01X102118Y99527D02*
X102113Y99533D01*
G01X102124Y99522D02*
X102118Y99527D01*
G01X102131Y99519D02*
X102124Y99522D01*
G01X102138Y99517D02*
X102131Y99519D01*
G01X102146Y99516D02*
X102138Y99517D01*
G01X102107Y102696D02*
X102106Y102703D01*
G01X102109Y102689D02*
X102107Y102696D01*
G01X102113Y102682D02*
X102109Y102689D01*
G01X102118Y102677D02*
X102113Y102682D01*
G01X102124Y102672D02*
X102118Y102677D01*
G01X102131Y102669D02*
X102124Y102672D01*
G01X102138Y102667D02*
X102131Y102669D01*
G01X102146Y102666D02*
X102138Y102667D01*
G01X103060Y94408D02*
X103070Y94404D01*
G01X103050Y94409D02*
X103060Y94408D01*
G01Y97557D02*
X103070Y97554D01*
G01X103050Y97559D02*
X103060Y97557D01*
G01Y100707D02*
X103070Y100703D01*
G01X103050Y100709D02*
X103060Y100707D01*
G01Y103857D02*
X103070Y103853D01*
G01X103050Y103858D02*
X103060Y103857D01*
G01X102119Y103850D02*
X102143Y103858D01*
G01X102108Y103835D02*
X102119Y103850D01*
G01X102106Y103828D02*
X102108Y103835D01*
G01X102119Y100700D02*
X102143Y100709D01*
G01X102108Y100685D02*
X102119Y100700D01*
G01X102106Y100679D02*
X102108Y100685D01*
G01X102119Y97550D02*
X102143Y97559D01*
G01X102108Y97536D02*
X102119Y97550D01*
G01X102106Y97529D02*
X102108Y97536D01*
G01X102119Y94401D02*
X102143Y94409D01*
G01X102108Y94386D02*
X102119Y94401D01*
G01X102106Y94380D02*
X102108Y94386D01*
G01X101359Y96417D02*
X100925D01*
G01X101733D02*
X101359D01*
G01X103081Y103857D02*
X103085Y103851D01*
G01X103076Y103861D02*
X103081Y103857D01*
G01X103070Y103865D02*
X103076Y103861D01*
G01X103065Y103867D02*
X103070Y103865D01*
G01X103058Y103869D02*
X103065Y103867D01*
G01X103051Y103869D02*
X103058D01*
G01X103090Y99546D02*
X103091Y99553D01*
G01X103087Y99539D02*
X103090Y99546D01*
G01X103084Y99533D02*
X103087Y99539D01*
G01X103079Y99527D02*
X103084Y99533D01*
G01X103073Y99522D02*
X103079Y99527D01*
G01X103066Y99519D02*
X103073Y99522D01*
G01X103059Y99517D02*
X103066Y99519D01*
G01X103051Y99516D02*
X103059Y99517D01*
G01X102129Y94417D02*
X102126Y94415D01*
G01X102132Y94418D02*
X102129Y94417D01*
G01X102135Y94419D02*
X102132Y94418D01*
G01X102139Y94420D02*
X102135Y94419D01*
G01X102142Y94420D02*
X102139D01*
G01X102146D02*
X102142D01*
G01X103068Y96370D02*
X103071Y96372D01*
G01X103065Y96369D02*
X103068Y96370D01*
G01X103062Y96368D02*
X103065Y96369D01*
G01X103058Y96367D02*
X103062Y96368D01*
G01X103055Y96367D02*
X103058D01*
G01X103051D02*
X103055D01*
G01X102129Y97567D02*
X102126Y97565D01*
G01X102132Y97568D02*
X102129Y97567D01*
G01X102135Y97569D02*
X102132Y97568D01*
G01X102139Y97570D02*
X102135Y97569D01*
G01X102142Y97570D02*
X102139D01*
G01X102146D02*
X102142D01*
G01X102129Y100716D02*
X102126Y100715D01*
G01X102132Y100717D02*
X102129Y100716D01*
G01X102135Y100719D02*
X102132Y100717D01*
G01X102139Y100719D02*
X102135D01*
G01X102142Y100720D02*
X102139Y100719D01*
G01X102146Y100720D02*
X102142D01*
G01X103068Y102669D02*
X103071Y102671D01*
G01X103065Y102668D02*
X103068Y102669D01*
G01X103062Y102667D02*
X103065Y102668D01*
G01X103058Y102667D02*
X103062D01*
G01X103055Y102666D02*
X103058Y102667D01*
G01X103051Y102666D02*
X103055D01*
G01X102129Y103866D02*
X102126Y103864D01*
G01X102132Y103867D02*
X102129Y103866D01*
G01X102135Y103868D02*
X102132Y103867D01*
G01X102139Y103869D02*
X102135Y103868D01*
G01X102142Y103869D02*
X102139D01*
G01X102146D02*
X102142D01*
G01X103091Y103825D02*
Y103832D01*
G01X103090Y103820D02*
X103091Y103825D01*
G01X103089Y103819D02*
X103090Y103820D01*
G01X103091Y100676D02*
Y100683D01*
G01X103090Y100671D02*
X103091Y100676D01*
G01X103089Y100669D02*
X103090Y100671D01*
G01X103091Y97526D02*
Y97533D01*
G01X103090Y97521D02*
X103091Y97526D01*
G01X103089Y97520D02*
X103090Y97521D01*
G01X103091Y94376D02*
Y94383D01*
G01X103090Y94372D02*
X103091Y94376D01*
G01X103089Y94370D02*
X103090Y94372D01*
G01X102109Y94390D02*
X102104Y94370D01*
G01X102124Y94404D02*
X102109Y94390D01*
G01X102143Y94409D02*
X102124Y94404D01*
G01X102109Y97539D02*
X102104Y97520D01*
G01X102124Y97554D02*
X102109Y97539D01*
G01X102143Y97559D02*
X102124Y97554D01*
G01X102109Y100689D02*
X102104Y100669D01*
G01X102124Y100703D02*
X102109Y100689D01*
G01X102143Y100709D02*
X102124Y100703D01*
G01X102109Y103839D02*
X102104Y103819D01*
G01X102124Y103853D02*
X102109Y103839D01*
G01X102143Y103858D02*
X102124Y103853D01*
G01X103084Y96398D02*
X103089Y96417D01*
G01X103069Y96383D02*
X103084Y96398D01*
G01X103050Y96378D02*
X103069Y96383D01*
G01X103084Y99547D02*
X103089Y99567D01*
G01X103069Y99533D02*
X103084Y99547D01*
G01X103050Y99528D02*
X103069Y99533D01*
G01X103084Y102697D02*
X103089Y102717D01*
G01X103069Y102682D02*
X103084Y102697D01*
G01X103050Y102677D02*
X103069Y102682D01*
G01X103051Y103863D02*
Y103869D01*
G01X103050Y103859D02*
X103051Y103863D01*
G01X103050Y103858D02*
Y103859D01*
G01X103051Y100714D02*
Y100720D01*
G01X103050Y100710D02*
X103051Y100714D01*
G01X103050Y100709D02*
Y100710D01*
G01X103051Y97564D02*
Y97570D01*
G01X103050Y97560D02*
X103051Y97564D01*
G01X103050Y97559D02*
Y97560D01*
G01X103051Y94415D02*
Y94420D01*
G01X103050Y94411D02*
X103051Y94415D01*
G01X103050Y94409D02*
Y94411D01*
G01X116516Y175622D02*
Y175613D01*
G01X116517Y175628D02*
X116516Y175622D01*
G01X116519Y175630D02*
X116517Y175628D01*
G01X116516Y170622D02*
Y170613D01*
G01X116517Y170628D02*
X116516Y170622D01*
G01X116519Y170630D02*
X116517Y170628D01*
G01X116516Y165622D02*
Y165613D01*
G01X116517Y165628D02*
X116516Y165622D01*
G01X116519Y165630D02*
X116517Y165628D01*
G01X116516Y160622D02*
Y160613D01*
G01X116517Y160628D02*
X116516Y160622D01*
G01X116519Y160630D02*
X116517Y160628D01*
G01X116516Y155622D02*
Y155613D01*
G01X116517Y155628D02*
X116516Y155622D01*
G01X116519Y155630D02*
X116517Y155628D01*
G01X116516Y150622D02*
Y150613D01*
G01X116517Y150628D02*
X116516Y150622D01*
G01X116519Y150630D02*
X116517Y150628D01*
G01X116516Y145622D02*
Y145613D01*
G01X116517Y145628D02*
X116516Y145622D01*
G01X116519Y145630D02*
X116517Y145628D01*
G01X116516Y140622D02*
Y140613D01*
G01X116517Y140628D02*
X116516Y140622D01*
G01X116519Y140630D02*
X116517Y140628D01*
G01X116516Y135622D02*
Y135613D01*
G01X116517Y135628D02*
X116516Y135622D01*
G01X116519Y135630D02*
X116517Y135628D01*
G01X116516Y130622D02*
Y130613D01*
G01X116517Y130628D02*
X116516Y130622D01*
G01X116519Y130630D02*
X116517Y130628D01*
G01X116516Y125622D02*
Y125613D01*
G01X116517Y125628D02*
X116516Y125622D01*
G01X116519Y125630D02*
X116517Y125628D01*
G01X116516Y120622D02*
Y120613D01*
G01X116517Y120628D02*
X116516Y120622D01*
G01X116519Y120630D02*
X116517Y120628D01*
G01X116516Y115622D02*
Y115613D01*
G01X116517Y115628D02*
X116516Y115622D01*
G01X116519Y115630D02*
X116517Y115628D01*
G01X116516Y110622D02*
Y110613D01*
G01X116517Y110628D02*
X116516Y110622D01*
G01X116519Y110630D02*
X116517Y110628D01*
G01X116516Y105622D02*
Y105613D01*
G01X116517Y105628D02*
X116516Y105622D01*
G01X116519Y105630D02*
X116517Y105628D01*
G01X102106Y103825D02*
Y103832D01*
G01X102105Y103820D02*
X102106Y103825D01*
G01X102104Y103819D02*
X102105Y103820D01*
G01X102106Y100675D02*
Y100683D01*
G01X102105Y100671D02*
X102106Y100675D01*
G01X102104Y100669D02*
X102105Y100671D01*
G01X102106Y97526D02*
Y97533D01*
G01X102105Y97521D02*
X102106Y97526D01*
G01X102104Y97520D02*
X102105Y97521D01*
G01X102106Y94376D02*
Y94383D01*
G01X102105Y94372D02*
X102106Y94376D01*
G01X102104Y94370D02*
X102105Y94372D01*
G01X103088Y102691D02*
X103091Y102703D01*
G01X103081Y102679D02*
X103088Y102691D01*
G01X103071Y102671D02*
X103081Y102679D01*
G01X103088Y96391D02*
X103091Y96404D01*
G01X103081Y96380D02*
X103088Y96391D01*
G01X103071Y96372D02*
X103081Y96380D01*
G01X102145Y103863D02*
Y103869D01*
G01Y103859D02*
Y103863D01*
G01X102143Y103858D02*
X102145Y103859D01*
G01Y100713D02*
Y100720D01*
G01Y100710D02*
Y100713D01*
G01X102143Y100709D02*
X102145Y100710D01*
G01Y97564D02*
Y97570D01*
G01Y97560D02*
Y97564D01*
G01X102143Y97559D02*
X102145Y97560D01*
G01Y94414D02*
Y94420D01*
G01Y94411D02*
Y94414D01*
G01X102143Y94409D02*
X102145Y94411D01*
G01X102107Y103839D02*
X102106Y103832D01*
G01X102109Y103845D02*
X102107Y103839D01*
G01X102111Y103851D02*
X102109Y103845D01*
G01X102115Y103856D02*
X102111Y103851D01*
G01X102120Y103861D02*
X102115Y103856D01*
G01X102126Y103864D02*
X102120Y103861D01*
G01X102107Y100689D02*
X102106Y100683D01*
G01X102109Y100695D02*
X102107Y100689D01*
G01X102111Y100701D02*
X102109Y100695D01*
G01X102115Y100706D02*
X102111Y100701D01*
G01X102120Y100711D02*
X102115Y100706D01*
G01X102126Y100715D02*
X102120Y100711D01*
G01X102107Y97539D02*
X102106Y97533D01*
G01X102109Y97546D02*
X102107Y97539D01*
G01X102111Y97552D02*
X102109Y97546D01*
G01X102115Y97557D02*
X102111Y97552D01*
G01X102120Y97561D02*
X102115Y97557D01*
G01X102126Y97565D02*
X102120Y97561D01*
G01X102107Y94390D02*
X102106Y94383D01*
G01X102109Y94396D02*
X102107Y94390D01*
G01X102111Y94402D02*
X102109Y94396D01*
G01X102115Y94407D02*
X102111Y94402D01*
G01X102120Y94412D02*
X102115Y94407D01*
G01X102126Y94415D02*
X102120Y94412D01*
G01X103062Y102679D02*
X103050Y102677D01*
G01X103072Y102684D02*
X103062Y102679D01*
G01Y99530D02*
X103050Y99528D01*
G01X103072Y99534D02*
X103062Y99530D01*
G01Y96380D02*
X103050Y96378D01*
G01X103072Y96385D02*
X103062Y96380D01*
G01X167717Y122047D02*
G03X178741I5512J0D01*
G01D02*
G03X167717I-5512J0D01*
G01X112913Y188130D02*
G03I-1889J0D01*
G01X113386D02*
G03I-2362J0D01*
G01X178740Y122047D02*
G03I-5512J0D01*
G01X115945Y103681D02*
X117126Y104862D01*
G01X112008Y103681D02*
X113189Y104862D01*
G01X121850Y186161D02*
X118504Y182815D01*
G01X112008Y180138D02*
X113189Y181319D01*
G01X108539Y185059D02*
X109843Y187028D01*
G01X114515Y192950D02*
X112205Y188720D01*
G01X109843Y187028D02*
X112205D01*
G01X103543Y185059D02*
X117913D01*
G01X103543Y183681D02*
X107283D01*
G01X117913D02*
X114764D01*
G01X103543Y182815D02*
X118504D01*
G01X105315Y181319D02*
X113189D01*
G01X106496Y180138D02*
X112008D01*
G01X116516Y177500D02*
X115531D01*
G01X115533Y177008D02*
X120866D01*
G01Y176969D02*
X116518D01*
G01X120866Y175630D02*
X115533D01*
G01X115531Y175138D02*
X116516D01*
G01Y172500D02*
X115531D01*
G01X115533Y172008D02*
X120866D01*
G01Y171969D02*
X116518D01*
G01X120866Y170630D02*
X115533D01*
G01X115531Y170138D02*
X116516D01*
G01Y167500D02*
X115531D01*
G01X115533Y167008D02*
X120866D01*
G01Y166969D02*
X116518D01*
G01X120866Y165630D02*
X115533D01*
G01X115531Y165138D02*
X116516D01*
G01Y162500D02*
X115531D01*
G01X115533Y162008D02*
X120866D01*
G01Y161969D02*
X116518D01*
G01X120866Y160630D02*
X115533D01*
G01X115531Y160138D02*
X116516D01*
G01Y157500D02*
X115531D01*
G01X115533Y157008D02*
X120866D01*
G01Y156969D02*
X116518D01*
G01X120866Y155630D02*
X115533D01*
G01X115531Y155138D02*
X116516D01*
G01Y152500D02*
X115531D01*
G01X115533Y152008D02*
X120866D01*
G01Y151969D02*
X116518D01*
G01X120866Y150630D02*
X115533D01*
G01X115531Y150138D02*
X116516D01*
G01Y147500D02*
X115531D01*
G01X115533Y147008D02*
X120866D01*
G01Y146969D02*
X116518D01*
G01X120866Y145630D02*
X115533D01*
G01X115531Y145138D02*
X116516D01*
G01Y142500D02*
X115531D01*
G01X115533Y142008D02*
X120866D01*
G01Y141969D02*
X116518D01*
G01X120866Y140630D02*
X115533D01*
G01X115531Y140138D02*
X116516D01*
G01Y137500D02*
X115531D01*
G01X115533Y137008D02*
X120866D01*
G01Y136969D02*
X116518D01*
G01X120866Y135630D02*
X115533D01*
G01X115531Y135138D02*
X116516D01*
G01Y132500D02*
X115531D01*
G01X115533Y132008D02*
X120866D01*
G01Y131969D02*
X116518D01*
G01X120866Y130630D02*
X115533D01*
G01X115531Y130138D02*
X116516D01*
G01Y127500D02*
X115531D01*
G01X115533Y127008D02*
X120866D01*
G01Y126969D02*
X116518D01*
G01X120866Y125630D02*
X115533D01*
G01X115531Y125138D02*
X116516D01*
G01Y122500D02*
X115531D01*
G01X115533Y122008D02*
X120866D01*
G01Y121969D02*
X116518D01*
G01X120866Y120630D02*
X115533D01*
G01X115531Y120138D02*
X116516D01*
G01Y117500D02*
X115531D01*
G01Y177204D02*
X116487Y177205D01*
G01X116516Y175434D02*
X115531Y175433D01*
G01Y172204D02*
X116487Y172205D01*
G01X116516Y170434D02*
X115531Y170433D01*
G01Y167204D02*
X116487Y167205D01*
G01X116516Y165434D02*
X115531Y165433D01*
G01Y162204D02*
X116487Y162205D01*
G01X116516Y160434D02*
X115531Y160433D01*
G01Y157204D02*
X116487Y157205D01*
G01X116516Y155434D02*
X115531Y155433D01*
G01Y152204D02*
X116487Y152205D01*
G01X116516Y150434D02*
X115531Y150433D01*
G01Y147204D02*
X116487Y147205D01*
G01X116516Y145434D02*
X115531Y145433D01*
G01Y142204D02*
X116487Y142205D01*
G01X116516Y140434D02*
X115531Y140433D01*
G01Y137204D02*
X116487Y137205D01*
G01X116516Y135434D02*
X115531Y135433D01*
G01Y132204D02*
X116487Y132205D01*
G01X116516Y130434D02*
X115531Y130433D01*
G01Y127204D02*
X116487Y127205D01*
G01X116516Y125434D02*
X115531Y125433D01*
G01Y122204D02*
X116487Y122205D01*
G01X116516Y120434D02*
X115531Y120433D01*
G01Y117204D02*
X116487Y117205D01*
G01X101993Y102717D02*
X102105Y102708D01*
G01X102104Y96414D02*
X101993Y96417D01*
G01X115533Y117008D02*
X120866D01*
G01Y116969D02*
X116518D01*
G01X120866Y115630D02*
X115533D01*
G01X115531Y115138D02*
X116516D01*
G01Y112500D02*
X115531D01*
G01X115533Y112008D02*
X120866D01*
G01Y111969D02*
X116518D01*
G01X120866Y110630D02*
X115533D01*
G01X115531Y110138D02*
X116516D01*
G01Y107500D02*
X115531D01*
G01X115533Y107008D02*
X120866D01*
G01Y106969D02*
X116518D01*
G01X103543Y106024D02*
X100197D01*
G01X120866Y105630D02*
X115533D01*
G01X115531Y105138D02*
X116516D01*
G01X113189Y104862D02*
X117126D01*
G01X103051Y104055D02*
X102146D01*
G01X103091Y104016D02*
X102106D01*
G01X112008Y103681D02*
X115945D01*
G01X102106Y102520D02*
X103091D01*
G01X102146Y102480D02*
X103051D01*
G01Y100906D02*
X102146D01*
G01X103091Y100866D02*
X102106D01*
G01Y99370D02*
X103091D01*
G01X102146Y99331D02*
X103051D01*
G01Y97756D02*
X102146D01*
G01X103091Y97717D02*
X102106D01*
G01Y96220D02*
X103091D01*
G01X102146Y96181D02*
X103051D01*
G01Y94606D02*
X102146D01*
G01X103091Y94567D02*
X102106D01*
G01X116516Y115434D02*
X115531Y115433D01*
G01Y112204D02*
X116487Y112205D01*
G01X116516Y110434D02*
X115531Y110433D01*
G01Y107204D02*
X116487Y107205D01*
G01X116516Y105434D02*
X115531Y105433D01*
G01X103090Y94372D02*
X103091Y94383D01*
G01X103090Y97522D02*
X103091Y97533D01*
G01X103090Y100671D02*
X103091Y100683D01*
G01X103090Y103821D02*
X103091Y103832D01*
G01X116516Y106982D02*
Y106991D01*
G01Y111982D02*
Y111991D01*
G01Y116982D02*
Y116991D01*
G01Y121982D02*
Y121991D01*
G01Y126982D02*
Y126991D01*
G01Y131982D02*
Y131991D01*
G01Y136982D02*
Y136991D01*
G01Y141982D02*
Y141991D01*
G01Y146982D02*
Y146991D01*
G01Y151982D02*
Y151991D01*
G01Y156982D02*
Y156991D01*
G01Y161982D02*
Y161991D01*
G01Y166982D02*
Y166991D01*
G01Y171982D02*
Y171991D01*
G01Y176982D02*
Y176991D01*
G01X121850Y186161D02*
Y201909D01*
G01X120866Y175630D02*
Y177008D01*
G01Y170630D02*
Y172008D01*
G01Y165630D02*
Y167008D01*
G01Y160630D02*
Y162008D01*
G01Y155630D02*
Y157008D01*
G01Y150630D02*
Y152008D01*
G01Y145630D02*
Y147008D01*
G01Y140630D02*
Y142008D01*
G01Y135630D02*
Y137008D01*
G01Y130630D02*
Y132008D01*
G01Y125630D02*
Y127008D01*
G01Y120630D02*
Y122008D01*
G01Y115630D02*
Y117008D01*
G01Y110630D02*
Y112008D01*
G01Y105630D02*
Y107008D01*
G01X117697D02*
Y105630D01*
G01Y112008D02*
Y110630D01*
G01Y117008D02*
Y115630D01*
G01Y122008D02*
Y120630D01*
G01Y127008D02*
Y125630D01*
G01Y132008D02*
Y130630D01*
G01Y137008D02*
Y135630D01*
G01Y142008D02*
Y140630D01*
G01Y147008D02*
Y145630D01*
G01Y152008D02*
Y150630D01*
G01Y157008D02*
Y155630D01*
G01Y162008D02*
Y160630D01*
G01Y167008D02*
Y165630D01*
G01Y172008D02*
Y170630D01*
G01Y177008D02*
Y175630D01*
G01X116516Y106982D02*
Y107125D01*
G01Y116982D02*
Y117125D01*
G01Y111982D02*
Y112125D01*
G01Y126982D02*
Y127125D01*
G01Y121982D02*
Y122125D01*
G01Y136982D02*
Y137125D01*
G01Y131982D02*
Y132125D01*
G01Y146982D02*
Y147125D01*
G01Y141982D02*
Y142125D01*
G01Y156982D02*
Y157125D01*
G01Y151982D02*
Y152125D01*
G01Y166982D02*
Y167125D01*
G01Y161982D02*
Y162125D01*
G01Y176982D02*
Y177125D01*
G01Y171982D02*
Y172125D01*
G01Y175138D02*
Y177500D01*
G01Y170138D02*
Y172500D01*
G01Y165138D02*
Y167500D01*
G01Y160138D02*
Y162500D01*
G01Y155138D02*
Y157500D01*
G01Y150138D02*
Y152500D01*
G01Y145138D02*
Y147500D01*
G01Y140138D02*
Y142500D01*
G01Y135138D02*
Y137500D01*
G01Y130138D02*
Y132500D01*
G01Y125138D02*
Y127500D01*
G01Y120138D02*
Y122500D01*
G01Y115138D02*
Y117500D01*
G01Y110138D02*
Y112500D01*
G01Y105138D02*
Y107500D01*
G01X115531D02*
Y105138D01*
G01Y112500D02*
Y110138D01*
G01Y117500D02*
Y115138D01*
G01Y122500D02*
Y120138D01*
G01Y127500D02*
Y125138D01*
G01Y132500D02*
Y130138D01*
G01Y137500D02*
Y135138D01*
G01Y142500D02*
Y140138D01*
G01Y147500D02*
Y145138D01*
G01Y152500D02*
Y150138D01*
G01Y157500D02*
Y155138D01*
G01Y162500D02*
Y160138D01*
G01Y167500D02*
Y165138D01*
G01Y172500D02*
Y170138D01*
G01Y177500D02*
Y175138D01*
G01X114764Y192224D02*
Y183681D01*
G01X113189Y181319D02*
Y104862D01*
G01X112205Y188720D02*
Y187028D01*
G01X112008Y180138D02*
Y103681D01*
G01X109843Y187028D02*
Y188720D01*
G01X107283Y183681D02*
Y192224D01*
G01X103543Y185059D02*
Y106024D01*
G01X103091Y102519D02*
Y104016D01*
G01Y99370D02*
Y100866D01*
G01Y96220D02*
Y97717D01*
G01X103051Y96367D02*
Y96220D01*
G01Y94567D02*
Y94420D01*
G01Y99516D02*
Y99369D01*
G01Y100867D02*
Y100720D01*
G01Y97717D02*
Y97570D01*
G01Y102666D02*
Y102519D01*
G01Y104016D02*
Y103869D01*
G01X102146Y102519D02*
Y102666D01*
G01Y103869D02*
Y104016D01*
G01Y99369D02*
Y99516D01*
G01Y100720D02*
Y100867D01*
G01Y97570D02*
Y97717D01*
G01Y96220D02*
Y96367D01*
G01Y94420D02*
Y94567D01*
G01X102106Y100866D02*
Y99370D01*
G01Y97717D02*
Y96220D01*
G01Y104016D02*
Y102520D01*
G01X100925Y97559D02*
Y96378D01*
G01Y100709D02*
Y99528D01*
G01Y103858D02*
Y102677D01*
G01X100197Y201909D02*
Y186161D01*
G01X103091Y102703D02*
X103090Y102714D01*
G01X103091Y99554D02*
X103090Y99564D01*
G01X103091Y96404D02*
X103090Y96415D01*
G01X103050Y99528D02*
X103053Y99516D01*
G01X109843Y188720D02*
X107532Y192950D01*
G01X112205Y187028D02*
X113508Y185059D01*
G01X105315Y181319D02*
X106496Y180138D01*
G01X100197Y186161D02*
X103543Y182815D01*
G01X114295Y264712D02*
G03X148106I16905J-13531D01*
G01X141181Y277843D02*
G03X148106Y264712I37662J11471D01*
G01X141181Y277843D02*
G03X121220I-9980J-3040D01*
G01X114295Y264712D02*
G03X121220Y277843I-30737J24602D01*
G01X193307Y254331D02*
G03X192126I-591J0D01*
G01Y260630D02*
G03X193307I591J0D01*
G01Y254331D02*
G03X192126I-591J0D01*
G01Y260630D02*
G03X193307I591J0D01*
G01X141181Y277843D02*
G03X148106Y264712I37662J11471D01*
G01X141181Y277843D02*
G03X121220I-9980J-3040D01*
G01X114295Y264712D02*
G03X148106I16905J-13531D01*
G01X114295D02*
G03X121220Y277843I-30737J24601D01*
G01X114961Y202500D02*
G03X114370Y203091I-591J0D01*
G01X107677D02*
G03X107087Y202500I1J-591D01*
G01X109843Y201319D02*
G03Y199350I0J-985D01*
G01X112205D02*
G03Y201319I0J984D01*
G01X108465Y193406D02*
G03X107283Y192224I-1J-1181D01*
G01X114764D02*
G03X113583Y193406I-1181J1D01*
G01X121850Y201909D02*
G03X119882Y203878I-1968J1D01*
G01X102165D02*
G03X100197Y201909I1J-1969D01*
G01X195276Y260630D02*
X193307D01*
G01X192126D02*
X191339D01*
G01X195276D02*
X193307D01*
G01X192126D02*
X191339D01*
G01X197244Y259646D02*
X191339D01*
G01Y259449D02*
X197244D01*
G01X191339Y255512D02*
X197244D01*
G01Y255315D02*
X191339D01*
G01X193307Y254331D02*
X195276D01*
G01X191339D02*
X192126D01*
G01X193307D02*
X195276D01*
G01X191339D02*
X192126D01*
G01X119882Y203878D02*
X102165D01*
G01X114370Y203091D02*
X107677D01*
G01X112205Y201319D02*
X109843D01*
G01Y199350D02*
X112205D01*
G01X114961Y197972D02*
X107087D01*
G01Y196398D02*
X114961D01*
G01X121850Y193445D02*
X100197D01*
G01X108465Y193406D02*
X113583D01*
G01X109843Y188720D02*
X112205D01*
G01X191339Y254331D02*
Y260630D01*
G01D02*
Y254331D01*
G01X114961Y196398D02*
Y202500D01*
G01X107087Y196398D02*
Y202500D01*
G01X116483Y504862D02*
X116487Y504961D01*
G01X116477Y504790D02*
X116483Y504862D01*
G01X116479Y504764D02*
X116477Y504790D01*
G01X116483Y509862D02*
X116487Y509961D01*
G01X116477Y509790D02*
X116483Y509862D01*
G01X116479Y509764D02*
X116477Y509790D01*
G01X116483Y514862D02*
X116487Y514961D01*
G01X116477Y514790D02*
X116483Y514862D01*
G01X116479Y514764D02*
X116477Y514790D01*
G01X116483Y519862D02*
X116487Y519961D01*
G01X116477Y519790D02*
X116483Y519862D01*
G01X116479Y519764D02*
X116477Y519790D01*
G01X116483Y524862D02*
X116487Y524961D01*
G01X116477Y524790D02*
X116483Y524862D01*
G01X116479Y524764D02*
X116477Y524790D01*
G01X116483Y529862D02*
X116487Y529961D01*
G01X116477Y529790D02*
X116483Y529862D01*
G01X116479Y529764D02*
X116477Y529790D01*
G01X116483Y534862D02*
X116487Y534961D01*
G01X116477Y534790D02*
X116483Y534862D01*
G01X116479Y534764D02*
X116477Y534790D01*
G01X116483Y559862D02*
X116487Y559961D01*
G01X116477Y559790D02*
X116483Y559862D01*
G01X116479Y559764D02*
X116477Y559790D01*
G01X116483Y564862D02*
X116487Y564961D01*
G01X116477Y564790D02*
X116483Y564862D01*
G01X116479Y564764D02*
X116477Y564790D01*
G01X116483Y569862D02*
X116487Y569961D01*
G01X116477Y569790D02*
X116483Y569862D01*
G01X116479Y569764D02*
X116477Y569790D01*
G01X102106Y549167D02*
Y549160D01*
G01X102105Y549172D02*
X102106Y549167D01*
G01Y549162D02*
X102105Y549172D01*
G01X102146Y556798D02*
Y556811D01*
G01X102143Y556785D02*
X102146Y556798D01*
G01X102143Y556772D02*
Y556785D01*
G01X102146Y553649D02*
Y553661D01*
G01X102143Y553636D02*
X102146Y553649D01*
G01X102143Y553622D02*
Y553636D01*
G01X102146Y550499D02*
Y550512D01*
G01X102143Y550486D02*
X102146Y550499D01*
G01X102143Y550472D02*
Y550486D01*
G01X102146Y547350D02*
Y547362D01*
G01X102143Y547337D02*
X102146Y547350D01*
G01X102143Y547323D02*
Y547337D01*
G01X102146Y544200D02*
Y544213D01*
G01X102143Y544187D02*
X102146Y544200D01*
G01X102143Y544173D02*
Y544187D01*
G01X102146Y541050D02*
Y541063D01*
G01X102143Y541037D02*
X102146Y541050D01*
G01X102143Y541024D02*
Y541037D01*
G01X102146Y537901D02*
Y537913D01*
G01X102143Y537888D02*
X102146Y537901D01*
G01X102143Y537874D02*
Y537888D01*
G01X115532Y568384D02*
X115533Y568386D01*
G01X115531Y568378D02*
X115532Y568384D01*
G01X115531Y568370D02*
Y568378D01*
G01X115532Y563384D02*
X115533Y563386D01*
G01X115531Y563378D02*
X115532Y563384D01*
G01X115531Y563370D02*
Y563378D01*
G01X115532Y558384D02*
X115533Y558386D01*
G01X115531Y558378D02*
X115532Y558384D01*
G01X115531Y558370D02*
Y558378D01*
G01X115532Y533384D02*
X115533Y533386D01*
G01X115531Y533378D02*
X115532Y533384D01*
G01X115531Y533370D02*
Y533378D01*
G01X115532Y528384D02*
X115533Y528386D01*
G01X115531Y528378D02*
X115532Y528384D01*
G01X115531Y528370D02*
Y528378D01*
G01X115532Y523384D02*
X115533Y523386D01*
G01X115531Y523378D02*
X115532Y523384D01*
G01X115531Y523370D02*
Y523378D01*
G01X115532Y518384D02*
X115533Y518386D01*
G01X115531Y518378D02*
X115532Y518384D01*
G01X115531Y518370D02*
Y518378D01*
G01X115532Y513384D02*
X115533Y513386D01*
G01X115531Y513378D02*
X115532Y513384D01*
G01X115531Y513370D02*
Y513378D01*
G01X115532Y508384D02*
X115533Y508386D01*
G01X115531Y508378D02*
X115532Y508384D01*
G01X115531Y508370D02*
Y508378D01*
G01X115532Y503384D02*
X115533Y503386D01*
G01X115531Y503378D02*
X115532Y503384D01*
G01X115531Y503370D02*
Y503378D01*
G01X102106Y555467D02*
Y555459D01*
G01X102105Y555471D02*
X102106Y555467D01*
G01X102105Y555463D02*
Y555471D01*
G01X102143Y555261D02*
X102142Y555275D01*
G01X102146Y555249D02*
X102143Y555261D01*
G01X102146Y555236D02*
Y555249D01*
G01X102143Y552112D02*
X102142Y552126D01*
G01X102146Y552099D02*
X102143Y552112D01*
G01X102146Y552087D02*
Y552099D01*
G01X102143Y548962D02*
X102142Y548976D01*
G01X102146Y548950D02*
X102143Y548962D01*
G01X102146Y548937D02*
Y548950D01*
G01X102143Y545813D02*
X102142Y545826D01*
G01X102146Y545800D02*
X102143Y545813D01*
G01X102146Y545787D02*
Y545800D01*
G01X102143Y542663D02*
X102142Y542677D01*
G01X102146Y542650D02*
X102143Y542663D01*
G01X102146Y542638D02*
Y542650D01*
G01X102143Y539513D02*
X102142Y539527D01*
G01X102146Y539501D02*
X102143Y539513D01*
G01X102146Y539488D02*
Y539501D01*
G01X102143Y536364D02*
X102142Y536378D01*
G01X102146Y536351D02*
X102143Y536364D01*
G01X102146Y536339D02*
Y536351D01*
G01X103054Y556785D02*
X103055Y556772D01*
G01X103050Y556798D02*
X103054Y556785D01*
G01X103051Y556811D02*
X103050Y556798D01*
G01X103054Y553636D02*
X103055Y553622D01*
G01X103050Y553649D02*
X103054Y553636D01*
G01X103051Y553661D02*
X103050Y553649D01*
G01X103054Y550486D02*
X103055Y550472D01*
G01X103050Y550499D02*
X103054Y550486D01*
G01X103051Y550512D02*
X103050Y550499D01*
G01X103054Y547337D02*
X103055Y547323D01*
G01X103050Y547350D02*
X103054Y547337D01*
G01X103051Y547362D02*
X103050Y547350D01*
G01X103054Y544187D02*
X103055Y544173D01*
G01X103050Y544200D02*
X103054Y544187D01*
G01X103051Y544213D02*
X103050Y544200D01*
G01X103054Y541037D02*
X103055Y541024D01*
G01X103050Y541050D02*
X103054Y541037D01*
G01X103051Y541063D02*
X103050Y541050D01*
G01X103054Y537888D02*
X103055Y537874D01*
G01X103050Y537901D02*
X103054Y537888D01*
G01X103051Y537913D02*
X103050Y537901D01*
G01X102106Y542868D02*
Y542861D01*
G01X102105Y542872D02*
X102106Y542868D01*
G01X102105Y542865D02*
Y542872D01*
G01X102106Y552317D02*
Y552309D01*
G01X102105Y552321D02*
X102106Y552317D01*
G01X102105Y552314D02*
Y552321D01*
G01X103050Y555249D02*
X103051Y555236D01*
G01X103053Y555261D02*
X103050Y555249D01*
G01X103054Y555275D02*
X103053Y555261D01*
G01X103050Y552099D02*
X103051Y552087D01*
G01X103053Y552112D02*
X103050Y552099D01*
G01X103054Y552126D02*
X103053Y552112D01*
G01X103050Y548950D02*
X103051Y548937D01*
G01X103053Y548962D02*
X103050Y548950D01*
G01X103054Y548976D02*
X103053Y548962D01*
G01X103050Y545800D02*
X103051Y545787D01*
G01X103053Y545813D02*
X103050Y545800D01*
G01X103054Y545826D02*
X103053Y545813D01*
G01X103050Y542650D02*
X103051Y542638D01*
G01X103053Y542663D02*
X103050Y542650D01*
G01X103054Y542677D02*
X103053Y542663D01*
G01X103050Y539501D02*
X103051Y539488D01*
G01X103053Y539513D02*
X103050Y539501D01*
G01X103054Y539527D02*
X103053Y539513D01*
G01X103050Y536351D02*
X103051Y536339D01*
G01X103053Y536364D02*
X103050Y536351D01*
G01X103054Y536378D02*
X103053Y536364D01*
G01X102106Y536569D02*
Y536561D01*
G01X102105Y536573D02*
X102106Y536569D01*
G01X102105Y536567D02*
Y536573D01*
G01X116516Y504731D02*
Y504738D01*
G01X116517Y504726D02*
X116516Y504731D01*
G01X116518Y504724D02*
X116517Y504726D01*
G01X116516Y509731D02*
Y509738D01*
G01X116517Y509726D02*
X116516Y509731D01*
G01X116518Y509724D02*
X116517Y509726D01*
G01X116516Y514731D02*
Y514738D01*
G01X116517Y514726D02*
X116516Y514731D01*
G01X116518Y514724D02*
X116517Y514726D01*
G01X116516Y519731D02*
Y519738D01*
G01X116517Y519726D02*
X116516Y519731D01*
G01X116518Y519724D02*
X116517Y519726D01*
G01X116516Y524731D02*
Y524738D01*
G01X116517Y524726D02*
X116516Y524731D01*
G01X116518Y524724D02*
X116517Y524726D01*
G01X116516Y529731D02*
Y529738D01*
G01X116517Y529726D02*
X116516Y529731D01*
G01X116518Y529724D02*
X116517Y529726D01*
G01X116516Y534731D02*
Y534738D01*
G01X116517Y534726D02*
X116516Y534731D01*
G01X116518Y534724D02*
X116517Y534726D01*
G01X102129Y539687D02*
X102143Y539685D01*
G01X102118Y539694D02*
X102129Y539687D01*
G01X102106Y539713D02*
X102118Y539694D01*
G01X102129Y549136D02*
X102143Y549134D01*
G01X102117Y549144D02*
X102129Y549136D01*
G01X102106Y549162D02*
X102117Y549144D01*
G01X102129Y542837D02*
X102143Y542835D01*
G01X102117Y542845D02*
X102129Y542837D01*
G01X102105Y542865D02*
X102117Y542845D01*
G01X102129Y552286D02*
X102143Y552283D01*
G01X102117Y552294D02*
X102129Y552286D01*
G01X102105Y552314D02*
X102117Y552294D01*
G01X103091Y536569D02*
Y536561D01*
G01X103090Y536573D02*
X103091Y536569D01*
G01X103089Y536575D02*
X103090Y536573D01*
G01X103091Y539719D02*
Y539711D01*
G01X103090Y539723D02*
X103091Y539719D01*
G01X103089Y539724D02*
X103090Y539723D01*
G01X103091Y542868D02*
Y542860D01*
G01X103090Y542872D02*
X103091Y542868D01*
G01X103089Y542874D02*
X103090Y542872D01*
G01X103091Y546018D02*
Y546010D01*
G01X103090Y546022D02*
X103091Y546018D01*
G01X103089Y546024D02*
X103090Y546022D01*
G01X103091Y549167D02*
Y549159D01*
G01X103090Y549172D02*
X103091Y549167D01*
G01X103089Y549173D02*
X103090Y549172D01*
G01X103091Y552317D02*
Y552309D01*
G01X103090Y552321D02*
X103091Y552317D01*
G01X103089Y552323D02*
X103090Y552321D01*
G01X103091Y555467D02*
Y555459D01*
G01X103090Y555471D02*
X103091Y555467D01*
G01X103089Y555472D02*
X103090Y555471D01*
G01X102129Y555436D02*
X102143Y555433D01*
G01X102116Y555444D02*
X102129Y555436D01*
G01X102105Y555464D02*
X102116Y555444D01*
G01X102128Y536538D02*
X102143Y536535D01*
G01X102115Y536547D02*
X102128Y536538D01*
G01X102105Y536567D02*
X102115Y536547D01*
G01X103090Y537697D02*
X103091Y537691D01*
G01X103088Y537704D02*
X103090Y537697D01*
G01X103085Y537709D02*
X103088Y537704D01*
G01X103090Y540847D02*
X103091Y540840D01*
G01X103088Y540853D02*
X103090Y540847D01*
G01X103085Y540859D02*
X103088Y540853D01*
G01X103090Y543996D02*
X103091Y543990D01*
G01X103088Y544003D02*
X103090Y543996D01*
G01X103085Y544009D02*
X103088Y544003D01*
G01X103090Y547146D02*
X103091Y547139D01*
G01X103088Y547152D02*
X103090Y547146D01*
G01X103085Y547158D02*
X103088Y547152D01*
G01X103090Y550296D02*
X103091Y550289D01*
G01X103088Y550302D02*
X103090Y550296D01*
G01X103085Y550308D02*
X103088Y550302D01*
G01X103090Y553445D02*
X103091Y553439D01*
G01X103088Y553452D02*
X103090Y553445D01*
G01X103085Y553457D02*
X103088Y553452D01*
G01X103090Y556595D02*
X103091Y556588D01*
G01X103088Y556601D02*
X103090Y556595D01*
G01X103085Y556607D02*
X103088Y556601D01*
G01X103052Y536530D02*
Y536524D01*
G01X103050Y536534D02*
X103052Y536530D01*
G01X103050Y536535D02*
Y536534D01*
G01X103052Y539680D02*
Y539674D01*
G01X103050Y539683D02*
X103052Y539680D01*
G01X103050Y539685D02*
Y539683D01*
G01X103052Y542830D02*
Y542823D01*
G01X103050Y542833D02*
X103052Y542830D01*
G01X103050Y542835D02*
Y542833D01*
G01X103052Y545979D02*
Y545973D01*
G01X103050Y545983D02*
X103052Y545979D01*
G01X103050Y545984D02*
Y545983D01*
G01X103052Y549129D02*
Y549122D01*
G01X103050Y549132D02*
X103052Y549129D01*
G01X103050Y549134D02*
Y549132D01*
G01X103052Y555428D02*
Y555422D01*
G01X103050Y555431D02*
X103052Y555428D01*
G01X103050Y555433D02*
Y555431D01*
G01X115531Y504771D02*
Y504780D01*
G01X115532Y504765D02*
X115531Y504771D01*
G01X115533Y504764D02*
X115532Y504765D01*
G01X115531Y509771D02*
Y509780D01*
G01X115532Y509765D02*
X115531Y509771D01*
G01X115533Y509764D02*
X115532Y509765D01*
G01X115531Y514771D02*
Y514780D01*
G01X115532Y514765D02*
X115531Y514771D01*
G01X115533Y514764D02*
X115532Y514765D01*
G01X115531Y519771D02*
Y519780D01*
G01X115532Y519765D02*
X115531Y519771D01*
G01X115533Y519764D02*
X115532Y519765D01*
G01X115531Y524771D02*
Y524780D01*
G01X115532Y524765D02*
X115531Y524771D01*
G01X115533Y524764D02*
X115532Y524765D01*
G01X115531Y529771D02*
Y529780D01*
G01X115532Y529765D02*
X115531Y529771D01*
G01X115533Y529764D02*
X115532Y529765D01*
G01X115531Y534771D02*
Y534780D01*
G01X115532Y534765D02*
X115531Y534771D01*
G01X115533Y534764D02*
X115532Y534765D01*
G01X115531Y559771D02*
Y559780D01*
G01X115532Y559765D02*
X115531Y559771D01*
G01X115533Y559764D02*
X115532Y559765D01*
G01X115531Y564771D02*
Y564780D01*
G01X115532Y564765D02*
X115531Y564771D01*
G01X115533Y564764D02*
X115532Y564765D01*
G01X115531Y569771D02*
Y569780D01*
G01X115532Y569765D02*
X115531Y569771D01*
G01X115533Y569764D02*
X115532Y569765D01*
G01X116508Y504907D02*
X116516Y504881D01*
G01X116498Y504934D02*
X116508Y504907D01*
G01X116487Y504961D02*
X116498Y504934D01*
G01X116508Y509907D02*
X116516Y509881D01*
G01X116498Y509934D02*
X116508Y509907D01*
G01X116487Y509961D02*
X116498Y509934D01*
G01X116508Y514907D02*
X116516Y514881D01*
G01X116498Y514934D02*
X116508Y514907D01*
G01X116487Y514961D02*
X116498Y514934D01*
G01X116508Y519907D02*
X116516Y519881D01*
G01X116498Y519934D02*
X116508Y519907D01*
G01X116487Y519961D02*
X116498Y519934D01*
G01X116508Y524907D02*
X116516Y524881D01*
G01X116498Y524934D02*
X116508Y524907D01*
G01X116487Y524961D02*
X116498Y524934D01*
G01X116508Y529907D02*
X116516Y529881D01*
G01X116498Y529934D02*
X116508Y529907D01*
G01X116487Y529961D02*
X116498Y529934D01*
G01X116508Y534907D02*
X116516Y534881D01*
G01X116498Y534934D02*
X116508Y534907D01*
G01X116487Y534961D02*
X116498Y534934D01*
G01X116508Y559907D02*
X116516Y559881D01*
G01X116498Y559934D02*
X116508Y559907D01*
G01X116487Y559961D02*
X116498Y559934D01*
G01X116508Y564907D02*
X116516Y564881D01*
G01X116498Y564934D02*
X116508Y564907D01*
G01X116487Y564961D02*
X116498Y564934D01*
G01X116508Y569907D02*
X116516Y569881D01*
G01X116498Y569934D02*
X116508Y569907D01*
G01X116487Y569961D02*
X116498Y569934D01*
G01X102124Y545989D02*
X102143Y545984D01*
G01X102111Y546002D02*
X102124Y545989D01*
G01X102104Y546019D02*
X102111Y546002D01*
G01X116498Y504759D02*
X116479Y504764D01*
G01X116513Y504744D02*
X116498Y504759D01*
G01X116518Y504724D02*
X116513Y504744D01*
G01X116498Y509759D02*
X116479Y509764D01*
G01X116513Y509744D02*
X116498Y509759D01*
G01X116518Y509724D02*
X116513Y509744D01*
G01X116498Y514759D02*
X116479Y514764D01*
G01X116513Y514744D02*
X116498Y514759D01*
G01X116518Y514724D02*
X116513Y514744D01*
G01X116498Y519759D02*
X116479Y519764D01*
G01X116513Y519744D02*
X116498Y519759D01*
G01X116518Y519724D02*
X116513Y519744D01*
G01X116498Y524759D02*
X116479Y524764D01*
G01X116513Y524744D02*
X116498Y524759D01*
G01X116518Y524724D02*
X116513Y524744D01*
G01X116498Y529759D02*
X116479Y529764D01*
G01X116513Y529744D02*
X116498Y529759D01*
G01X116518Y529724D02*
X116513Y529744D01*
G01X116498Y534759D02*
X116479Y534764D01*
G01X116513Y534744D02*
X116498Y534759D01*
G01X116518Y534724D02*
X116513Y534744D01*
G01X116498Y559759D02*
X116479Y559764D01*
G01X116513Y559744D02*
X116498Y559759D01*
G01X116518Y559724D02*
X116513Y559744D01*
G01X116498Y564759D02*
X116479Y564764D01*
G01X116513Y564744D02*
X116498Y564759D01*
G01X116518Y564724D02*
X116513Y564744D01*
G01X116498Y569759D02*
X116479Y569764D01*
G01X116513Y569744D02*
X116498Y569759D01*
G01X116518Y569724D02*
X116513Y569744D01*
G01X103083Y543998D02*
X103076Y544006D01*
G01X103088Y543987D02*
X103083Y543998D01*
G01X103089Y543976D02*
X103088Y543987D01*
G01X103083Y537698D02*
X103076Y537707D01*
G01X103088Y537688D02*
X103083Y537698D01*
G01X103089Y537677D02*
X103088Y537688D01*
G01X103083Y540848D02*
X103076Y540856D01*
G01X103088Y540838D02*
X103083Y540848D01*
G01X103089Y540827D02*
X103088Y540838D01*
G01X103083Y547147D02*
X103076Y547156D01*
G01X103088Y547137D02*
X103083Y547147D01*
G01X103089Y547126D02*
X103088Y547137D01*
G01X103083Y550297D02*
X103076Y550305D01*
G01X103088Y550287D02*
X103083Y550297D01*
G01X103089Y550276D02*
X103088Y550287D01*
G01X103083Y553446D02*
X103076Y553455D01*
G01X103088Y553436D02*
X103083Y553446D01*
G01X103089Y553425D02*
X103088Y553436D01*
G01X103083Y556596D02*
X103076Y556604D01*
G01X103088Y556586D02*
X103083Y556596D01*
G01X103089Y556575D02*
X103088Y556586D01*
G01X102119Y556606D02*
X102143Y556614D01*
G01X102108Y556591D02*
X102119Y556606D01*
G01X102106Y556584D02*
X102108Y556591D01*
G01X102119Y553456D02*
X102143Y553465D01*
G01X102108Y553441D02*
X102119Y553456D01*
G01X102106Y553435D02*
X102108Y553441D01*
G01X102119Y550306D02*
X102143Y550315D01*
G01X102108Y550292D02*
X102119Y550306D01*
G01X102106Y550285D02*
X102108Y550292D01*
G01X102119Y547157D02*
X102143Y547165D01*
G01X102108Y547142D02*
X102119Y547157D01*
G01X102106Y547135D02*
X102108Y547142D01*
G01X102119Y544007D02*
X102143Y544016D01*
G01X102108Y543993D02*
X102119Y544007D01*
G01X102106Y543986D02*
X102108Y543993D01*
G01X102119Y540857D02*
X102143Y540866D01*
G01X102108Y540843D02*
X102119Y540857D01*
G01X102106Y540836D02*
X102108Y540843D01*
G01X102119Y537708D02*
X102143Y537717D01*
G01X102108Y537693D02*
X102119Y537708D01*
G01X102106Y537687D02*
X102108Y537693D01*
G01X102145Y536530D02*
X102146Y536524D01*
G01X102144Y536534D02*
X102145Y536530D01*
G01X102143Y536535D02*
X102144Y536534D01*
G01X102145Y539680D02*
X102146Y539674D01*
G01X102144Y539684D02*
X102145Y539680D01*
G01X102143Y539685D02*
X102144Y539684D01*
G01X102145Y542830D02*
X102146Y542823D01*
G01X102144Y542833D02*
X102145Y542830D01*
G01X102143Y542835D02*
X102144Y542833D01*
G01X102145Y545979D02*
X102146Y545973D01*
G01X102144Y545983D02*
X102145Y545979D01*
G01X102143Y545984D02*
X102144Y545983D01*
G01X102145Y549129D02*
X102146Y549122D01*
G01X102144Y549133D02*
X102145Y549129D01*
G01X102143Y549134D02*
X102144Y549133D01*
G01X102145Y552278D02*
X102146Y552272D01*
G01X102144Y552282D02*
X102145Y552278D01*
G01X102143Y552283D02*
X102144Y552282D01*
G01X116516Y559731D02*
Y559738D01*
G01X116517Y559726D02*
X116516Y559731D01*
G01X116518Y559724D02*
X116517Y559726D01*
G01X116516Y564731D02*
Y564738D01*
G01X116517Y564726D02*
X116516Y564731D01*
G01X116518Y564724D02*
X116517Y564726D01*
G01X116516Y569731D02*
Y569738D01*
G01X116517Y569726D02*
X116516Y569731D01*
G01X116518Y569724D02*
X116517Y569726D01*
G01X103091Y556581D02*
Y556588D01*
G01X103090Y556576D02*
X103091Y556581D01*
G01X103089Y556575D02*
X103090Y556576D01*
G01X103091Y553431D02*
Y553439D01*
G01X103090Y553427D02*
X103091Y553431D01*
G01X103089Y553425D02*
X103090Y553427D01*
G01X103091Y550282D02*
Y550289D01*
G01X103090Y550277D02*
X103091Y550282D01*
G01X103089Y550276D02*
X103090Y550277D01*
G01X103091Y547132D02*
Y547139D01*
G01X103090Y547128D02*
X103091Y547132D01*
G01X103089Y547126D02*
X103090Y547128D01*
G01X103091Y543983D02*
Y543990D01*
G01X103090Y543978D02*
X103091Y543983D01*
G01X103089Y543976D02*
X103090Y543978D01*
G01X103091Y540833D02*
Y540840D01*
G01X103090Y540828D02*
X103091Y540833D01*
G01X103089Y540827D02*
X103090Y540828D01*
G01X103091Y537683D02*
Y537691D01*
G01X103090Y537679D02*
X103091Y537683D01*
G01X103089Y537677D02*
X103090Y537679D01*
G01X102106Y546018D02*
Y546010D01*
G01X102105Y546022D02*
X102106Y546018D01*
G01X102104Y546019D02*
X102105Y546022D01*
G01X103059Y544015D02*
X103050Y544016D01*
G01X103068Y544011D02*
X103059Y544015D01*
G01X103076Y544006D02*
X103068Y544011D01*
G01X103059Y537715D02*
X103050Y537717D01*
G01X103068Y537712D02*
X103059Y537715D01*
G01X103076Y537707D02*
X103068Y537712D01*
G01X103059Y540865D02*
X103050Y540866D01*
G01X103068Y540862D02*
X103059Y540865D01*
G01X103076Y540856D02*
X103068Y540862D01*
G01X103059Y547164D02*
X103050Y547165D01*
G01X103068Y547161D02*
X103059Y547164D01*
G01X103076Y547156D02*
X103068Y547161D01*
G01X103059Y550314D02*
X103050Y550315D01*
G01X103068Y550311D02*
X103059Y550314D01*
G01X103076Y550305D02*
X103068Y550311D01*
G01X103059Y553463D02*
X103050Y553465D01*
G01X103068Y553460D02*
X103059Y553463D01*
G01X103076Y553455D02*
X103068Y553460D01*
G01X103059Y556613D02*
X103050Y556614D01*
G01X103068Y556610D02*
X103059Y556613D01*
G01X103076Y556604D02*
X103068Y556610D01*
G01X102145Y555428D02*
X102146Y555422D01*
G01X102144Y555432D02*
X102145Y555428D01*
G01X102143Y555433D02*
X102144Y555432D01*
G01X102106Y539719D02*
Y539711D01*
G01X102105Y539723D02*
X102106Y539719D01*
G01X102104Y539721D02*
X102105Y539723D01*
G01X103051Y556619D02*
Y556625D01*
G01X103050Y556615D02*
X103051Y556619D01*
G01X103050Y556614D02*
Y556615D01*
G01X103051Y553470D02*
Y553476D01*
G01X103050Y553466D02*
X103051Y553470D01*
G01X103050Y553465D02*
Y553466D01*
G01X103051Y550320D02*
Y550326D01*
G01X103050Y550316D02*
X103051Y550320D01*
G01X103050Y550315D02*
Y550316D01*
G01X103051Y547170D02*
Y547176D01*
G01X103050Y547167D02*
X103051Y547170D01*
G01X103050Y547165D02*
Y547167D01*
G01X103051Y544021D02*
Y544027D01*
G01X103050Y544017D02*
X103051Y544021D01*
G01X103050Y544016D02*
Y544017D01*
G01X103051Y540871D02*
Y540877D01*
G01X103050Y540867D02*
X103051Y540871D01*
G01X103050Y540866D02*
Y540867D01*
G01X103051Y537722D02*
Y537728D01*
G01X103050Y537718D02*
X103051Y537722D01*
G01X103050Y537717D02*
Y537718D01*
G01X116516Y568378D02*
Y568369D01*
G01X116517Y568384D02*
X116516Y568378D01*
G01X116519Y568386D02*
X116517Y568384D01*
G01X116516Y563378D02*
Y563369D01*
G01X116517Y563384D02*
X116516Y563378D01*
G01X116519Y563386D02*
X116517Y563384D01*
G01X116516Y558378D02*
Y558369D01*
G01X116517Y558384D02*
X116516Y558378D01*
G01X116519Y558386D02*
X116517Y558384D01*
G01X116516Y533378D02*
Y533369D01*
G01X116517Y533384D02*
X116516Y533378D01*
G01X116519Y533386D02*
X116517Y533384D01*
G01X116516Y528378D02*
Y528369D01*
G01X116517Y528384D02*
X116516Y528378D01*
G01X116519Y528386D02*
X116517Y528384D01*
G01X116516Y523378D02*
Y523369D01*
G01X116517Y523384D02*
X116516Y523378D01*
G01X116519Y523386D02*
X116517Y523384D01*
G01X116516Y518378D02*
Y518369D01*
G01X116517Y518384D02*
X116516Y518378D01*
G01X116519Y518386D02*
X116517Y518384D01*
G01X116516Y513378D02*
Y513369D01*
G01X116517Y513384D02*
X116516Y513378D01*
G01X116519Y513386D02*
X116517Y513384D01*
G01X116516Y508378D02*
Y508369D01*
G01X116517Y508384D02*
X116516Y508378D01*
G01X116519Y508386D02*
X116517Y508384D01*
G01X116516Y503378D02*
Y503369D01*
G01X116517Y503384D02*
X116516Y503378D01*
G01X116519Y503386D02*
X116517Y503384D01*
G01X102106Y556581D02*
Y556588D01*
G01X102105Y556576D02*
X102106Y556581D01*
G01X102104Y556575D02*
X102105Y556576D01*
G01X102106Y553431D02*
Y553439D01*
G01X102105Y553427D02*
X102106Y553431D01*
G01X102104Y553425D02*
X102105Y553427D01*
G01X102106Y550281D02*
Y550289D01*
G01X102105Y550277D02*
X102106Y550281D01*
G01X102104Y550276D02*
X102105Y550277D01*
G01X102106Y547132D02*
Y547139D01*
G01X102105Y547128D02*
X102106Y547132D01*
G01X102104Y547126D02*
X102105Y547128D01*
G01X102106Y543982D02*
Y543990D01*
G01X102105Y543978D02*
X102106Y543982D01*
G01X102104Y543976D02*
X102105Y543978D01*
G01X102106Y540833D02*
Y540840D01*
G01X102105Y540828D02*
X102106Y540833D01*
G01X102104Y540827D02*
X102105Y540828D01*
G01X102106Y537683D02*
Y537691D01*
G01X102105Y537679D02*
X102106Y537683D01*
G01X102104Y537677D02*
X102105Y537679D01*
G01X102106Y542864D02*
Y542860D01*
G01X102108Y542858D02*
X102106Y542864D01*
G01X102119Y542843D02*
X102108Y542858D01*
G01X102144Y542835D02*
X102119Y542843D01*
G01X102106Y536565D02*
Y536561D01*
G01X102108Y536559D02*
X102106Y536565D01*
G01X102119Y536544D02*
X102108Y536559D01*
G01X102144Y536535D02*
X102119Y536544D01*
G01X116503Y504755D02*
X116514Y504740D01*
G01X116479Y504764D02*
X116503Y504755D01*
G01Y509755D02*
X116514Y509740D01*
G01X116479Y509764D02*
X116503Y509755D01*
G01Y514755D02*
X116514Y514740D01*
G01X116479Y514764D02*
X116503Y514755D01*
G01Y519755D02*
X116514Y519740D01*
G01X116479Y519764D02*
X116503Y519755D01*
G01Y524755D02*
X116514Y524740D01*
G01X116479Y524764D02*
X116503Y524755D01*
G01Y529755D02*
X116514Y529740D01*
G01X116479Y529764D02*
X116503Y529755D01*
G01Y534755D02*
X116514Y534740D01*
G01X116479Y534764D02*
X116503Y534755D01*
G01X102106Y546014D02*
Y546010D01*
G01X102108Y546008D02*
X102106Y546014D01*
G01X102118Y545994D02*
X102108Y546008D01*
G01X102141Y545984D02*
X102118Y545994D01*
G01X102106Y539715D02*
Y539711D01*
G01X102108Y539708D02*
X102106Y539715D01*
G01X102120Y539693D02*
X102108Y539708D01*
G01X102144Y539685D02*
X102120Y539693D01*
G01X102106Y549163D02*
Y549159D01*
G01X102108Y549157D02*
X102106Y549163D01*
G01X102119Y549142D02*
X102108Y549157D01*
G01X102144Y549134D02*
X102119Y549142D01*
G01X102106Y552313D02*
Y552309D01*
G01X102108Y552307D02*
X102106Y552313D01*
G01X102119Y552292D02*
X102108Y552307D01*
G01X102144Y552283D02*
X102119Y552292D01*
G01X102106Y555463D02*
Y555459D01*
G01X102108Y555457D02*
X102106Y555463D01*
G01X102119Y555441D02*
X102108Y555457D01*
G01X102144Y555433D02*
X102119Y555441D01*
G01X116503Y559755D02*
X116514Y559740D01*
G01X116479Y559764D02*
X116503Y559755D01*
G01Y564755D02*
X116514Y564740D01*
G01X116479Y564764D02*
X116503Y564755D01*
G01Y569755D02*
X116514Y569740D01*
G01X116479Y569764D02*
X116503Y569755D01*
G01X103088Y555446D02*
X103091Y555459D01*
G01X103081Y555435D02*
X103088Y555446D01*
G01X103071Y555427D02*
X103081Y555435D01*
G01X103088Y549147D02*
X103091Y549159D01*
G01X103081Y549136D02*
X103088Y549147D01*
G01X103071Y549128D02*
X103081Y549136D01*
G01X103088Y545998D02*
X103091Y546010D01*
G01X103081Y545986D02*
X103088Y545998D01*
G01X103071Y545978D02*
X103081Y545986D01*
G01X103088Y542848D02*
X103091Y542860D01*
G01X103081Y542837D02*
X103088Y542848D01*
G01X103071Y542829D02*
X103081Y542837D01*
G01X103088Y539698D02*
X103091Y539711D01*
G01X103081Y539687D02*
X103088Y539698D01*
G01X103071Y539679D02*
X103081Y539687D01*
G01X103088Y536549D02*
X103091Y536561D01*
G01X103081Y536537D02*
X103088Y536549D01*
G01X103071Y536530D02*
X103081Y536537D01*
G01X102145Y556619D02*
Y556625D01*
G01Y556615D02*
Y556619D01*
G01X102143Y556614D02*
X102145Y556615D01*
G01Y553469D02*
Y553476D01*
G01Y553466D02*
Y553469D01*
G01X102143Y553465D02*
X102145Y553466D01*
G01Y550320D02*
Y550326D01*
G01Y550316D02*
Y550320D01*
G01X102143Y550315D02*
X102145Y550316D01*
G01Y547170D02*
Y547176D01*
G01Y547167D02*
Y547170D01*
G01X102143Y547165D02*
X102145Y547167D01*
G01Y544020D02*
Y544027D01*
G01Y544017D02*
Y544020D01*
G01X102143Y544016D02*
X102145Y544017D01*
G01Y540871D02*
Y540877D01*
G01Y540867D02*
Y540871D01*
G01X102143Y540866D02*
X102145Y540867D01*
G01X103060Y537715D02*
X103070Y537711D01*
G01X103050Y537717D02*
X103060Y537715D01*
G01Y540865D02*
X103070Y540861D01*
G01X103050Y540866D02*
X103060Y540865D01*
G01Y544014D02*
X103070Y544010D01*
G01X103050Y544016D02*
X103060Y544014D01*
G01Y547164D02*
X103070Y547160D01*
G01X103050Y547165D02*
X103060Y547164D01*
G01Y550313D02*
X103070Y550309D01*
G01X103050Y550315D02*
X103060Y550313D01*
G01Y553463D02*
X103070Y553459D01*
G01X103050Y553465D02*
X103060Y553463D01*
G01Y556613D02*
X103070Y556609D01*
G01X103050Y556614D02*
X103060Y556613D01*
G01X102145Y537721D02*
Y537728D01*
G01Y537718D02*
Y537721D01*
G01X102143Y537717D02*
X102145Y537718D01*
G01X102107Y556594D02*
X102106Y556588D01*
G01X102109Y556601D02*
X102107Y556594D01*
G01X102111Y556607D02*
X102109Y556601D01*
G01X102115Y556612D02*
X102111Y556607D01*
G01X102120Y556617D02*
X102115Y556612D01*
G01X102126Y556620D02*
X102120Y556617D01*
G01X102107Y553445D02*
X102106Y553439D01*
G01X102109Y553451D02*
X102107Y553445D01*
G01X102111Y553457D02*
X102109Y553451D01*
G01X102115Y553462D02*
X102111Y553457D01*
G01X102120Y553467D02*
X102115Y553462D01*
G01X102126Y553470D02*
X102120Y553467D01*
G01X102107Y550295D02*
X102106Y550289D01*
G01X102109Y550302D02*
X102107Y550295D01*
G01X102111Y550307D02*
X102109Y550302D01*
G01X102115Y550313D02*
X102111Y550307D01*
G01X102120Y550317D02*
X102115Y550313D01*
G01X102126Y550321D02*
X102120Y550317D01*
G01X102107Y547146D02*
X102106Y547139D01*
G01X102109Y547152D02*
X102107Y547146D01*
G01X102111Y547158D02*
X102109Y547152D01*
G01X102115Y547163D02*
X102111Y547158D01*
G01X102120Y547168D02*
X102115Y547163D01*
G01X102126Y547171D02*
X102120Y547168D01*
G01X102107Y543996D02*
X102106Y543990D01*
G01X102109Y544002D02*
X102107Y543996D01*
G01X102111Y544008D02*
X102109Y544002D01*
G01X102115Y544013D02*
X102111Y544008D01*
G01X102120Y544018D02*
X102115Y544013D01*
G01X102126Y544022D02*
X102120Y544018D01*
G01X102107Y540846D02*
X102106Y540840D01*
G01X102109Y540853D02*
X102107Y540846D01*
G01X102111Y540859D02*
X102109Y540853D01*
G01X102115Y540864D02*
X102111Y540859D01*
G01X102120Y540869D02*
X102115Y540864D01*
G01X102126Y540872D02*
X102120Y540869D01*
G01X102107Y537697D02*
X102106Y537691D01*
G01X102109Y537703D02*
X102107Y537697D01*
G01X102111Y537709D02*
X102109Y537703D01*
G01X102115Y537714D02*
X102111Y537709D01*
G01X102120Y537719D02*
X102115Y537714D01*
G01X102126Y537722D02*
X102120Y537719D01*
G01X103081Y537715D02*
X103085Y537709D01*
G01X103076Y537719D02*
X103081Y537715D01*
G01X103070Y537723D02*
X103076Y537719D01*
G01X103065Y537726D02*
X103070Y537723D01*
G01X103058Y537727D02*
X103065Y537726D01*
G01X103051Y537728D02*
X103058Y537727D01*
G01X103081Y540865D02*
X103085Y540859D01*
G01X103076Y540869D02*
X103081Y540865D01*
G01X103070Y540872D02*
X103076Y540869D01*
G01X103065Y540875D02*
X103070Y540872D01*
G01X103058Y540877D02*
X103065Y540875D01*
G01X103051Y540877D02*
X103058D01*
G01X103081Y544014D02*
X103085Y544009D01*
G01X103076Y544019D02*
X103081Y544014D01*
G01X103070Y544022D02*
X103076Y544019D01*
G01X103065Y544025D02*
X103070Y544022D01*
G01X103058Y544026D02*
X103065Y544025D01*
G01X103051Y544027D02*
X103058Y544026D01*
G01X103081Y547164D02*
X103085Y547158D01*
G01X103076Y547168D02*
X103081Y547164D01*
G01X103070Y547172D02*
X103076Y547168D01*
G01X103065Y547174D02*
X103070Y547172D01*
G01X103058Y547176D02*
X103065Y547174D01*
G01X103051Y547176D02*
X103058D01*
G01X103081Y550313D02*
X103085Y550308D01*
G01X103076Y550318D02*
X103081Y550313D01*
G01X103070Y550321D02*
X103076Y550318D01*
G01X103065Y550324D02*
X103070Y550321D01*
G01X103058Y550326D02*
X103065Y550324D01*
G01X103051Y550326D02*
X103058D01*
G01X103081Y553463D02*
X103085Y553457D01*
G01X103076Y553467D02*
X103081Y553463D01*
G01X103070Y553471D02*
X103076Y553467D01*
G01X103065Y553474D02*
X103070Y553471D01*
G01X103058Y553475D02*
X103065Y553474D01*
G01X103051Y553476D02*
X103058Y553475D01*
G01X103081Y556613D02*
X103085Y556607D01*
G01X103076Y556617D02*
X103081Y556613D01*
G01X103070Y556620D02*
X103076Y556617D01*
G01X103065Y556623D02*
X103070Y556620D01*
G01X103058Y556625D02*
X103065Y556623D01*
G01X103051Y556625D02*
X103058D01*
G01X102107Y536554D02*
X102106Y536561D01*
G01X102109Y536547D02*
X102107Y536554D01*
G01X102113Y536541D02*
X102109Y536547D01*
G01X102118Y536535D02*
X102113Y536541D01*
G01X102124Y536530D02*
X102118Y536535D01*
G01X102131Y536527D02*
X102124Y536530D01*
G01X102138Y536525D02*
X102131Y536527D01*
G01X102146Y536524D02*
X102138Y536525D01*
G01X102107Y539704D02*
X102106Y539711D01*
G01X102109Y539696D02*
X102107Y539704D01*
G01X102113Y539690D02*
X102109Y539696D01*
G01X102118Y539685D02*
X102113Y539690D01*
G01X102124Y539680D02*
X102118Y539685D01*
G01X102131Y539676D02*
X102124Y539680D01*
G01X102138Y539674D02*
X102131Y539676D01*
G01X102146Y539674D02*
X102138D01*
G01X102107Y542853D02*
X102106Y542860D01*
G01X102109Y542846D02*
X102107Y542853D01*
G01X102113Y542840D02*
X102109Y542846D01*
G01X102118Y542834D02*
X102113Y542840D01*
G01X102124Y542830D02*
X102118Y542834D01*
G01X102131Y542826D02*
X102124Y542830D01*
G01X102138Y542824D02*
X102131Y542826D01*
G01X102146Y542823D02*
X102138Y542824D01*
G01X102107Y546003D02*
X102106Y546010D01*
G01X102109Y545996D02*
X102107Y546003D01*
G01X102113Y545989D02*
X102109Y545996D01*
G01X102118Y545984D02*
X102113Y545989D01*
G01X102124Y545979D02*
X102118Y545984D01*
G01X102131Y545976D02*
X102124Y545979D01*
G01X102138Y545974D02*
X102131Y545976D01*
G01X102146Y545973D02*
X102138Y545974D01*
G01X102107Y549152D02*
X102106Y549159D01*
G01X102109Y549145D02*
X102107Y549152D01*
G01X102113Y549139D02*
X102109Y549145D01*
G01X102118Y549133D02*
X102113Y549139D01*
G01X102124Y549129D02*
X102118Y549133D01*
G01X102131Y549125D02*
X102124Y549129D01*
G01X102138Y549123D02*
X102131Y549125D01*
G01X102146Y549122D02*
X102138Y549123D01*
G01X102107Y552302D02*
X102106Y552309D01*
G01X102109Y552295D02*
X102107Y552302D01*
G01X102113Y552289D02*
X102109Y552295D01*
G01X102118Y552283D02*
X102113Y552289D01*
G01X102124Y552278D02*
X102118Y552283D01*
G01X102131Y552275D02*
X102124Y552278D01*
G01X102138Y552273D02*
X102131Y552275D01*
G01X102146Y552272D02*
X102138Y552273D01*
G01X102107Y555452D02*
X102106Y555459D01*
G01X102109Y555444D02*
X102107Y555452D01*
G01X102113Y555438D02*
X102109Y555444D01*
G01X102118Y555433D02*
X102113Y555438D01*
G01X102124Y555428D02*
X102118Y555433D01*
G01X102131Y555424D02*
X102124Y555428D01*
G01X102138Y555422D02*
X102131Y555424D01*
G01X102146Y555422D02*
X102138D01*
G01X103062Y555435D02*
X103050Y555433D01*
G01X103072Y555440D02*
X103062Y555435D01*
G01Y552285D02*
X103050Y552283D01*
G01X103072Y552290D02*
X103062Y552285D01*
G01Y549136D02*
X103050Y549134D01*
G01X103072Y549141D02*
X103062Y549136D01*
G01Y545986D02*
X103050Y545984D01*
G01X103072Y545991D02*
X103062Y545986D01*
G01Y542837D02*
X103050Y542835D01*
G01X103072Y542841D02*
X103062Y542837D01*
G01Y539687D02*
X103050Y539685D01*
G01X103072Y539692D02*
X103062Y539687D01*
G01Y536537D02*
X103050Y536535D01*
G01X103072Y536542D02*
X103062Y536537D01*
G01X103068Y536528D02*
X103071Y536530D01*
G01X103065Y536526D02*
X103068Y536528D01*
G01X103062Y536526D02*
X103065D01*
G01X103058Y536525D02*
X103062Y536526D01*
G01X103055Y536524D02*
X103058Y536525D01*
G01X103051Y536524D02*
X103055D01*
G01X102129Y537724D02*
X102126Y537722D01*
G01X102132Y537725D02*
X102129Y537724D01*
G01X102135Y537726D02*
X102132Y537725D01*
G01X102139Y537727D02*
X102135Y537726D01*
G01X102142Y537728D02*
X102139Y537727D01*
G01X102146Y537728D02*
X102142D01*
G01X103068Y539677D02*
X103071Y539679D01*
G01X103065Y539676D02*
X103068Y539677D01*
G01X103062Y539675D02*
X103065Y539676D01*
G01X103058Y539674D02*
X103062Y539675D01*
G01X103055Y539674D02*
X103058D01*
G01X103051D02*
X103055D01*
G01X102129Y540874D02*
X102126Y540872D01*
G01X102132Y540875D02*
X102129Y540874D01*
G01X102135Y540876D02*
X102132Y540875D01*
G01X102139Y540877D02*
X102135Y540876D01*
G01X102142Y540877D02*
X102139D01*
G01X102146D02*
X102142D01*
G01X103068Y542827D02*
X103071Y542829D01*
G01X103065Y542826D02*
X103068Y542827D01*
G01X103062Y542825D02*
X103065Y542826D01*
G01X103058Y542824D02*
X103062Y542825D01*
G01X103055Y542824D02*
X103058D01*
G01X103051Y542823D02*
X103055Y542824D01*
G01X102129Y544023D02*
X102126Y544022D01*
G01X102132Y544024D02*
X102129Y544023D01*
G01X102135Y544026D02*
X102132Y544024D01*
G01X102139Y544026D02*
X102135D01*
G01X102142Y544027D02*
X102139Y544026D01*
G01X102146Y544027D02*
X102142D01*
G01X103068Y545976D02*
X103071Y545978D01*
G01X103065Y545975D02*
X103068Y545976D01*
G01X103062Y545974D02*
X103065Y545975D01*
G01X103058Y545974D02*
X103062D01*
G01X103055Y545973D02*
X103058Y545974D01*
G01X103051Y545973D02*
X103055D01*
G01X102129Y547173D02*
X102126Y547171D01*
G01X102132Y547174D02*
X102129Y547173D01*
G01X102135Y547175D02*
X102132Y547174D01*
G01X102139Y547176D02*
X102135Y547175D01*
G01X102142Y547176D02*
X102139D01*
G01X102146D02*
X102142D01*
G01X103068Y549126D02*
X103071Y549128D01*
G01X103065Y549125D02*
X103068Y549126D01*
G01X103062Y549124D02*
X103065Y549125D01*
G01X103058Y549123D02*
X103062Y549124D01*
G01X103055Y549123D02*
X103058D01*
G01X103051Y549122D02*
X103055Y549123D01*
G01X102129Y550322D02*
X102126Y550321D01*
G01X102132Y550324D02*
X102129Y550322D01*
G01X102135Y550325D02*
X102132Y550324D01*
G01X102139Y550326D02*
X102135Y550325D01*
G01X102142Y550326D02*
X102139D01*
G01X102146D02*
X102142D01*
G01X102129Y553472D02*
X102126Y553470D01*
G01X102132Y553473D02*
X102129Y553472D01*
G01X102135Y553474D02*
X102132Y553473D01*
G01X102139Y553475D02*
X102135Y553474D01*
G01X102142Y553476D02*
X102139Y553475D01*
G01X102146Y553476D02*
X102142D01*
G01X103068Y555425D02*
X103071Y555427D01*
G01X103065Y555424D02*
X103068Y555425D01*
G01X103062Y555423D02*
X103065Y555424D01*
G01X103058Y555422D02*
X103062Y555423D01*
G01X103055Y555422D02*
X103058D01*
G01X103051D02*
X103055D01*
G01X102129Y556622D02*
X102126Y556620D01*
G01X102132Y556623D02*
X102129Y556622D01*
G01X102135Y556624D02*
X102132Y556623D01*
G01X102139Y556625D02*
X102135Y556624D01*
G01X102142Y556625D02*
X102139D01*
G01X102146D02*
X102142D01*
G01X101359Y539724D02*
X100925D01*
G01X101733D02*
X101359D01*
G01Y546024D02*
X100925D01*
G01X101733D02*
X101359D01*
G01Y549173D02*
X100925D01*
G01X101733D02*
X101359D01*
G01X103090Y552302D02*
X103091Y552309D01*
G01X103087Y552295D02*
X103090Y552302D01*
G01X103084Y552289D02*
X103087Y552295D01*
G01X103079Y552283D02*
X103084Y552289D01*
G01X103073Y552278D02*
X103079Y552283D01*
G01X103066Y552275D02*
X103073Y552278D01*
G01X103059Y552273D02*
X103066Y552275D01*
G01X103051Y552272D02*
X103059Y552273D01*
G01X102109Y537697D02*
X102104Y537677D01*
G01X102124Y537711D02*
X102109Y537697D01*
G01X102143Y537717D02*
X102124Y537711D01*
G01X102109Y540846D02*
X102104Y540827D01*
G01X102124Y540861D02*
X102109Y540846D01*
G01X102143Y540866D02*
X102124Y540861D01*
G01X103084Y536555D02*
X103089Y536575D01*
G01X103069Y536541D02*
X103084Y536555D01*
G01X103050Y536535D02*
X103069Y536541D01*
G01X103084Y539705D02*
X103089Y539724D01*
G01X103069Y539690D02*
X103084Y539705D01*
G01X103050Y539685D02*
X103069Y539690D01*
G01X103084Y542854D02*
X103089Y542874D01*
G01X103069Y542840D02*
X103084Y542854D01*
G01X103050Y542835D02*
X103069Y542840D01*
G01X102109Y543996D02*
X102104Y543976D01*
G01X102124Y544010D02*
X102109Y543996D01*
G01X102143Y544016D02*
X102124Y544010D01*
G01X102109Y547146D02*
X102104Y547126D01*
G01X102124Y547160D02*
X102109Y547146D01*
G01X102143Y547165D02*
X102124Y547160D01*
G01X102109Y550295D02*
X102104Y550276D01*
G01X102124Y550309D02*
X102109Y550295D01*
G01X102143Y550315D02*
X102124Y550309D01*
G01X102109Y553445D02*
X102104Y553425D01*
G01X102124Y553459D02*
X102109Y553445D01*
G01X102143Y553465D02*
X102124Y553459D01*
G01X102109Y556594D02*
X102104Y556575D01*
G01X102124Y556609D02*
X102109Y556594D01*
G01X102143Y556614D02*
X102124Y556609D01*
G01X103084Y546004D02*
X103089Y546024D01*
G01X103069Y545989D02*
X103084Y546004D01*
G01X103050Y545984D02*
X103069Y545989D01*
G01X103084Y549154D02*
X103089Y549173D01*
G01X103069Y549139D02*
X103084Y549154D01*
G01X103050Y549134D02*
X103069Y549139D01*
G01X103084Y552303D02*
X103089Y552323D01*
G01X103069Y552289D02*
X103084Y552303D01*
G01X103050Y552283D02*
X103069Y552289D01*
G01X103084Y555453D02*
X103089Y555472D01*
G01X103069Y555438D02*
X103084Y555453D01*
G01X103050Y555433D02*
X103069Y555438D01*
G01X112126Y492264D02*
G03I-1102J0D01*
G01X113583Y486988D02*
G03X114764Y488169I0J1181D01*
G01X107283D02*
G03X108465Y486988I1181J0D01*
G01X112598Y492264D02*
G03I-1574J0D01*
G01X107087Y477894D02*
G03X107677Y477303I590J-1D01*
G01X114370D02*
G03X114961Y477894I0J591D01*
G01X112205Y479075D02*
G03Y481043I0J984D01*
G01X109843D02*
G03Y479075I0J-984D01*
G01X100197Y478484D02*
G03X102165Y476516I1968J0D01*
G01X119882D02*
G03X121850Y478484I0J1968D01*
G01X116516Y570256D02*
X115531D01*
G01X115533Y569764D02*
X120866D01*
G01Y569724D02*
X116518D01*
G01X120866Y568386D02*
X115533D01*
G01X115531Y567894D02*
X116516D01*
G01Y565256D02*
X115531D01*
G01X115533Y564764D02*
X120866D01*
G01Y564724D02*
X116518D01*
G01X120866Y563386D02*
X115533D01*
G01X115531Y562894D02*
X116516D01*
G01Y560256D02*
X115531D01*
G01X115533Y559764D02*
X120866D01*
G01Y559724D02*
X116518D01*
G01X103543Y558780D02*
X100197D01*
G01X120866Y558386D02*
X115533D01*
G01X115531Y557894D02*
X116516D01*
G01X113189Y557618D02*
X117126D01*
G01X103051Y556811D02*
X102146D01*
G01X103091Y556772D02*
X102106D01*
G01X112008Y556437D02*
X115945D01*
G01X102106Y555276D02*
X103091D01*
G01X102146Y555236D02*
X103051D01*
G01Y553661D02*
X102146D01*
G01X103091Y553622D02*
X102106D01*
G01Y552126D02*
X103091D01*
G01X102146Y552087D02*
X103051D01*
G01Y550512D02*
X102146D01*
G01X103091Y550472D02*
X102106D01*
G01Y548976D02*
X103091D01*
G01X102146Y548937D02*
X103051D01*
G01Y547362D02*
X102146D01*
G01X103091Y547323D02*
X102106D01*
G01Y545827D02*
X103091D01*
G01X102146Y545787D02*
X103051D01*
G01Y544213D02*
X102146D01*
G01X103091Y544173D02*
X102106D01*
G01Y542677D02*
X103091D01*
G01X102146Y542638D02*
X103051D01*
G01Y541063D02*
X102146D01*
G01X103091Y541024D02*
X102106D01*
G01Y539528D02*
X103091D01*
G01X102146Y539488D02*
X103051D01*
G01Y537913D02*
X102146D01*
G01X103091Y537874D02*
X102106D01*
G01X115945Y536713D02*
X112008D01*
G01X102106Y536378D02*
X103091D01*
G01X102146Y536339D02*
X103051D01*
G01X117126Y535531D02*
X113189D01*
G01X116516Y535256D02*
X115531D01*
G01X115533Y534764D02*
X120866D01*
G01Y534724D02*
X116518D01*
G01X103543Y534370D02*
X100197D01*
G01X120866Y533386D02*
X115533D01*
G01X115531Y532894D02*
X116516D01*
G01Y530256D02*
X115531D01*
G01X115533Y529764D02*
X120866D01*
G01Y529724D02*
X116518D01*
G01X120866Y528386D02*
X115533D01*
G01X115531Y569959D02*
X116487Y569961D01*
G01X116516Y568190D02*
X115531Y568189D01*
G01Y564959D02*
X116487Y564961D01*
G01X116516Y563190D02*
X115531Y563189D01*
G01Y559959D02*
X116487Y559961D01*
G01X116516Y558190D02*
X115531Y558189D01*
G01Y534959D02*
X116487Y534961D01*
G01X116516Y533190D02*
X115531Y533189D01*
G01Y529959D02*
X116487Y529961D01*
G01X116516Y528190D02*
X115531Y528189D01*
G01X101993Y555472D02*
X102105Y555464D01*
G01X102104Y546019D02*
X101993Y546024D01*
G01X102104Y539721D02*
X101993Y539724D01*
G01X102104Y549170D02*
X101993Y549173D01*
G01X115531Y527894D02*
X116516D01*
G01Y525256D02*
X115531D01*
G01X115533Y524764D02*
X120866D01*
G01Y524724D02*
X116518D01*
G01X120866Y523386D02*
X115533D01*
G01X115531Y522894D02*
X116516D01*
G01Y520256D02*
X115531D01*
G01X115533Y519764D02*
X120866D01*
G01Y519724D02*
X116518D01*
G01X120866Y518386D02*
X115533D01*
G01X115531Y517894D02*
X116516D01*
G01Y515256D02*
X115531D01*
G01X115533Y514764D02*
X120866D01*
G01Y514724D02*
X116518D01*
G01X120866Y513386D02*
X115533D01*
G01X115531Y512894D02*
X116516D01*
G01Y510256D02*
X115531D01*
G01X115533Y509764D02*
X120866D01*
G01Y509724D02*
X116518D01*
G01X120866Y508386D02*
X115533D01*
G01X115531Y507894D02*
X116516D01*
G01Y505256D02*
X115531D01*
G01X115533Y504764D02*
X120866D01*
G01Y504724D02*
X116518D01*
G01X120866Y503386D02*
X115533D01*
G01X115531Y502894D02*
X116516D01*
G01X112008Y500256D02*
X106496D01*
G01X113189Y499075D02*
X105315D01*
G01X118504Y497579D02*
X103543D01*
G01X114764Y496713D02*
X117913D01*
G01X107283D02*
X103543D01*
G01Y495335D02*
X117913D01*
G01X112205Y493366D02*
X109843D01*
G01X112205Y491673D02*
X109843D01*
G01X113583Y486988D02*
X108465D01*
G01X121850Y486949D02*
X100197D01*
G01X114961Y483996D02*
X107087D01*
G01Y482421D02*
X114961D01*
G01X112205Y481043D02*
X109843D01*
G01Y479075D02*
X112205D01*
G01X114370Y477303D02*
X107677D01*
G01X119882Y476516D02*
X102165D01*
G01X115531Y524959D02*
X116487Y524961D01*
G01X116516Y523190D02*
X115531Y523189D01*
G01Y519959D02*
X116487Y519961D01*
G01X116516Y518190D02*
X115531Y518189D01*
G01Y514959D02*
X116487Y514961D01*
G01X116516Y513190D02*
X115531Y513189D01*
G01Y509959D02*
X116487Y509961D01*
G01X116516Y508190D02*
X115531Y508189D01*
G01Y504959D02*
X116487Y504961D01*
G01X116516Y503190D02*
X115531Y503189D01*
G01X106496Y500256D02*
X105315Y499075D01*
G01X103543Y497579D02*
X100197Y494232D01*
G01X115945Y556437D02*
X117126Y557618D01*
G01X112008Y556437D02*
X113189Y557618D01*
G01X113508Y495335D02*
X112205Y493366D01*
G01X107532Y487444D02*
X109843Y491673D01*
G01X115945Y536713D02*
X117126Y535531D01*
G01X112008Y536713D02*
X113189Y535531D01*
G01X118504Y497579D02*
X121850Y494232D01*
G01X112008Y500256D02*
X113189Y499075D01*
G01X103050Y552283D02*
X103053Y552272D01*
G01X112205Y491673D02*
X114515Y487444D01*
G01X109843Y493366D02*
X108539Y495335D01*
G01X103090Y537679D02*
X103091Y537691D01*
G01X103090Y540829D02*
X103091Y540840D01*
G01X103090Y543978D02*
X103091Y543990D01*
G01X103090Y547128D02*
X103091Y547139D01*
G01X103090Y550278D02*
X103091Y550289D01*
G01X103090Y553427D02*
X103091Y553439D01*
G01X103090Y556577D02*
X103091Y556588D01*
G01X116516Y504738D02*
Y504746D01*
G01Y509738D02*
Y509746D01*
G01Y514738D02*
Y514746D01*
G01Y519738D02*
Y519746D01*
G01Y524738D02*
Y524746D01*
G01Y529738D02*
Y529746D01*
G01Y534738D02*
Y534746D01*
G01Y559738D02*
Y559746D01*
G01Y564738D02*
Y564746D01*
G01Y569738D02*
Y569746D01*
G01X121850Y478484D02*
Y494232D01*
G01X120866Y568386D02*
Y569764D01*
G01Y563386D02*
Y564764D01*
G01Y558386D02*
Y559764D01*
G01Y533386D02*
Y534764D01*
G01Y528386D02*
Y529764D01*
G01Y523386D02*
Y524764D01*
G01Y518386D02*
Y519764D01*
G01Y513386D02*
Y514764D01*
G01Y508386D02*
Y509764D01*
G01Y503386D02*
Y504764D01*
G01X118504Y635571D02*
Y497579D01*
G01X117913Y637815D02*
Y495335D01*
G01X117697Y504764D02*
Y503386D01*
G01Y509764D02*
Y508386D01*
G01Y514764D02*
Y513386D01*
G01Y519764D02*
Y518386D01*
G01Y524764D02*
Y523386D01*
G01Y529764D02*
Y528386D01*
G01Y534764D02*
Y533386D01*
G01Y559764D02*
Y558386D01*
G01Y564764D02*
Y563386D01*
G01Y569764D02*
Y568386D01*
G01X117126Y557618D02*
Y535531D01*
G01X116516Y504738D02*
Y504881D01*
G01Y514738D02*
Y514881D01*
G01Y509738D02*
Y509881D01*
G01Y524738D02*
Y524881D01*
G01Y519738D02*
Y519881D01*
G01Y534738D02*
Y534881D01*
G01Y529738D02*
Y529881D01*
G01Y564738D02*
Y564881D01*
G01Y559738D02*
Y559881D01*
G01Y567894D02*
Y570256D01*
G01Y562894D02*
Y565256D01*
G01Y557894D02*
Y560256D01*
G01Y532894D02*
Y535256D01*
G01Y527894D02*
Y530256D01*
G01Y522894D02*
Y525256D01*
G01Y517894D02*
Y520256D01*
G01Y512894D02*
Y515256D01*
G01Y507894D02*
Y510256D01*
G01Y502894D02*
Y505256D01*
G01X115945Y556437D02*
Y536713D01*
G01X115531Y505256D02*
Y502894D01*
G01Y510256D02*
Y507894D01*
G01Y515256D02*
Y512894D01*
G01Y520256D02*
Y517894D01*
G01Y525256D02*
Y522894D01*
G01Y530256D02*
Y527894D01*
G01Y535256D02*
Y532894D01*
G01Y560256D02*
Y557894D01*
G01Y565256D02*
Y562894D01*
G01Y570256D02*
Y567894D01*
G01X114961Y483996D02*
Y477894D01*
G01X114764Y496713D02*
Y488169D01*
G01X113189Y535531D02*
Y499075D01*
G01Y634075D02*
Y557618D01*
G01X112205Y493366D02*
Y491673D01*
G01X112008Y536713D02*
Y500256D01*
G01Y632894D02*
Y556437D01*
G01X109843Y491673D02*
Y493366D01*
G01X107283Y488169D02*
Y496713D01*
G01X107087Y483996D02*
Y477894D01*
G01X106496Y500256D02*
Y632894D01*
G01X105315Y499075D02*
Y634075D01*
G01X103543Y534370D02*
Y495335D01*
G01Y637815D02*
Y558780D01*
G01X103091Y555275D02*
Y556772D01*
G01Y552126D02*
Y553622D01*
G01Y548976D02*
Y550472D01*
G01Y545826D02*
Y547323D01*
G01Y542677D02*
Y544173D01*
G01Y539527D02*
Y541024D01*
G01Y536378D02*
Y537874D01*
G01X103051Y536524D02*
Y536377D01*
G01Y539674D02*
Y539527D01*
G01Y541024D02*
Y540877D01*
G01Y537874D02*
Y537728D01*
G01Y545973D02*
Y545826D01*
G01Y542823D02*
Y542676D01*
G01Y544174D02*
Y544027D01*
G01Y549122D02*
Y548976D01*
G01Y550473D02*
Y550326D01*
G01Y547323D02*
Y547176D01*
G01Y555422D02*
Y555275D01*
G01Y552272D02*
Y552125D01*
G01Y553622D02*
Y553476D01*
G01Y556772D02*
Y556625D01*
G01X102146D02*
Y556772D01*
G01Y555275D02*
Y555422D01*
G01Y552125D02*
Y552272D01*
G01Y553476D02*
Y553622D01*
G01Y548976D02*
Y549122D01*
G01Y550326D02*
Y550473D01*
G01Y547176D02*
Y547323D01*
G01Y545826D02*
Y545973D01*
G01Y542676D02*
Y542823D01*
G01Y544027D02*
Y544174D01*
G01Y539527D02*
Y539674D01*
G01Y540877D02*
Y541024D01*
G01Y537728D02*
Y537874D01*
G01Y536377D02*
Y536524D01*
G01X102106Y541024D02*
Y539528D01*
G01Y537874D02*
Y536378D01*
G01Y544173D02*
Y542677D01*
G01Y550472D02*
Y548976D01*
G01Y547323D02*
Y545827D01*
G01Y553622D02*
Y552126D01*
G01Y556772D02*
Y555276D01*
G01X100925Y537717D02*
Y536535D01*
G01Y540866D02*
Y539685D01*
G01Y547165D02*
Y545984D01*
G01Y544016D02*
Y542835D01*
G01Y550315D02*
Y549134D01*
G01Y556614D02*
Y555433D01*
G01Y553465D02*
Y552283D01*
G01X100591Y558780D02*
Y534370D01*
G01X100197D02*
Y558780D01*
G01Y494232D02*
Y478484D01*
G01X103091Y555459D02*
X103090Y555470D01*
G01X103091Y552309D02*
X103090Y552320D01*
G01X103091Y549160D02*
X103090Y549170D01*
G01X103091Y546010D02*
X103090Y546021D01*
G01X103091Y542861D02*
X103090Y542871D01*
G01X103091Y539711D02*
X103090Y539722D01*
G01X103091Y536561D02*
X103090Y536572D01*
G01X116483Y574862D02*
X116487Y574961D01*
G01X116477Y574790D02*
X116483Y574862D01*
G01X116479Y574764D02*
X116477Y574790D01*
G01X116483Y579862D02*
X116487Y579961D01*
G01X116477Y579790D02*
X116483Y579862D01*
G01X116479Y579764D02*
X116477Y579790D01*
G01X116483Y584862D02*
X116487Y584961D01*
G01X116477Y584790D02*
X116483Y584862D01*
G01X116479Y584764D02*
X116477Y584790D01*
G01X116483Y589862D02*
X116487Y589961D01*
G01X116477Y589790D02*
X116483Y589862D01*
G01X116479Y589764D02*
X116477Y589790D01*
G01X116483Y594862D02*
X116487Y594961D01*
G01X116477Y594790D02*
X116483Y594862D01*
G01X116479Y594764D02*
X116477Y594790D01*
G01X116483Y599862D02*
X116487Y599961D01*
G01X116477Y599790D02*
X116483Y599862D01*
G01X116479Y599764D02*
X116477Y599790D01*
G01X116483Y604862D02*
X116487Y604961D01*
G01X116477Y604790D02*
X116483Y604862D01*
G01X116479Y604764D02*
X116477Y604790D01*
G01X116483Y609862D02*
X116487Y609961D01*
G01X116477Y609790D02*
X116483Y609862D01*
G01X116479Y609764D02*
X116477Y609790D01*
G01X116483Y614862D02*
X116487Y614961D01*
G01X116477Y614790D02*
X116483Y614862D01*
G01X116479Y614764D02*
X116477Y614790D01*
G01X116483Y619862D02*
X116487Y619961D01*
G01X116477Y619790D02*
X116483Y619862D01*
G01X116479Y619764D02*
X116477Y619790D01*
G01X116483Y624862D02*
X116487Y624961D01*
G01X116477Y624790D02*
X116483Y624862D01*
G01X116479Y624764D02*
X116477Y624790D01*
G01X116483Y629862D02*
X116487Y629961D01*
G01X116477Y629790D02*
X116483Y629862D01*
G01X116479Y629764D02*
X116477Y629790D01*
G01X115532Y628384D02*
X115533Y628386D01*
G01X115531Y628378D02*
X115532Y628384D01*
G01X115531Y628370D02*
Y628378D01*
G01X115532Y623384D02*
X115533Y623386D01*
G01X115531Y623378D02*
X115532Y623384D01*
G01X115531Y623370D02*
Y623378D01*
G01X115532Y618384D02*
X115533Y618386D01*
G01X115531Y618378D02*
X115532Y618384D01*
G01X115531Y618370D02*
Y618378D01*
G01X115532Y613384D02*
X115533Y613386D01*
G01X115531Y613378D02*
X115532Y613384D01*
G01X115531Y613370D02*
Y613378D01*
G01X115532Y608384D02*
X115533Y608386D01*
G01X115531Y608378D02*
X115532Y608384D01*
G01X115531Y608370D02*
Y608378D01*
G01X115532Y603384D02*
X115533Y603386D01*
G01X115531Y603378D02*
X115532Y603384D01*
G01X115531Y603370D02*
Y603378D01*
G01X115532Y598384D02*
X115533Y598386D01*
G01X115531Y598378D02*
X115532Y598384D01*
G01X115531Y598370D02*
Y598378D01*
G01X115532Y593384D02*
X115533Y593386D01*
G01X115531Y593378D02*
X115532Y593384D01*
G01X115531Y593370D02*
Y593378D01*
G01X115532Y588384D02*
X115533Y588386D01*
G01X115531Y588378D02*
X115532Y588384D01*
G01X115531Y588370D02*
Y588378D01*
G01X115532Y583384D02*
X115533Y583386D01*
G01X115531Y583378D02*
X115532Y583384D01*
G01X115531Y583370D02*
Y583378D01*
G01X115532Y578384D02*
X115533Y578386D01*
G01X115531Y578378D02*
X115532Y578384D01*
G01X115531Y578370D02*
Y578378D01*
G01X115532Y573384D02*
X115533Y573386D01*
G01X115531Y573378D02*
X115532Y573384D01*
G01X115531Y573370D02*
Y573378D01*
G01Y574771D02*
Y574780D01*
G01X115532Y574765D02*
X115531Y574771D01*
G01X115533Y574764D02*
X115532Y574765D01*
G01X115531Y579771D02*
Y579780D01*
G01X115532Y579765D02*
X115531Y579771D01*
G01X115533Y579764D02*
X115532Y579765D01*
G01X115531Y584771D02*
Y584780D01*
G01X115532Y584765D02*
X115531Y584771D01*
G01X115533Y584764D02*
X115532Y584765D01*
G01X115531Y589771D02*
Y589780D01*
G01X115532Y589765D02*
X115531Y589771D01*
G01X115533Y589764D02*
X115532Y589765D01*
G01X115531Y594771D02*
Y594780D01*
G01X115532Y594765D02*
X115531Y594771D01*
G01X115533Y594764D02*
X115532Y594765D01*
G01X115531Y599771D02*
Y599780D01*
G01X115532Y599765D02*
X115531Y599771D01*
G01X115533Y599764D02*
X115532Y599765D01*
G01X115531Y604771D02*
Y604780D01*
G01X115532Y604765D02*
X115531Y604771D01*
G01X115533Y604764D02*
X115532Y604765D01*
G01X115531Y609771D02*
Y609780D01*
G01X115532Y609765D02*
X115531Y609771D01*
G01X115533Y609764D02*
X115532Y609765D01*
G01X115531Y614771D02*
Y614780D01*
G01X115532Y614765D02*
X115531Y614771D01*
G01X115533Y614764D02*
X115532Y614765D01*
G01X115531Y619771D02*
Y619780D01*
G01X115532Y619765D02*
X115531Y619771D01*
G01X115533Y619764D02*
X115532Y619765D01*
G01X115531Y624771D02*
Y624780D01*
G01X115532Y624765D02*
X115531Y624771D01*
G01X115533Y624764D02*
X115532Y624765D01*
G01X115531Y629771D02*
Y629780D01*
G01X115532Y629765D02*
X115531Y629771D01*
G01X115533Y629764D02*
X115532Y629765D01*
G01X116508Y574907D02*
X116516Y574881D01*
G01X116498Y574934D02*
X116508Y574907D01*
G01X116487Y574961D02*
X116498Y574934D01*
G01X116508Y579907D02*
X116516Y579881D01*
G01X116498Y579934D02*
X116508Y579907D01*
G01X116487Y579961D02*
X116498Y579934D01*
G01X116508Y584907D02*
X116516Y584881D01*
G01X116498Y584934D02*
X116508Y584907D01*
G01X116487Y584961D02*
X116498Y584934D01*
G01X116508Y589907D02*
X116516Y589881D01*
G01X116498Y589934D02*
X116508Y589907D01*
G01X116487Y589961D02*
X116498Y589934D01*
G01X116508Y594907D02*
X116516Y594881D01*
G01X116498Y594934D02*
X116508Y594907D01*
G01X116487Y594961D02*
X116498Y594934D01*
G01X116508Y599907D02*
X116516Y599881D01*
G01X116498Y599934D02*
X116508Y599907D01*
G01X116487Y599961D02*
X116498Y599934D01*
G01X116508Y604907D02*
X116516Y604881D01*
G01X116498Y604934D02*
X116508Y604907D01*
G01X116487Y604961D02*
X116498Y604934D01*
G01X116508Y609907D02*
X116516Y609881D01*
G01X116498Y609934D02*
X116508Y609907D01*
G01X116487Y609961D02*
X116498Y609934D01*
G01X116508Y614907D02*
X116516Y614881D01*
G01X116498Y614934D02*
X116508Y614907D01*
G01X116487Y614961D02*
X116498Y614934D01*
G01X116508Y619907D02*
X116516Y619881D01*
G01X116498Y619934D02*
X116508Y619907D01*
G01X116487Y619961D02*
X116498Y619934D01*
G01X116508Y624907D02*
X116516Y624881D01*
G01X116498Y624934D02*
X116508Y624907D01*
G01X116487Y624961D02*
X116498Y624934D01*
G01X116508Y629907D02*
X116516Y629881D01*
G01X116498Y629934D02*
X116508Y629907D01*
G01X116487Y629961D02*
X116498Y629934D01*
G01Y574759D02*
X116479Y574764D01*
G01X116513Y574744D02*
X116498Y574759D01*
G01X116518Y574724D02*
X116513Y574744D01*
G01X116498Y579759D02*
X116479Y579764D01*
G01X116513Y579744D02*
X116498Y579759D01*
G01X116518Y579724D02*
X116513Y579744D01*
G01X116498Y584759D02*
X116479Y584764D01*
G01X116513Y584744D02*
X116498Y584759D01*
G01X116518Y584724D02*
X116513Y584744D01*
G01X116498Y589759D02*
X116479Y589764D01*
G01X116513Y589744D02*
X116498Y589759D01*
G01X116518Y589724D02*
X116513Y589744D01*
G01X116498Y594759D02*
X116479Y594764D01*
G01X116513Y594744D02*
X116498Y594759D01*
G01X116518Y594724D02*
X116513Y594744D01*
G01X116498Y599759D02*
X116479Y599764D01*
G01X116513Y599744D02*
X116498Y599759D01*
G01X116518Y599724D02*
X116513Y599744D01*
G01X116498Y604759D02*
X116479Y604764D01*
G01X116513Y604744D02*
X116498Y604759D01*
G01X116518Y604724D02*
X116513Y604744D01*
G01X116498Y609759D02*
X116479Y609764D01*
G01X116513Y609744D02*
X116498Y609759D01*
G01X116518Y609724D02*
X116513Y609744D01*
G01X116498Y614759D02*
X116479Y614764D01*
G01X116513Y614744D02*
X116498Y614759D01*
G01X116518Y614724D02*
X116513Y614744D01*
G01X116498Y619759D02*
X116479Y619764D01*
G01X116513Y619744D02*
X116498Y619759D01*
G01X116518Y619724D02*
X116513Y619744D01*
G01X116498Y624759D02*
X116479Y624764D01*
G01X116513Y624744D02*
X116498Y624759D01*
G01X116518Y624724D02*
X116513Y624744D01*
G01X116498Y629759D02*
X116479Y629764D01*
G01X116513Y629744D02*
X116498Y629759D01*
G01X116518Y629724D02*
X116513Y629744D01*
G01X116516Y574731D02*
Y574738D01*
G01X116517Y574726D02*
X116516Y574731D01*
G01X116518Y574724D02*
X116517Y574726D01*
G01X116516Y579731D02*
Y579738D01*
G01X116517Y579726D02*
X116516Y579731D01*
G01X116518Y579724D02*
X116517Y579726D01*
G01X116516Y584731D02*
Y584738D01*
G01X116517Y584726D02*
X116516Y584731D01*
G01X116518Y584724D02*
X116517Y584726D01*
G01X116516Y589731D02*
Y589738D01*
G01X116517Y589726D02*
X116516Y589731D01*
G01X116518Y589724D02*
X116517Y589726D01*
G01X116516Y594731D02*
Y594738D01*
G01X116517Y594726D02*
X116516Y594731D01*
G01X116518Y594724D02*
X116517Y594726D01*
G01X116516Y599731D02*
Y599738D01*
G01X116517Y599726D02*
X116516Y599731D01*
G01X116518Y599724D02*
X116517Y599726D01*
G01X116516Y604731D02*
Y604738D01*
G01X116517Y604726D02*
X116516Y604731D01*
G01X116518Y604724D02*
X116517Y604726D01*
G01X116516Y609731D02*
Y609738D01*
G01X116517Y609726D02*
X116516Y609731D01*
G01X116518Y609724D02*
X116517Y609726D01*
G01X116516Y614731D02*
Y614738D01*
G01X116517Y614726D02*
X116516Y614731D01*
G01X116518Y614724D02*
X116517Y614726D01*
G01X116516Y619731D02*
Y619738D01*
G01X116517Y619726D02*
X116516Y619731D01*
G01X116518Y619724D02*
X116517Y619726D01*
G01X116516Y624731D02*
Y624738D01*
G01X116517Y624726D02*
X116516Y624731D01*
G01X116518Y624724D02*
X116517Y624726D01*
G01X116516Y629731D02*
Y629738D01*
G01X116517Y629726D02*
X116516Y629731D01*
G01X116518Y629724D02*
X116517Y629726D01*
G01X116516Y628378D02*
Y628369D01*
G01X116517Y628384D02*
X116516Y628378D01*
G01X116519Y628386D02*
X116517Y628384D01*
G01X116516Y623378D02*
Y623369D01*
G01X116517Y623384D02*
X116516Y623378D01*
G01X116519Y623386D02*
X116517Y623384D01*
G01X116516Y618378D02*
Y618369D01*
G01X116517Y618384D02*
X116516Y618378D01*
G01X116519Y618386D02*
X116517Y618384D01*
G01X116516Y613378D02*
Y613369D01*
G01X116517Y613384D02*
X116516Y613378D01*
G01X116519Y613386D02*
X116517Y613384D01*
G01X116516Y608378D02*
Y608369D01*
G01X116517Y608384D02*
X116516Y608378D01*
G01X116519Y608386D02*
X116517Y608384D01*
G01X116516Y603378D02*
Y603369D01*
G01X116517Y603384D02*
X116516Y603378D01*
G01X116519Y603386D02*
X116517Y603384D01*
G01X116516Y598378D02*
Y598369D01*
G01X116517Y598384D02*
X116516Y598378D01*
G01X116519Y598386D02*
X116517Y598384D01*
G01X116516Y593378D02*
Y593369D01*
G01X116517Y593384D02*
X116516Y593378D01*
G01X116519Y593386D02*
X116517Y593384D01*
G01X116516Y588378D02*
Y588369D01*
G01X116517Y588384D02*
X116516Y588378D01*
G01X116519Y588386D02*
X116517Y588384D01*
G01X116516Y583378D02*
Y583369D01*
G01X116517Y583384D02*
X116516Y583378D01*
G01X116519Y583386D02*
X116517Y583384D01*
G01X116516Y578378D02*
Y578369D01*
G01X116517Y578384D02*
X116516Y578378D01*
G01X116519Y578386D02*
X116517Y578384D01*
G01X116516Y573378D02*
Y573369D01*
G01X116517Y573384D02*
X116516Y573378D01*
G01X116519Y573386D02*
X116517Y573384D01*
G01X116503Y574755D02*
X116514Y574740D01*
G01X116479Y574764D02*
X116503Y574755D01*
G01Y579755D02*
X116514Y579740D01*
G01X116479Y579764D02*
X116503Y579755D01*
G01Y584755D02*
X116514Y584740D01*
G01X116479Y584764D02*
X116503Y584755D01*
G01Y589755D02*
X116514Y589740D01*
G01X116479Y589764D02*
X116503Y589755D01*
G01Y594755D02*
X116514Y594740D01*
G01X116479Y594764D02*
X116503Y594755D01*
G01Y599755D02*
X116514Y599740D01*
G01X116479Y599764D02*
X116503Y599755D01*
G01Y604755D02*
X116514Y604740D01*
G01X116479Y604764D02*
X116503Y604755D01*
G01Y609755D02*
X116514Y609740D01*
G01X116479Y609764D02*
X116503Y609755D01*
G01Y614755D02*
X116514Y614740D01*
G01X116479Y614764D02*
X116503Y614755D01*
G01Y619755D02*
X116514Y619740D01*
G01X116479Y619764D02*
X116503Y619755D01*
G01Y624755D02*
X116514Y624740D01*
G01X116479Y624764D02*
X116503Y624755D01*
G01Y629755D02*
X116514Y629740D01*
G01X116479Y629764D02*
X116503Y629755D01*
G01X114961Y655256D02*
G03X114370Y655846I-591J-1D01*
G01X107677D02*
G03X107087Y655256I0J-590D01*
G01X109843Y654075D02*
G03Y652106I0J-985D01*
G01X112205D02*
G03Y654075I0J984D01*
G01X108465Y646161D02*
G03X107283Y644980I-1J-1181D01*
G01X114764D02*
G03X113583Y646161I-1181J0D01*
G01X112913Y640886D02*
G03I-1889J0D01*
G01X121850Y654665D02*
G03X119882Y656634I-1968J1D01*
G01X102165D02*
G03X100197Y654665I1J-1969D01*
G01X113386Y640886D02*
G03I-2362J0D01*
G01X119882Y656634D02*
X102165D01*
G01X114370Y655846D02*
X107677D01*
G01X112205Y654075D02*
X109843D01*
G01Y652106D02*
X112205D01*
G01X114961Y650728D02*
X107087D01*
G01Y649154D02*
X114961D01*
G01X121850Y646201D02*
X100197D01*
G01X108465Y646161D02*
X113583D01*
G01X109843Y641476D02*
X112205D01*
G01X109843Y639783D02*
X112205D01*
G01X103543Y637815D02*
X117913D01*
G01X103543Y636437D02*
X107283D01*
G01X117913D02*
X114764D01*
G01X103543Y635571D02*
X118504D01*
G01X105315Y634075D02*
X113189D01*
G01X106496Y632894D02*
X112008D01*
G01X116516Y630256D02*
X115531D01*
G01X115533Y629764D02*
X120866D01*
G01Y629724D02*
X116518D01*
G01X120866Y628386D02*
X115533D01*
G01X115531Y627894D02*
X116516D01*
G01Y625256D02*
X115531D01*
G01X115533Y624764D02*
X120866D01*
G01Y624724D02*
X116518D01*
G01X120866Y623386D02*
X115533D01*
G01X115531Y622894D02*
X116516D01*
G01Y620256D02*
X115531D01*
G01X115533Y619764D02*
X120866D01*
G01Y619724D02*
X116518D01*
G01X120866Y618386D02*
X115533D01*
G01X115531Y617894D02*
X116516D01*
G01Y615256D02*
X115531D01*
G01X115533Y614764D02*
X120866D01*
G01Y614724D02*
X116518D01*
G01X120866Y613386D02*
X115533D01*
G01X115531Y612894D02*
X116516D01*
G01Y610256D02*
X115531D01*
G01Y629959D02*
X116487Y629961D01*
G01X116516Y628190D02*
X115531Y628189D01*
G01Y624959D02*
X116487Y624961D01*
G01X116516Y623190D02*
X115531Y623189D01*
G01Y619959D02*
X116487Y619961D01*
G01X116516Y618190D02*
X115531Y618189D01*
G01Y614959D02*
X116487Y614961D01*
G01X116516Y613190D02*
X115531Y613189D01*
G01Y609959D02*
X116487Y609961D01*
G01X115533Y609764D02*
X120866D01*
G01Y609724D02*
X116518D01*
G01X120866Y608386D02*
X115533D01*
G01X115531Y607894D02*
X116516D01*
G01Y605256D02*
X115531D01*
G01X115533Y604764D02*
X120866D01*
G01Y604724D02*
X116518D01*
G01X120866Y603386D02*
X115533D01*
G01X115531Y602894D02*
X116516D01*
G01Y600256D02*
X115531D01*
G01X115533Y599764D02*
X120866D01*
G01Y599724D02*
X116518D01*
G01X120866Y598386D02*
X115533D01*
G01X115531Y597894D02*
X116516D01*
G01Y595256D02*
X115531D01*
G01X115533Y594764D02*
X120866D01*
G01Y594724D02*
X116518D01*
G01X120866Y593386D02*
X115533D01*
G01X115531Y592894D02*
X116516D01*
G01Y590256D02*
X115531D01*
G01X115533Y589764D02*
X120866D01*
G01Y589724D02*
X116518D01*
G01X120866Y588386D02*
X115533D01*
G01X115531Y587894D02*
X116516D01*
G01Y585256D02*
X115531D01*
G01X115533Y584764D02*
X120866D01*
G01Y584724D02*
X116518D01*
G01X120866Y583386D02*
X115533D01*
G01X115531Y582894D02*
X116516D01*
G01Y580256D02*
X115531D01*
G01X115533Y579764D02*
X120866D01*
G01Y579724D02*
X116518D01*
G01X120866Y578386D02*
X115533D01*
G01X115531Y577894D02*
X116516D01*
G01Y575256D02*
X115531D01*
G01X115533Y574764D02*
X120866D01*
G01Y574724D02*
X116518D01*
G01X120866Y573386D02*
X115533D01*
G01X115531Y572894D02*
X116516D01*
G01Y608190D02*
X115531Y608189D01*
G01Y604959D02*
X116487Y604961D01*
G01X116516Y603190D02*
X115531Y603189D01*
G01Y599959D02*
X116487Y599961D01*
G01X116516Y598190D02*
X115531Y598189D01*
G01Y594959D02*
X116487Y594961D01*
G01X116516Y593190D02*
X115531Y593189D01*
G01Y589959D02*
X116487Y589961D01*
G01X116516Y588190D02*
X115531Y588189D01*
G01Y584959D02*
X116487Y584961D01*
G01X116516Y583190D02*
X115531Y583189D01*
G01Y579959D02*
X116487Y579961D01*
G01X116516Y578190D02*
X115531Y578189D01*
G01Y574959D02*
X116487Y574961D01*
G01X116516Y573190D02*
X115531Y573189D01*
G01X121850Y638917D02*
X118504Y635571D01*
G01X112008Y632894D02*
X113189Y634075D01*
G01X105315D02*
X106496Y632894D01*
G01X100197Y638917D02*
X103543Y635571D01*
G01X108539Y637815D02*
X109843Y639783D01*
G01X114515Y645706D02*
X112205Y641476D01*
G01Y639783D02*
X113508Y637815D01*
G01X109843Y641476D02*
X107532Y645706D01*
G01X116516Y574738D02*
Y574746D01*
G01Y579738D02*
Y579746D01*
G01Y584738D02*
Y584746D01*
G01Y589738D02*
Y589746D01*
G01Y594738D02*
Y594746D01*
G01Y599738D02*
Y599746D01*
G01Y604738D02*
Y604746D01*
G01Y609738D02*
Y609746D01*
G01Y614738D02*
Y614746D01*
G01Y619738D02*
Y619746D01*
G01Y624738D02*
Y624746D01*
G01Y629738D02*
Y629746D01*
G01X121850Y638917D02*
Y654665D01*
G01X120866Y628386D02*
Y629764D01*
G01Y623386D02*
Y624764D01*
G01Y618386D02*
Y619764D01*
G01Y613386D02*
Y614764D01*
G01Y608386D02*
Y609764D01*
G01Y603386D02*
Y604764D01*
G01Y598386D02*
Y599764D01*
G01Y593386D02*
Y594764D01*
G01Y588386D02*
Y589764D01*
G01Y583386D02*
Y584764D01*
G01Y578386D02*
Y579764D01*
G01Y573386D02*
Y574764D01*
G01X117697D02*
Y573386D01*
G01Y579764D02*
Y578386D01*
G01Y584764D02*
Y583386D01*
G01Y589764D02*
Y588386D01*
G01Y594764D02*
Y593386D01*
G01Y599764D02*
Y598386D01*
G01Y604764D02*
Y603386D01*
G01Y609764D02*
Y608386D01*
G01Y614764D02*
Y613386D01*
G01Y619764D02*
Y618386D01*
G01Y624764D02*
Y623386D01*
G01Y629764D02*
Y628386D01*
G01X116516Y627894D02*
Y630256D01*
G01Y622894D02*
Y625256D01*
G01Y617894D02*
Y620256D01*
G01Y612894D02*
Y615256D01*
G01Y607894D02*
Y610256D01*
G01Y602894D02*
Y605256D01*
G01Y597894D02*
Y600256D01*
G01Y592894D02*
Y595256D01*
G01Y587894D02*
Y590256D01*
G01Y582894D02*
Y585256D01*
G01Y577894D02*
Y580256D01*
G01Y572894D02*
Y575256D01*
G01X115531D02*
Y572894D01*
G01Y580256D02*
Y577894D01*
G01Y585256D02*
Y582894D01*
G01Y590256D02*
Y587894D01*
G01Y595256D02*
Y592894D01*
G01Y600256D02*
Y597894D01*
G01Y605256D02*
Y602894D01*
G01Y610256D02*
Y607894D01*
G01Y615256D02*
Y612894D01*
G01Y620256D02*
Y617894D01*
G01Y625256D02*
Y622894D01*
G01Y630256D02*
Y627894D01*
G01X114961Y649154D02*
Y655256D01*
G01X114764Y644980D02*
Y636437D01*
G01X112205Y641476D02*
Y639783D01*
G01X109843D02*
Y641476D01*
G01X107283Y636437D02*
Y644980D01*
G01X107087Y649154D02*
Y655256D01*
G01X100197Y654665D02*
Y638917D01*
G01X114295Y717468D02*
G03X148106I16905J-13531D01*
G01X141181Y730599D02*
G03X148106Y717468I37662J11471D01*
G01X141181Y730599D02*
G03X121220I-9980J-3040D01*
G01X114295Y717468D02*
G03X121220Y730599I-30737J24601D01*
G01X193307Y707087D02*
G03X192126I-591J0D01*
G01Y713386D02*
G03X193307I591J0D01*
G01Y707087D02*
G03X192126I-591J0D01*
G01Y713386D02*
G03X193307I591J0D01*
G01X141181Y730599D02*
G03X148106Y717468I37662J11471D01*
G01X141181Y730599D02*
G03X121220I-9980J-3040D01*
G01X114295Y717468D02*
G03X148106I16905J-13531D01*
G01X114295D02*
G03X121220Y730599I-30737J24601D01*
G01X195276Y713386D02*
X193307D01*
G01X192126D02*
X191339D01*
G01X195276D02*
X193307D01*
G01X192126D02*
X191339D01*
G01X197244Y712402D02*
X191339D01*
G01Y712205D02*
X197244D01*
G01X191339Y708268D02*
X197244D01*
G01Y708071D02*
X191339D01*
G01X193307Y707087D02*
X195276D01*
G01X191339D02*
X192126D01*
G01X193307D02*
X195276D01*
G01X191339D02*
X192126D01*
G01X191339D02*
Y713386D01*
G01D02*
Y707087D01*
G01X112126Y945020D02*
G03I-1102J0D01*
G01X113583Y939744D02*
G03X114764Y940925I0J1181D01*
G01X107283D02*
G03X108465Y939744I1181J0D01*
G01X112598Y945020D02*
G03I-1574J0D01*
G01X107087Y930650D02*
G03X107677Y930059I590J-1D01*
G01X114370D02*
G03X114961Y930650I0J591D01*
G01X112205Y931831D02*
G03Y933799I0J984D01*
G01X109843D02*
G03Y931831I0J-984D01*
G01X100197Y931240D02*
G03X102165Y929272I1968J0D01*
G01X119882D02*
G03X121850Y931240I0J1968D01*
G01X113189Y951831D02*
X105315D01*
G01X118504Y950335D02*
X103543D01*
G01X114764Y949469D02*
X117913D01*
G01X107283D02*
X103543D01*
G01Y948091D02*
X117913D01*
G01X112205Y946122D02*
X109843D01*
G01X112205Y944429D02*
X109843D01*
G01X113583Y939744D02*
X108465D01*
G01X121850Y939705D02*
X100197D01*
G01X114961Y936752D02*
X107087D01*
G01Y935177D02*
X114961D01*
G01X112205Y933799D02*
X109843D01*
G01Y931831D02*
X112205D01*
G01X114370Y930059D02*
X107677D01*
G01X119882Y929272D02*
X102165D01*
G01X118504Y950335D02*
X121850Y946988D01*
G01X112008Y953012D02*
X113189Y951831D01*
G01X109843Y946122D02*
X108539Y948091D01*
G01X112205Y944429D02*
X114515Y940200D01*
G01X106496Y953012D02*
X105315Y951831D01*
G01X103543Y950335D02*
X100197Y946988D01*
G01X113508Y948091D02*
X112205Y946122D01*
G01X107532Y940200D02*
X109843Y944429D01*
G01X121850Y931240D02*
Y946988D01*
G01X118504Y1088327D02*
Y950335D01*
G01X117913Y1090571D02*
Y948091D01*
G01X114961Y936752D02*
Y930650D01*
G01X114764Y949469D02*
Y940925D01*
G01X113189Y988287D02*
Y951831D01*
G01X112205Y946122D02*
Y944429D01*
G01X109843D02*
Y946122D01*
G01X107283Y940925D02*
Y949469D01*
G01X107087Y936752D02*
Y930650D01*
G01X105315Y951831D02*
Y1086831D01*
G01X103543Y987126D02*
Y948091D01*
G01X100197Y946988D02*
Y931240D01*
G01X102119Y1009361D02*
X102143Y1009370D01*
G01X102108Y1009347D02*
X102119Y1009361D01*
G01X102106Y1009340D02*
X102108Y1009347D01*
G01X102119Y1006212D02*
X102143Y1006220D01*
G01X102108Y1006197D02*
X102119Y1006212D01*
G01X102106Y1006191D02*
X102108Y1006197D01*
G01X102119Y1003062D02*
X102143Y1003071D01*
G01X102108Y1003048D02*
X102119Y1003062D01*
G01X102106Y1003041D02*
X102108Y1003048D01*
G01X102119Y999913D02*
X102143Y999921D01*
G01X102108Y999898D02*
X102119Y999913D01*
G01X102106Y999891D02*
X102108Y999898D01*
G01X102119Y996763D02*
X102143Y996772D01*
G01X102108Y996748D02*
X102119Y996763D01*
G01X102106Y996742D02*
X102108Y996748D01*
G01X102119Y993613D02*
X102143Y993622D01*
G01X102108Y993599D02*
X102119Y993613D01*
G01X102106Y993592D02*
X102108Y993599D01*
G01X102119Y990464D02*
X102143Y990472D01*
G01X102108Y990449D02*
X102119Y990464D01*
G01X102106Y990443D02*
X102108Y990449D01*
G01X116483Y957618D02*
X116487Y957717D01*
G01X116477Y957546D02*
X116483Y957618D01*
G01X116479Y957520D02*
X116477Y957546D01*
G01X116483Y962618D02*
X116487Y962717D01*
G01X116477Y962546D02*
X116483Y962618D01*
G01X116479Y962520D02*
X116477Y962546D01*
G01X116483Y967618D02*
X116487Y967717D01*
G01X116477Y967546D02*
X116483Y967618D01*
G01X116479Y967520D02*
X116477Y967546D01*
G01X116483Y972618D02*
X116487Y972717D01*
G01X116477Y972546D02*
X116483Y972618D01*
G01X116479Y972520D02*
X116477Y972546D01*
G01X116483Y977618D02*
X116487Y977717D01*
G01X116477Y977546D02*
X116483Y977618D01*
G01X116479Y977520D02*
X116477Y977546D01*
G01X116483Y982618D02*
X116487Y982717D01*
G01X116477Y982546D02*
X116483Y982618D01*
G01X116479Y982520D02*
X116477Y982546D01*
G01X116483Y987618D02*
X116487Y987717D01*
G01X116477Y987546D02*
X116483Y987618D01*
G01X116479Y987520D02*
X116477Y987546D01*
G01X116483Y1012618D02*
X116487Y1012717D01*
G01X116477Y1012546D02*
X116483Y1012618D01*
G01X116479Y1012520D02*
X116477Y1012546D01*
G01X116483Y1017618D02*
X116487Y1017717D01*
G01X116477Y1017546D02*
X116483Y1017618D01*
G01X116479Y1017520D02*
X116477Y1017546D01*
G01X116483Y1022618D02*
X116487Y1022717D01*
G01X116477Y1022546D02*
X116483Y1022618D01*
G01X116479Y1022520D02*
X116477Y1022546D01*
G01X116483Y1027618D02*
X116487Y1027717D01*
G01X116477Y1027546D02*
X116483Y1027618D01*
G01X116479Y1027520D02*
X116477Y1027546D01*
G01X116483Y1032618D02*
X116487Y1032717D01*
G01X116477Y1032546D02*
X116483Y1032618D01*
G01X116479Y1032520D02*
X116477Y1032546D01*
G01X116483Y1037618D02*
X116487Y1037717D01*
G01X116477Y1037546D02*
X116483Y1037618D01*
G01X116479Y1037520D02*
X116477Y1037546D01*
G01X116483Y1042618D02*
X116487Y1042717D01*
G01X116477Y1042546D02*
X116483Y1042618D01*
G01X116479Y1042520D02*
X116477Y1042546D01*
G01X102106Y1001923D02*
Y1001916D01*
G01X102105Y1001928D02*
X102106Y1001923D01*
G01Y1001918D02*
X102105Y1001928D01*
G01X102146Y1009554D02*
Y1009567D01*
G01X102143Y1009541D02*
X102146Y1009554D01*
G01X102143Y1009528D02*
Y1009541D01*
G01X102146Y1006405D02*
Y1006417D01*
G01X102143Y1006392D02*
X102146Y1006405D01*
G01X102143Y1006378D02*
Y1006392D01*
G01X102146Y1003255D02*
Y1003268D01*
G01X102143Y1003242D02*
X102146Y1003255D01*
G01X102143Y1003228D02*
Y1003242D01*
G01X102146Y1000106D02*
Y1000118D01*
G01X102143Y1000093D02*
X102146Y1000106D01*
G01X102143Y1000079D02*
Y1000093D01*
G01X102146Y996956D02*
Y996969D01*
G01X102143Y996943D02*
X102146Y996956D01*
G01X102143Y996929D02*
Y996943D01*
G01X102146Y993806D02*
Y993819D01*
G01X102143Y993793D02*
X102146Y993806D01*
G01X102143Y993780D02*
Y993793D01*
G01X102146Y990657D02*
Y990669D01*
G01X102143Y990644D02*
X102146Y990657D01*
G01X102143Y990630D02*
Y990644D01*
G01X115532Y1046140D02*
X115533Y1046142D01*
G01X115531Y1046134D02*
X115532Y1046140D01*
G01X115531Y1046126D02*
Y1046134D01*
G01X115532Y1041140D02*
X115533Y1041142D01*
G01X115531Y1041134D02*
X115532Y1041140D01*
G01X115531Y1041126D02*
Y1041134D01*
G01X115532Y1036140D02*
X115533Y1036142D01*
G01X115531Y1036134D02*
X115532Y1036140D01*
G01X115531Y1036126D02*
Y1036134D01*
G01X115532Y1031140D02*
X115533Y1031142D01*
G01X115531Y1031134D02*
X115532Y1031140D01*
G01X115531Y1031126D02*
Y1031134D01*
G01X115532Y1026140D02*
X115533Y1026142D01*
G01X115531Y1026134D02*
X115532Y1026140D01*
G01X115531Y1026126D02*
Y1026134D01*
G01X115532Y1021140D02*
X115533Y1021142D01*
G01X115531Y1021134D02*
X115532Y1021140D01*
G01X115531Y1021126D02*
Y1021134D01*
G01X115532Y1016140D02*
X115533Y1016142D01*
G01X115531Y1016134D02*
X115532Y1016140D01*
G01X115531Y1016126D02*
Y1016134D01*
G01X115532Y1011140D02*
X115533Y1011142D01*
G01X115531Y1011134D02*
X115532Y1011140D01*
G01X115531Y1011126D02*
Y1011134D01*
G01X115532Y986140D02*
X115533Y986142D01*
G01X115531Y986134D02*
X115532Y986140D01*
G01X115531Y986126D02*
Y986134D01*
G01X115532Y981140D02*
X115533Y981142D01*
G01X115531Y981134D02*
X115532Y981140D01*
G01X115531Y981126D02*
Y981134D01*
G01X115532Y976140D02*
X115533Y976142D01*
G01X115531Y976134D02*
X115532Y976140D01*
G01X115531Y976126D02*
Y976134D01*
G01X115532Y971140D02*
X115533Y971142D01*
G01X115531Y971134D02*
X115532Y971140D01*
G01X115531Y971126D02*
Y971134D01*
G01X115532Y966140D02*
X115533Y966142D01*
G01X115531Y966134D02*
X115532Y966140D01*
G01X115531Y966126D02*
Y966134D01*
G01X115532Y961140D02*
X115533Y961142D01*
G01X115531Y961134D02*
X115532Y961140D01*
G01X115531Y961126D02*
Y961134D01*
G01X115532Y956140D02*
X115533Y956142D01*
G01X115531Y956134D02*
X115532Y956140D01*
G01X115531Y956126D02*
Y956134D01*
G01X102106Y1008222D02*
Y1008215D01*
G01X102105Y1008227D02*
X102106Y1008222D01*
G01X102105Y1008219D02*
Y1008227D01*
G01X102143Y1008017D02*
X102142Y1008031D01*
G01X102146Y1008005D02*
X102143Y1008017D01*
G01X102146Y1007992D02*
Y1008005D01*
G01X102143Y1004868D02*
X102142Y1004881D01*
G01X102146Y1004855D02*
X102143Y1004868D01*
G01X102146Y1004843D02*
Y1004855D01*
G01X102143Y1001718D02*
X102142Y1001732D01*
G01X102146Y1001706D02*
X102143Y1001718D01*
G01X102146Y1001693D02*
Y1001706D01*
G01X102143Y998569D02*
X102142Y998582D01*
G01X102146Y998556D02*
X102143Y998569D01*
G01X102146Y998543D02*
Y998556D01*
G01X102143Y995419D02*
X102142Y995433D01*
G01X102146Y995406D02*
X102143Y995419D01*
G01X102146Y995394D02*
Y995406D01*
G01X102143Y992269D02*
X102142Y992283D01*
G01X102146Y992257D02*
X102143Y992269D01*
G01X102146Y992244D02*
Y992257D01*
G01X102143Y989120D02*
X102142Y989133D01*
G01X102146Y989107D02*
X102143Y989120D01*
G01X102146Y989094D02*
Y989107D01*
G01X103054Y1009541D02*
X103055Y1009528D01*
G01X103050Y1009554D02*
X103054Y1009541D01*
G01X103051Y1009567D02*
X103050Y1009554D01*
G01X103054Y1006392D02*
X103055Y1006378D01*
G01X103050Y1006405D02*
X103054Y1006392D01*
G01X103051Y1006417D02*
X103050Y1006405D01*
G01X103054Y1003242D02*
X103055Y1003228D01*
G01X103050Y1003255D02*
X103054Y1003242D01*
G01X103051Y1003268D02*
X103050Y1003255D01*
G01X103054Y1000093D02*
X103055Y1000079D01*
G01X103050Y1000106D02*
X103054Y1000093D01*
G01X103051Y1000118D02*
X103050Y1000106D01*
G01X103054Y996943D02*
X103055Y996929D01*
G01X103050Y996956D02*
X103054Y996943D01*
G01X103051Y996969D02*
X103050Y996956D01*
G01X103054Y993793D02*
X103055Y993780D01*
G01X103050Y993806D02*
X103054Y993793D01*
G01X103051Y993819D02*
X103050Y993806D01*
G01X103054Y990644D02*
X103055Y990630D01*
G01X103050Y990657D02*
X103054Y990644D01*
G01X103051Y990669D02*
X103050Y990657D01*
G01X102106Y995624D02*
Y995617D01*
G01X102105Y995628D02*
X102106Y995624D01*
G01X102105Y995621D02*
Y995628D01*
G01X102106Y1005073D02*
Y1005065D01*
G01X102105Y1005077D02*
X102106Y1005073D01*
G01X102105Y1005070D02*
Y1005077D01*
G01X103050Y1008005D02*
X103051Y1007992D01*
G01X103053Y1008017D02*
X103050Y1008005D01*
G01X103054Y1008031D02*
X103053Y1008017D01*
G01X103050Y1004855D02*
X103051Y1004843D01*
G01X103053Y1004868D02*
X103050Y1004855D01*
G01X103054Y1004881D02*
X103053Y1004868D01*
G01X103050Y1001706D02*
X103051Y1001693D01*
G01X103053Y1001718D02*
X103050Y1001706D01*
G01X103054Y1001732D02*
X103053Y1001718D01*
G01X103050Y998556D02*
X103051Y998543D01*
G01X103053Y998569D02*
X103050Y998556D01*
G01X103054Y998582D02*
X103053Y998569D01*
G01X103050Y995406D02*
X103051Y995394D01*
G01X103053Y995419D02*
X103050Y995406D01*
G01X103054Y995433D02*
X103053Y995419D01*
G01X103050Y992257D02*
X103051Y992244D01*
G01X103053Y992269D02*
X103050Y992257D01*
G01X103054Y992283D02*
X103053Y992269D01*
G01X103050Y989107D02*
X103051Y989094D01*
G01X103053Y989120D02*
X103050Y989107D01*
G01X103054Y989133D02*
X103053Y989120D01*
G01X102106Y989325D02*
Y989317D01*
G01X102105Y989329D02*
X102106Y989325D01*
G01X102105Y989323D02*
Y989329D01*
G01X103091Y1009337D02*
Y1009344D01*
G01X103090Y1009332D02*
X103091Y1009337D01*
G01X103089Y1009331D02*
X103090Y1009332D01*
G01X103091Y1006187D02*
Y1006194D01*
G01X103090Y1006183D02*
X103091Y1006187D01*
G01X103089Y1006181D02*
X103090Y1006183D01*
G01X103091Y1003038D02*
Y1003045D01*
G01X103090Y1003033D02*
X103091Y1003038D01*
G01X103089Y1003031D02*
X103090Y1003033D01*
G01X103091Y999888D02*
Y999895D01*
G01X103090Y999883D02*
X103091Y999888D01*
G01X103089Y999882D02*
X103090Y999883D01*
G01X103091Y996739D02*
Y996746D01*
G01X103090Y996734D02*
X103091Y996739D01*
G01X103089Y996732D02*
X103090Y996734D01*
G01X103091Y993589D02*
Y993596D01*
G01X103090Y993584D02*
X103091Y993589D01*
G01X103089Y993583D02*
X103090Y993584D01*
G01X103091Y990439D02*
Y990446D01*
G01X103090Y990435D02*
X103091Y990439D01*
G01X103089Y990433D02*
X103090Y990435D01*
G01X102106Y998774D02*
Y998766D01*
G01X102105Y998778D02*
X102106Y998774D01*
G01X102104Y998775D02*
X102105Y998778D01*
G01X102106Y992474D02*
Y992467D01*
G01X102105Y992479D02*
X102106Y992474D01*
G01X102104Y992477D02*
X102105Y992479D01*
G01X103051Y1009375D02*
Y1009381D01*
G01X103050Y1009371D02*
X103051Y1009375D01*
G01X103050Y1009370D02*
Y1009371D01*
G01X103051Y1006226D02*
Y1006231D01*
G01X103050Y1006222D02*
X103051Y1006226D01*
G01X103050Y1006220D02*
Y1006222D01*
G01X103051Y1003076D02*
Y1003082D01*
G01X103050Y1003072D02*
X103051Y1003076D01*
G01X103050Y1003071D02*
Y1003072D01*
G01X103051Y999926D02*
Y999932D01*
G01X103050Y999922D02*
X103051Y999926D01*
G01X103050Y999921D02*
Y999922D01*
G01X103051Y996777D02*
Y996783D01*
G01X103050Y996773D02*
X103051Y996777D01*
G01X103050Y996772D02*
Y996773D01*
G01X103051Y993627D02*
Y993633D01*
G01X103050Y993623D02*
X103051Y993627D01*
G01X103050Y993622D02*
Y993623D01*
G01X103051Y990478D02*
Y990483D01*
G01X103050Y990474D02*
X103051Y990478D01*
G01X103050Y990472D02*
Y990474D01*
G01X116516Y1046134D02*
Y1046125D01*
G01X116517Y1046140D02*
X116516Y1046134D01*
G01X116519Y1046142D02*
X116517Y1046140D01*
G01X116516Y1041134D02*
Y1041125D01*
G01X116517Y1041140D02*
X116516Y1041134D01*
G01X116519Y1041142D02*
X116517Y1041140D01*
G01X116516Y1036134D02*
Y1036125D01*
G01X116517Y1036140D02*
X116516Y1036134D01*
G01X116519Y1036142D02*
X116517Y1036140D01*
G01X116516Y1031134D02*
Y1031125D01*
G01X116517Y1031140D02*
X116516Y1031134D01*
G01X116519Y1031142D02*
X116517Y1031140D01*
G01X116516Y1026134D02*
Y1026125D01*
G01X116517Y1026140D02*
X116516Y1026134D01*
G01X116519Y1026142D02*
X116517Y1026140D01*
G01X116516Y1021134D02*
Y1021125D01*
G01X116517Y1021140D02*
X116516Y1021134D01*
G01X116519Y1021142D02*
X116517Y1021140D01*
G01X116516Y1016134D02*
Y1016125D01*
G01X116517Y1016140D02*
X116516Y1016134D01*
G01X116519Y1016142D02*
X116517Y1016140D01*
G01X116516Y1011134D02*
Y1011125D01*
G01X116517Y1011140D02*
X116516Y1011134D01*
G01X116519Y1011142D02*
X116517Y1011140D01*
G01X103083Y996754D02*
X103076Y996762D01*
G01X103088Y996743D02*
X103083Y996754D01*
G01X103089Y996732D02*
X103088Y996743D01*
G01X103083Y990454D02*
X103076Y990463D01*
G01X103088Y990444D02*
X103083Y990454D01*
G01X103089Y990433D02*
X103088Y990444D01*
G01X103083Y993604D02*
X103076Y993612D01*
G01X103088Y993594D02*
X103083Y993604D01*
G01X103089Y993583D02*
X103088Y993594D01*
G01X103083Y999903D02*
X103076Y999911D01*
G01X103088Y999893D02*
X103083Y999903D01*
G01X103089Y999882D02*
X103088Y999893D01*
G01X103083Y1003053D02*
X103076Y1003061D01*
G01X103088Y1003043D02*
X103083Y1003053D01*
G01X103089Y1003031D02*
X103088Y1003043D01*
G01X103083Y1006202D02*
X103076Y1006211D01*
G01X103088Y1006192D02*
X103083Y1006202D01*
G01X103089Y1006181D02*
X103088Y1006192D01*
G01X103083Y1009352D02*
X103076Y1009360D01*
G01X103088Y1009342D02*
X103083Y1009352D01*
G01X103089Y1009331D02*
X103088Y1009342D01*
G01X116516Y986134D02*
Y986125D01*
G01X116517Y986140D02*
X116516Y986134D01*
G01X116519Y986142D02*
X116517Y986140D01*
G01X116516Y981134D02*
Y981125D01*
G01X116517Y981140D02*
X116516Y981134D01*
G01X116519Y981142D02*
X116517Y981140D01*
G01X116516Y976134D02*
Y976125D01*
G01X116517Y976140D02*
X116516Y976134D01*
G01X116519Y976142D02*
X116517Y976140D01*
G01X116516Y971134D02*
Y971125D01*
G01X116517Y971140D02*
X116516Y971134D01*
G01X116519Y971142D02*
X116517Y971140D01*
G01X116516Y966134D02*
Y966125D01*
G01X116517Y966140D02*
X116516Y966134D01*
G01X116519Y966142D02*
X116517Y966140D01*
G01X116516Y961134D02*
Y961125D01*
G01X116517Y961140D02*
X116516Y961134D01*
G01X116519Y961142D02*
X116517Y961140D01*
G01X116516Y956134D02*
Y956125D01*
G01X116517Y956140D02*
X116516Y956134D01*
G01X116519Y956142D02*
X116517Y956140D01*
G01X102106Y1009337D02*
Y1009344D01*
G01X102105Y1009332D02*
X102106Y1009337D01*
G01X102104Y1009331D02*
X102105Y1009332D01*
G01X102106Y1006187D02*
Y1006194D01*
G01X102105Y1006183D02*
X102106Y1006187D01*
G01X102104Y1006181D02*
X102105Y1006183D01*
G01X102106Y1003037D02*
Y1003045D01*
G01X102105Y1003033D02*
X102106Y1003037D01*
G01X102104Y1003031D02*
X102105Y1003033D01*
G01X102106Y999888D02*
Y999895D01*
G01X102105Y999883D02*
X102106Y999888D01*
G01X102104Y999882D02*
X102105Y999883D01*
G01X102106Y996738D02*
Y996746D01*
G01X102105Y996734D02*
X102106Y996738D01*
G01X102104Y996732D02*
X102105Y996734D01*
G01X102106Y993589D02*
Y993596D01*
G01X102105Y993584D02*
X102106Y993589D01*
G01X102104Y993583D02*
X102105Y993584D01*
G01X102106Y990439D02*
Y990446D01*
G01X102105Y990435D02*
X102106Y990439D01*
G01X102104Y990433D02*
X102105Y990435D01*
G01X103088Y1008202D02*
X103091Y1008215D01*
G01X103081Y1008191D02*
X103088Y1008202D01*
G01X103071Y1008183D02*
X103081Y1008191D01*
G01X103088Y1001903D02*
X103091Y1001915D01*
G01X103081Y1001892D02*
X103088Y1001903D01*
G01X103071Y1001884D02*
X103081Y1001892D01*
G01X102124Y998745D02*
X102143Y998740D01*
G01X102111Y998757D02*
X102124Y998745D01*
G01X102104Y998775D02*
X102111Y998757D01*
G01X116498Y957515D02*
X116479Y957520D01*
G01X116513Y957500D02*
X116498Y957515D01*
G01X116518Y957480D02*
X116513Y957500D01*
G01X116498Y962515D02*
X116479Y962520D01*
G01X116513Y962500D02*
X116498Y962515D01*
G01X116518Y962480D02*
X116513Y962500D01*
G01X116498Y967515D02*
X116479Y967520D01*
G01X116513Y967500D02*
X116498Y967515D01*
G01X116518Y967480D02*
X116513Y967500D01*
G01X116498Y972515D02*
X116479Y972520D01*
G01X116513Y972500D02*
X116498Y972515D01*
G01X116518Y972480D02*
X116513Y972500D01*
G01X116498Y977515D02*
X116479Y977520D01*
G01X116513Y977500D02*
X116498Y977515D01*
G01X116518Y977480D02*
X116513Y977500D01*
G01X116498Y982515D02*
X116479Y982520D01*
G01X116513Y982500D02*
X116498Y982515D01*
G01X116518Y982480D02*
X116513Y982500D01*
G01X116498Y987515D02*
X116479Y987520D01*
G01X116513Y987500D02*
X116498Y987515D01*
G01X116518Y987480D02*
X116513Y987500D01*
G01X116498Y1012515D02*
X116479Y1012520D01*
G01X116513Y1012500D02*
X116498Y1012515D01*
G01X116518Y1012480D02*
X116513Y1012500D01*
G01X116498Y1017515D02*
X116479Y1017520D01*
G01X116513Y1017500D02*
X116498Y1017515D01*
G01X116518Y1017480D02*
X116513Y1017500D01*
G01X116498Y1022515D02*
X116479Y1022520D01*
G01X116513Y1022500D02*
X116498Y1022515D01*
G01X116518Y1022480D02*
X116513Y1022500D01*
G01X116498Y1027515D02*
X116479Y1027520D01*
G01X116513Y1027500D02*
X116498Y1027515D01*
G01X116518Y1027480D02*
X116513Y1027500D01*
G01X116498Y1032515D02*
X116479Y1032520D01*
G01X116513Y1032500D02*
X116498Y1032515D01*
G01X116518Y1032480D02*
X116513Y1032500D01*
G01X116498Y1037515D02*
X116479Y1037520D01*
G01X116513Y1037500D02*
X116498Y1037515D01*
G01X116518Y1037480D02*
X116513Y1037500D01*
G01X116498Y1042515D02*
X116479Y1042520D01*
G01X116513Y1042500D02*
X116498Y1042515D01*
G01X116518Y1042480D02*
X116513Y1042500D01*
G01X116498Y1047515D02*
X116479Y1047520D01*
G01X116513Y1047500D02*
X116498Y1047515D01*
G01X116518Y1047480D02*
X116513Y1047500D01*
G01X103088Y998754D02*
X103091Y998766D01*
G01X103081Y998742D02*
X103088Y998754D01*
G01X103071Y998734D02*
X103081Y998742D01*
G01X103088Y995604D02*
X103091Y995616D01*
G01X103081Y995593D02*
X103088Y995604D01*
G01X103071Y995585D02*
X103081Y995593D01*
G01X103088Y992454D02*
X103091Y992467D01*
G01X103081Y992443D02*
X103088Y992454D01*
G01X103071Y992435D02*
X103081Y992443D01*
G01X103088Y989305D02*
X103091Y989317D01*
G01X103081Y989293D02*
X103088Y989305D01*
G01X103071Y989285D02*
X103081Y989293D01*
G01X102145Y1009375D02*
Y1009381D01*
G01Y1009371D02*
Y1009375D01*
G01X102143Y1009370D02*
X102145Y1009371D01*
G01Y1006225D02*
Y1006231D01*
G01Y1006222D02*
Y1006225D01*
G01X102143Y1006220D02*
X102145Y1006222D01*
G01Y1003076D02*
Y1003082D01*
G01Y1003072D02*
Y1003076D01*
G01X102143Y1003071D02*
X102145Y1003072D01*
G01Y999926D02*
Y999932D01*
G01Y999922D02*
Y999926D01*
G01X102143Y999921D02*
X102145Y999922D01*
G01Y996776D02*
Y996783D01*
G01Y996773D02*
Y996776D01*
G01X102143Y996772D02*
X102145Y996773D01*
G01Y993627D02*
Y993633D01*
G01Y993623D02*
Y993627D01*
G01X102143Y993622D02*
X102145Y993623D01*
G01Y990477D02*
Y990483D01*
G01Y990474D02*
Y990477D01*
G01X102143Y990472D02*
X102145Y990474D01*
G01X102107Y1009350D02*
X102106Y1009344D01*
G01X102109Y1009357D02*
X102107Y1009350D01*
G01X102111Y1009363D02*
X102109Y1009357D01*
G01X102115Y1009368D02*
X102111Y1009363D01*
G01X102120Y1009372D02*
X102115Y1009368D01*
G01X102126Y1009376D02*
X102120Y1009372D01*
G01X102107Y1006201D02*
X102106Y1006194D01*
G01X102109Y1006207D02*
X102107Y1006201D01*
G01X102111Y1006213D02*
X102109Y1006207D01*
G01X102115Y1006218D02*
X102111Y1006213D01*
G01X102120Y1006223D02*
X102115Y1006218D01*
G01X102126Y1006226D02*
X102120Y1006223D01*
G01X102107Y1003051D02*
X102106Y1003045D01*
G01X102109Y1003057D02*
X102107Y1003051D01*
G01X102111Y1003063D02*
X102109Y1003057D01*
G01X102115Y1003069D02*
X102111Y1003063D01*
G01X102120Y1003073D02*
X102115Y1003069D01*
G01X102126Y1003077D02*
X102120Y1003073D01*
G01X102107Y999902D02*
X102106Y999895D01*
G01X102109Y999908D02*
X102107Y999902D01*
G01X102111Y999914D02*
X102109Y999908D01*
G01X102115Y999919D02*
X102111Y999914D01*
G01X102120Y999924D02*
X102115Y999919D01*
G01X102126Y999927D02*
X102120Y999924D01*
G01X102107Y996752D02*
X102106Y996746D01*
G01X102109Y996758D02*
X102107Y996752D01*
G01X102111Y996764D02*
X102109Y996758D01*
G01X102115Y996769D02*
X102111Y996764D01*
G01X102120Y996774D02*
X102115Y996769D01*
G01X102126Y996778D02*
X102120Y996774D01*
G01X102107Y993602D02*
X102106Y993596D01*
G01X102109Y993609D02*
X102107Y993602D01*
G01X102111Y993615D02*
X102109Y993609D01*
G01X102115Y993620D02*
X102111Y993615D01*
G01X102120Y993624D02*
X102115Y993620D01*
G01X102126Y993628D02*
X102120Y993624D01*
G01X102107Y990453D02*
X102106Y990446D01*
G01X102109Y990459D02*
X102107Y990453D01*
G01X102111Y990465D02*
X102109Y990459D01*
G01X102115Y990470D02*
X102111Y990465D01*
G01X102120Y990475D02*
X102115Y990470D01*
G01X102126Y990478D02*
X102120Y990475D01*
G01X102128Y989294D02*
X102143Y989291D01*
G01X102115Y989303D02*
X102128Y989294D01*
G01X102105Y989323D02*
X102115Y989303D01*
G01X103090Y990453D02*
X103091Y990446D01*
G01X103088Y990459D02*
X103090Y990453D01*
G01X103085Y990465D02*
X103088Y990459D01*
G01X103090Y993603D02*
X103091Y993596D01*
G01X103088Y993609D02*
X103090Y993603D01*
G01X103085Y993615D02*
X103088Y993609D01*
G01X103090Y996752D02*
X103091Y996746D01*
G01X103088Y996759D02*
X103090Y996752D01*
G01X103085Y996765D02*
X103088Y996759D01*
G01X103090Y999902D02*
X103091Y999895D01*
G01X103088Y999908D02*
X103090Y999902D01*
G01X103085Y999914D02*
X103088Y999908D01*
G01X103090Y1003052D02*
X103091Y1003045D01*
G01X103088Y1003058D02*
X103090Y1003052D01*
G01X103085Y1003064D02*
X103088Y1003058D01*
G01X103090Y1006201D02*
X103091Y1006194D01*
G01X103088Y1006207D02*
X103090Y1006201D01*
G01X103085Y1006213D02*
X103088Y1006207D01*
G01X103090Y1009351D02*
X103091Y1009344D01*
G01X103088Y1009357D02*
X103090Y1009351D01*
G01X103085Y1009363D02*
X103088Y1009357D01*
G01X103052Y989286D02*
Y989280D01*
G01X103050Y989290D02*
X103052Y989286D01*
G01X103050Y989291D02*
Y989290D01*
G01X103052Y992436D02*
Y992430D01*
G01X103050Y992439D02*
X103052Y992436D01*
G01X103050Y992441D02*
Y992439D01*
G01X103052Y995585D02*
Y995579D01*
G01X103050Y995589D02*
X103052Y995585D01*
G01X103050Y995591D02*
Y995589D01*
G01X103052Y998735D02*
Y998729D01*
G01X103050Y998739D02*
X103052Y998735D01*
G01X103050Y998740D02*
Y998739D01*
G01X103052Y1001885D02*
Y1001878D01*
G01X103050Y1001888D02*
X103052Y1001885D01*
G01X103050Y1001890D02*
Y1001888D01*
G01X103052Y1008184D02*
Y1008178D01*
G01X103050Y1008187D02*
X103052Y1008184D01*
G01X103050Y1008189D02*
Y1008187D01*
G01X115531Y957527D02*
Y957536D01*
G01X115532Y957521D02*
X115531Y957527D01*
G01X115533Y957520D02*
X115532Y957521D01*
G01X115531Y962527D02*
Y962536D01*
G01X115532Y962521D02*
X115531Y962527D01*
G01X115533Y962520D02*
X115532Y962521D01*
G01X115531Y967527D02*
Y967536D01*
G01X115532Y967521D02*
X115531Y967527D01*
G01X115533Y967520D02*
X115532Y967521D01*
G01X115531Y972527D02*
Y972536D01*
G01X115532Y972521D02*
X115531Y972527D01*
G01X115533Y972520D02*
X115532Y972521D01*
G01X115531Y977527D02*
Y977536D01*
G01X115532Y977521D02*
X115531Y977527D01*
G01X115533Y977520D02*
X115532Y977521D01*
G01X115531Y982527D02*
Y982536D01*
G01X115532Y982521D02*
X115531Y982527D01*
G01X115533Y982520D02*
X115532Y982521D01*
G01X115531Y987527D02*
Y987536D01*
G01X115532Y987521D02*
X115531Y987527D01*
G01X115533Y987520D02*
X115532Y987521D01*
G01X115531Y1012527D02*
Y1012536D01*
G01X115532Y1012521D02*
X115531Y1012527D01*
G01X115533Y1012520D02*
X115532Y1012521D01*
G01X115531Y1017527D02*
Y1017536D01*
G01X115532Y1017521D02*
X115531Y1017527D01*
G01X115533Y1017520D02*
X115532Y1017521D01*
G01X115531Y1022527D02*
Y1022536D01*
G01X115532Y1022521D02*
X115531Y1022527D01*
G01X115533Y1022520D02*
X115532Y1022521D01*
G01X115531Y1027527D02*
Y1027536D01*
G01X115532Y1027521D02*
X115531Y1027527D01*
G01X115533Y1027520D02*
X115532Y1027521D01*
G01X115531Y1032527D02*
Y1032536D01*
G01X115532Y1032521D02*
X115531Y1032527D01*
G01X115533Y1032520D02*
X115532Y1032521D01*
G01X115531Y1037527D02*
Y1037536D01*
G01X115532Y1037521D02*
X115531Y1037527D01*
G01X115533Y1037520D02*
X115532Y1037521D01*
G01X115531Y1042527D02*
Y1042536D01*
G01X115532Y1042521D02*
X115531Y1042527D01*
G01X115533Y1042520D02*
X115532Y1042521D01*
G01X115533Y1047520D02*
X115532Y1047521D01*
G01X116508Y957663D02*
X116516Y957637D01*
G01X116498Y957690D02*
X116508Y957663D01*
G01X116487Y957717D02*
X116498Y957690D01*
G01X116508Y962663D02*
X116516Y962637D01*
G01X116498Y962690D02*
X116508Y962663D01*
G01X116487Y962717D02*
X116498Y962690D01*
G01X116508Y967663D02*
X116516Y967637D01*
G01X116498Y967690D02*
X116508Y967663D01*
G01X116487Y967717D02*
X116498Y967690D01*
G01X116508Y972663D02*
X116516Y972637D01*
G01X116498Y972690D02*
X116508Y972663D01*
G01X116487Y972717D02*
X116498Y972690D01*
G01X116508Y977663D02*
X116516Y977637D01*
G01X116498Y977690D02*
X116508Y977663D01*
G01X116487Y977717D02*
X116498Y977690D01*
G01X116508Y982663D02*
X116516Y982637D01*
G01X116498Y982690D02*
X116508Y982663D01*
G01X116487Y982717D02*
X116498Y982690D01*
G01X116508Y987663D02*
X116516Y987637D01*
G01X116498Y987690D02*
X116508Y987663D01*
G01X116487Y987717D02*
X116498Y987690D01*
G01X116508Y1012663D02*
X116516Y1012637D01*
G01X116498Y1012690D02*
X116508Y1012663D01*
G01X116487Y1012717D02*
X116498Y1012690D01*
G01X116508Y1017663D02*
X116516Y1017637D01*
G01X116498Y1017690D02*
X116508Y1017663D01*
G01X116487Y1017717D02*
X116498Y1017690D01*
G01X116508Y1022663D02*
X116516Y1022637D01*
G01X116498Y1022690D02*
X116508Y1022663D01*
G01X116487Y1022717D02*
X116498Y1022690D01*
G01X116508Y1027663D02*
X116516Y1027637D01*
G01X116498Y1027690D02*
X116508Y1027663D01*
G01X116487Y1027717D02*
X116498Y1027690D01*
G01X116508Y1032663D02*
X116516Y1032637D01*
G01X116498Y1032690D02*
X116508Y1032663D01*
G01X116487Y1032717D02*
X116498Y1032690D01*
G01X116508Y1037663D02*
X116516Y1037637D01*
G01X116498Y1037690D02*
X116508Y1037663D01*
G01X116487Y1037717D02*
X116498Y1037690D01*
G01X116508Y1042663D02*
X116516Y1042637D01*
G01X116498Y1042690D02*
X116508Y1042663D01*
G01X116487Y1042717D02*
X116498Y1042690D01*
G01X103062Y1008191D02*
X103050Y1008189D01*
G01X103072Y1008196D02*
X103062Y1008191D01*
G01Y1005041D02*
X103050Y1005039D01*
G01X103072Y1005046D02*
X103062Y1005041D01*
G01Y1001892D02*
X103050Y1001890D01*
G01X103072Y1001896D02*
X103062Y1001892D01*
G01Y998742D02*
X103050Y998740D01*
G01X103072Y998747D02*
X103062Y998742D01*
G01Y995593D02*
X103050Y995591D01*
G01X103072Y995597D02*
X103062Y995593D01*
G01Y992443D02*
X103050Y992441D01*
G01X103072Y992448D02*
X103062Y992443D01*
G01Y989293D02*
X103050Y989291D01*
G01X103072Y989298D02*
X103062Y989293D01*
G01X102129Y992443D02*
X102143Y992441D01*
G01X102118Y992450D02*
X102129Y992443D01*
G01X102106Y992469D02*
X102118Y992450D01*
G01X102129Y1001892D02*
X102143Y1001890D01*
G01X102117Y1001900D02*
X102129Y1001892D01*
G01X102106Y1001918D02*
X102117Y1001900D01*
G01X102129Y995593D02*
X102143Y995591D01*
G01X102117Y995601D02*
X102129Y995593D01*
G01X102105Y995621D02*
X102117Y995601D01*
G01X102129Y1005042D02*
X102143Y1005039D01*
G01X102117Y1005050D02*
X102129Y1005042D01*
G01X102105Y1005070D02*
X102117Y1005050D01*
G01X103091Y989325D02*
Y989317D01*
G01X103090Y989329D02*
X103091Y989325D01*
G01X103089Y989331D02*
X103090Y989329D01*
G01X103091Y992474D02*
Y992467D01*
G01X103090Y992479D02*
X103091Y992474D01*
G01X103089Y992480D02*
X103090Y992479D01*
G01X103091Y995624D02*
Y995616D01*
G01X103090Y995628D02*
X103091Y995624D01*
G01X103089Y995630D02*
X103090Y995628D01*
G01X103091Y998774D02*
Y998766D01*
G01X103090Y998778D02*
X103091Y998774D01*
G01X103089Y998780D02*
X103090Y998778D01*
G01X103091Y1001923D02*
Y1001915D01*
G01X103090Y1001928D02*
X103091Y1001923D01*
G01X103089Y1001929D02*
X103090Y1001928D01*
G01X103091Y1005073D02*
Y1005065D01*
G01X103090Y1005077D02*
X103091Y1005073D01*
G01X103089Y1005079D02*
X103090Y1005077D01*
G01X103091Y1008222D02*
Y1008215D01*
G01X103090Y1008227D02*
X103091Y1008222D01*
G01X103089Y1008228D02*
X103090Y1008227D01*
G01X102129Y1008192D02*
X102143Y1008189D01*
G01X102116Y1008200D02*
X102129Y1008192D01*
G01X102105Y1008220D02*
X102116Y1008200D01*
G01X116516Y957487D02*
Y957494D01*
G01X116517Y957482D02*
X116516Y957487D01*
G01X116518Y957480D02*
X116517Y957482D01*
G01X116516Y962487D02*
Y962494D01*
G01X116517Y962482D02*
X116516Y962487D01*
G01X116518Y962480D02*
X116517Y962482D01*
G01X116516Y967487D02*
Y967494D01*
G01X116517Y967482D02*
X116516Y967487D01*
G01X116518Y967480D02*
X116517Y967482D01*
G01X116516Y972487D02*
Y972494D01*
G01X116517Y972482D02*
X116516Y972487D01*
G01X116518Y972480D02*
X116517Y972482D01*
G01X116516Y977487D02*
Y977494D01*
G01X116517Y977482D02*
X116516Y977487D01*
G01X116518Y977480D02*
X116517Y977482D01*
G01X116516Y982487D02*
Y982494D01*
G01X116517Y982482D02*
X116516Y982487D01*
G01X116518Y982480D02*
X116517Y982482D01*
G01X116516Y987487D02*
Y987494D01*
G01X116517Y987482D02*
X116516Y987487D01*
G01X116518Y987480D02*
X116517Y987482D01*
G01X116516Y1012487D02*
Y1012494D01*
G01X116517Y1012482D02*
X116516Y1012487D01*
G01X116518Y1012480D02*
X116517Y1012482D01*
G01X116516Y1017487D02*
Y1017494D01*
G01X116517Y1017482D02*
X116516Y1017487D01*
G01X116518Y1017480D02*
X116517Y1017482D01*
G01X116516Y1022487D02*
Y1022494D01*
G01X116517Y1022482D02*
X116516Y1022487D01*
G01X116518Y1022480D02*
X116517Y1022482D01*
G01X116516Y1027487D02*
Y1027494D01*
G01X116517Y1027482D02*
X116516Y1027487D01*
G01X116518Y1027480D02*
X116517Y1027482D01*
G01X116516Y1032487D02*
Y1032494D01*
G01X116517Y1032482D02*
X116516Y1032487D01*
G01X116518Y1032480D02*
X116517Y1032482D01*
G01X116516Y1037487D02*
Y1037494D01*
G01X116517Y1037482D02*
X116516Y1037487D01*
G01X116518Y1037480D02*
X116517Y1037482D01*
G01X116516Y1042487D02*
Y1042494D01*
G01X116517Y1042482D02*
X116516Y1042487D01*
G01X116518Y1042480D02*
X116517Y1042482D01*
G01Y1047482D02*
X116516Y1047487D01*
G01X116518Y1047480D02*
X116517Y1047482D01*
G01X102145Y989286D02*
X102146Y989280D01*
G01X102144Y989290D02*
X102145Y989286D01*
G01X102143Y989291D02*
X102144Y989290D01*
G01X102145Y992436D02*
X102146Y992430D01*
G01X102144Y992440D02*
X102145Y992436D01*
G01X102143Y992441D02*
X102144Y992440D01*
G01X102145Y995585D02*
X102146Y995579D01*
G01X102144Y995589D02*
X102145Y995585D01*
G01X102143Y995591D02*
X102144Y995589D01*
G01X102145Y998735D02*
X102146Y998729D01*
G01X102144Y998739D02*
X102145Y998735D01*
G01X102143Y998740D02*
X102144Y998739D01*
G01X102145Y1001885D02*
X102146Y1001878D01*
G01X102144Y1001889D02*
X102145Y1001885D01*
G01X102143Y1001890D02*
X102144Y1001889D01*
G01X102145Y1005034D02*
X102146Y1005028D01*
G01X102144Y1005038D02*
X102145Y1005034D01*
G01X102143Y1005039D02*
X102144Y1005038D01*
G01X102145Y1008184D02*
X102146Y1008178D01*
G01X102144Y1008188D02*
X102145Y1008184D01*
G01X102143Y1008189D02*
X102144Y1008188D01*
G01X103059Y996770D02*
X103050Y996772D01*
G01X103068Y996767D02*
X103059Y996770D01*
G01X103076Y996762D02*
X103068Y996767D01*
G01X103059Y990471D02*
X103050Y990472D01*
G01X103068Y990468D02*
X103059Y990471D01*
G01X103076Y990463D02*
X103068Y990468D01*
G01X103059Y993621D02*
X103050Y993622D01*
G01X103068Y993618D02*
X103059Y993621D01*
G01X103076Y993612D02*
X103068Y993618D01*
G01X103059Y999920D02*
X103050Y999921D01*
G01X103068Y999917D02*
X103059Y999920D01*
G01X103076Y999911D02*
X103068Y999917D01*
G01X103059Y1003070D02*
X103050Y1003071D01*
G01X103068Y1003067D02*
X103059Y1003070D01*
G01X103076Y1003061D02*
X103068Y1003067D01*
G01X103059Y1006219D02*
X103050Y1006220D01*
G01X103068Y1006216D02*
X103059Y1006219D01*
G01X103076Y1006211D02*
X103068Y1006216D01*
G01X103059Y1009369D02*
X103050Y1009370D01*
G01X103068Y1009366D02*
X103059Y1009369D01*
G01X103076Y1009360D02*
X103068Y1009366D01*
G01X116503Y957511D02*
X116514Y957496D01*
G01X116479Y957520D02*
X116503Y957511D01*
G01Y962511D02*
X116514Y962496D01*
G01X116479Y962520D02*
X116503Y962511D01*
G01Y967511D02*
X116514Y967496D01*
G01X116479Y967520D02*
X116503Y967511D01*
G01Y972511D02*
X116514Y972496D01*
G01X116479Y972520D02*
X116503Y972511D01*
G01Y977511D02*
X116514Y977496D01*
G01X116479Y977520D02*
X116503Y977511D01*
G01Y982511D02*
X116514Y982496D01*
G01X116479Y982520D02*
X116503Y982511D01*
G01X102106Y998770D02*
Y998766D01*
G01X102108Y998764D02*
X102106Y998770D01*
G01X102118Y998750D02*
X102108Y998764D01*
G01X102141Y998740D02*
X102118Y998750D01*
G01X102106Y992470D02*
Y992467D01*
G01X102108Y992464D02*
X102106Y992470D01*
G01X102120Y992449D02*
X102108Y992464D01*
G01X102144Y992441D02*
X102120Y992449D01*
G01X102106Y995620D02*
Y995616D01*
G01X102108Y995614D02*
X102106Y995620D01*
G01X102119Y995599D02*
X102108Y995614D01*
G01X102144Y995591D02*
X102119Y995599D01*
G01X102106Y1001919D02*
Y1001915D01*
G01X102108Y1001913D02*
X102106Y1001919D01*
G01X102119Y1001898D02*
X102108Y1001913D01*
G01X102144Y1001890D02*
X102119Y1001898D01*
G01X102106Y1005069D02*
Y1005065D01*
G01X102108Y1005063D02*
X102106Y1005069D01*
G01X102119Y1005048D02*
X102108Y1005063D01*
G01X102144Y1005039D02*
X102119Y1005048D01*
G01X102106Y989321D02*
Y989317D01*
G01X102108Y989315D02*
X102106Y989321D01*
G01X102119Y989300D02*
X102108Y989315D01*
G01X102144Y989291D02*
X102119Y989300D01*
G01X102106Y1008219D02*
Y1008215D01*
G01X102108Y1008213D02*
X102106Y1008219D01*
G01X102119Y1008197D02*
X102108Y1008213D01*
G01X102144Y1008189D02*
X102119Y1008197D01*
G01X116503Y987511D02*
X116514Y987496D01*
G01X116479Y987520D02*
X116503Y987511D01*
G01Y1012511D02*
X116514Y1012496D01*
G01X116479Y1012520D02*
X116503Y1012511D01*
G01Y1017511D02*
X116514Y1017496D01*
G01X116479Y1017520D02*
X116503Y1017511D01*
G01Y1022511D02*
X116514Y1022496D01*
G01X116479Y1022520D02*
X116503Y1022511D01*
G01Y1027511D02*
X116514Y1027496D01*
G01X116479Y1027520D02*
X116503Y1027511D01*
G01Y1032511D02*
X116514Y1032496D01*
G01X116479Y1032520D02*
X116503Y1032511D01*
G01Y1037511D02*
X116514Y1037496D01*
G01X116479Y1037520D02*
X116503Y1037511D01*
G01Y1042511D02*
X116514Y1042496D01*
G01X116479Y1042520D02*
X116503Y1042511D01*
G01Y1047511D02*
X116514Y1047496D01*
G01X116479Y1047520D02*
X116503Y1047511D01*
G01X103081Y990471D02*
X103085Y990465D01*
G01X103076Y990475D02*
X103081Y990471D01*
G01X103070Y990479D02*
X103076Y990475D01*
G01X103065Y990481D02*
X103070Y990479D01*
G01X103058Y990483D02*
X103065Y990481D01*
G01X103051Y990483D02*
X103058D01*
G01X103081Y993620D02*
X103085Y993615D01*
G01X103076Y993625D02*
X103081Y993620D01*
G01X103070Y993628D02*
X103076Y993625D01*
G01X103065Y993631D02*
X103070Y993628D01*
G01X103058Y993633D02*
X103065Y993631D01*
G01X103051Y993633D02*
X103058D01*
G01X103081Y996770D02*
X103085Y996765D01*
G01X103076Y996774D02*
X103081Y996770D01*
G01X103070Y996778D02*
X103076Y996774D01*
G01X103065Y996781D02*
X103070Y996778D01*
G01X103058Y996782D02*
X103065Y996781D01*
G01X103051Y996783D02*
X103058Y996782D01*
G01X103081Y999920D02*
X103085Y999914D01*
G01X103076Y999924D02*
X103081Y999920D01*
G01X103070Y999928D02*
X103076Y999924D01*
G01X103065Y999930D02*
X103070Y999928D01*
G01X103058Y999932D02*
X103065Y999930D01*
G01X103051Y999932D02*
X103058D01*
G01X103081Y1003069D02*
X103085Y1003064D01*
G01X103076Y1003074D02*
X103081Y1003069D01*
G01X103070Y1003077D02*
X103076Y1003074D01*
G01X103065Y1003080D02*
X103070Y1003077D01*
G01X103058Y1003081D02*
X103065Y1003080D01*
G01X103051Y1003082D02*
X103058Y1003081D01*
G01X103081Y1006219D02*
X103085Y1006213D01*
G01X103076Y1006223D02*
X103081Y1006219D01*
G01X103070Y1006227D02*
X103076Y1006223D01*
G01X103065Y1006230D02*
X103070Y1006227D01*
G01X103058Y1006231D02*
X103065Y1006230D01*
G01X103051Y1006231D02*
X103058D01*
G01X102107Y989310D02*
X102106Y989317D01*
G01X102109Y989303D02*
X102107Y989310D01*
G01X102113Y989296D02*
X102109Y989303D01*
G01X102118Y989291D02*
X102113Y989296D01*
G01X102124Y989286D02*
X102118Y989291D01*
G01X102131Y989283D02*
X102124Y989286D01*
G01X102138Y989281D02*
X102131Y989283D01*
G01X102146Y989280D02*
X102138Y989281D01*
G01X102107Y992459D02*
X102106Y992467D01*
G01X102109Y992452D02*
X102107Y992459D01*
G01X102113Y992446D02*
X102109Y992452D01*
G01X102118Y992441D02*
X102113Y992446D01*
G01X102124Y992436D02*
X102118Y992441D01*
G01X102131Y992432D02*
X102124Y992436D01*
G01X102138Y992430D02*
X102131Y992432D01*
G01X102146Y992430D02*
X102138D01*
G01X102107Y995609D02*
X102106Y995616D01*
G01X102109Y995602D02*
X102107Y995609D01*
G01X102113Y995596D02*
X102109Y995602D01*
G01X102118Y995590D02*
X102113Y995596D01*
G01X102124Y995585D02*
X102118Y995590D01*
G01X102131Y995582D02*
X102124Y995585D01*
G01X102138Y995580D02*
X102131Y995582D01*
G01X102146Y995579D02*
X102138Y995580D01*
G01X102107Y998759D02*
X102106Y998766D01*
G01X102109Y998752D02*
X102107Y998759D01*
G01X102113Y998745D02*
X102109Y998752D01*
G01X102118Y998740D02*
X102113Y998745D01*
G01X102124Y998735D02*
X102118Y998740D01*
G01X102131Y998731D02*
X102124Y998735D01*
G01X102138Y998730D02*
X102131Y998731D01*
G01X102146Y998729D02*
X102138Y998730D01*
G01X102107Y1001908D02*
X102106Y1001915D01*
G01X102109Y1001901D02*
X102107Y1001908D01*
G01X102113Y1001895D02*
X102109Y1001901D01*
G01X102118Y1001889D02*
X102113Y1001895D01*
G01X102124Y1001885D02*
X102118Y1001889D01*
G01X102131Y1001881D02*
X102124Y1001885D01*
G01X102138Y1001879D02*
X102131Y1001881D01*
G01X102146Y1001878D02*
X102138Y1001879D01*
G01X102107Y1005058D02*
X102106Y1005065D01*
G01X102109Y1005051D02*
X102107Y1005058D01*
G01X102113Y1005044D02*
X102109Y1005051D01*
G01X102118Y1005039D02*
X102113Y1005044D01*
G01X102124Y1005034D02*
X102118Y1005039D01*
G01X102131Y1005031D02*
X102124Y1005034D01*
G01X102138Y1005029D02*
X102131Y1005031D01*
G01X102146Y1005028D02*
X102138Y1005029D01*
G01X102107Y1008207D02*
X102106Y1008215D01*
G01X102109Y1008200D02*
X102107Y1008207D01*
G01X102113Y1008194D02*
X102109Y1008200D01*
G01X102118Y1008189D02*
X102113Y1008194D01*
G01X102124Y1008184D02*
X102118Y1008189D01*
G01X102131Y1008180D02*
X102124Y1008184D01*
G01X102138Y1008178D02*
X102131Y1008180D01*
G01X102146Y1008178D02*
X102138D01*
G01X103060Y990471D02*
X103070Y990467D01*
G01X103050Y990472D02*
X103060Y990471D01*
G01Y993620D02*
X103070Y993617D01*
G01X103050Y993622D02*
X103060Y993620D01*
G01Y996770D02*
X103070Y996766D01*
G01X103050Y996772D02*
X103060Y996770D01*
G01Y999920D02*
X103070Y999916D01*
G01X103050Y999921D02*
X103060Y999920D01*
G01Y1003069D02*
X103070Y1003065D01*
G01X103050Y1003071D02*
X103060Y1003069D01*
G01Y1006219D02*
X103070Y1006215D01*
G01X103050Y1006220D02*
X103060Y1006219D01*
G01Y1009369D02*
X103070Y1009365D01*
G01X103050Y1009370D02*
X103060Y1009369D01*
G01X101359Y992480D02*
X100925D01*
G01X101733D02*
X101359D01*
G01Y998780D02*
X100925D01*
G01X101733D02*
X101359D01*
G01Y1001929D02*
X100925D01*
G01X101733D02*
X101359D01*
G01X103081Y1009369D02*
X103085Y1009363D01*
G01X103076Y1009373D02*
X103081Y1009369D01*
G01X103070Y1009376D02*
X103076Y1009373D01*
G01X103065Y1009379D02*
X103070Y1009376D01*
G01X103058Y1009381D02*
X103065Y1009379D01*
G01X103051Y1009381D02*
X103058D01*
G01X103090Y1005058D02*
X103091Y1005065D01*
G01X103087Y1005051D02*
X103090Y1005058D01*
G01X103084Y1005044D02*
X103087Y1005051D01*
G01X103079Y1005039D02*
X103084Y1005044D01*
G01X103073Y1005034D02*
X103079Y1005039D01*
G01X103066Y1005031D02*
X103073Y1005034D01*
G01X103059Y1005029D02*
X103066Y1005031D01*
G01X103051Y1005028D02*
X103059Y1005029D01*
G01X103068Y989283D02*
X103071Y989285D01*
G01X103065Y989282D02*
X103068Y989283D01*
G01X103062Y989281D02*
X103065Y989282D01*
G01X103058Y989281D02*
X103062D01*
G01X103055Y989280D02*
X103058Y989281D01*
G01X103051Y989280D02*
X103055D01*
G01X102129Y990480D02*
X102126Y990478D01*
G01X102132Y990481D02*
X102129Y990480D01*
G01X102135Y990482D02*
X102132Y990481D01*
G01X102139Y990483D02*
X102135Y990482D01*
G01X102142Y990483D02*
X102139D01*
G01X102146D02*
X102142D01*
G01X103068Y992433D02*
X103071Y992435D01*
G01X103065Y992432D02*
X103068Y992433D01*
G01X103062Y992431D02*
X103065Y992432D01*
G01X103058Y992430D02*
X103062Y992431D01*
G01X103055Y992430D02*
X103058D01*
G01X103051D02*
X103055D01*
G01X102129Y993630D02*
X102126Y993628D01*
G01X102132Y993631D02*
X102129Y993630D01*
G01X102135Y993632D02*
X102132Y993631D01*
G01X102139Y993633D02*
X102135Y993632D01*
G01X102142Y993633D02*
X102139D01*
G01X102146D02*
X102142D01*
G01X103068Y995583D02*
X103071Y995585D01*
G01X103065Y995581D02*
X103068Y995583D01*
G01X103062Y995581D02*
X103065D01*
G01X103058Y995580D02*
X103062Y995581D01*
G01X103055Y995580D02*
X103058D01*
G01X103051Y995579D02*
X103055Y995580D01*
G01X102129Y996779D02*
X102126Y996778D01*
G01X102132Y996780D02*
X102129Y996779D01*
G01X102135Y996781D02*
X102132Y996780D01*
G01X102139Y996782D02*
X102135Y996781D01*
G01X102142Y996783D02*
X102139Y996782D01*
G01X102146Y996783D02*
X102142D01*
G01X103068Y998732D02*
X103071Y998734D01*
G01X103065Y998731D02*
X103068Y998732D01*
G01X103062Y998730D02*
X103065Y998731D01*
G01X103058Y998730D02*
X103062D01*
G01X103055Y998729D02*
X103058Y998730D01*
G01X103051Y998729D02*
X103055D01*
G01X102129Y999929D02*
X102126Y999927D01*
G01X102132Y999930D02*
X102129Y999929D01*
G01X102135Y999931D02*
X102132Y999930D01*
G01X102139Y999932D02*
X102135Y999931D01*
G01X102142Y999932D02*
X102139D01*
G01X102146D02*
X102142D01*
G01X103068Y1001882D02*
X103071Y1001884D01*
G01X103065Y1001881D02*
X103068Y1001882D01*
G01X103062Y1001880D02*
X103065Y1001881D01*
G01X103058Y1001879D02*
X103062Y1001880D01*
G01X103055Y1001879D02*
X103058D01*
G01X103051Y1001878D02*
X103055Y1001879D01*
G01X102129Y1003078D02*
X102126Y1003077D01*
G01X102132Y1003080D02*
X102129Y1003078D01*
G01X102135Y1003081D02*
X102132Y1003080D01*
G01X102139Y1003081D02*
X102135D01*
G01X102142Y1003082D02*
X102139Y1003081D01*
G01X102146Y1003082D02*
X102142D01*
G01X102129Y1006228D02*
X102126Y1006226D01*
G01X102132Y1006229D02*
X102129Y1006228D01*
G01X102135Y1006230D02*
X102132Y1006229D01*
G01X102139Y1006231D02*
X102135Y1006230D01*
G01X102142Y1006231D02*
X102139D01*
G01X102146D02*
X102142D01*
G01X103068Y1008181D02*
X103071Y1008183D01*
G01X103065Y1008180D02*
X103068Y1008181D01*
G01X103062Y1008179D02*
X103065Y1008180D01*
G01X103058Y1008178D02*
X103062Y1008179D01*
G01X103055Y1008178D02*
X103058D01*
G01X103051D02*
X103055D01*
G01X102129Y1009378D02*
X102126Y1009376D01*
G01X102132Y1009379D02*
X102129Y1009378D01*
G01X102135Y1009380D02*
X102132Y1009379D01*
G01X102139Y1009381D02*
X102135Y1009380D01*
G01X102142Y1009381D02*
X102139D01*
G01X102146D02*
X102142D01*
G01X102109Y990453D02*
X102104Y990433D01*
G01X102124Y990467D02*
X102109Y990453D01*
G01X102143Y990472D02*
X102124Y990467D01*
G01X102109Y993602D02*
X102104Y993583D01*
G01X102124Y993617D02*
X102109Y993602D01*
G01X102143Y993622D02*
X102124Y993617D01*
G01X102109Y996752D02*
X102104Y996732D01*
G01X102124Y996766D02*
X102109Y996752D01*
G01X102143Y996772D02*
X102124Y996766D01*
G01X102109Y999902D02*
X102104Y999882D01*
G01X102124Y999916D02*
X102109Y999902D01*
G01X102143Y999921D02*
X102124Y999916D01*
G01X102109Y1003051D02*
X102104Y1003031D01*
G01X102124Y1003065D02*
X102109Y1003051D01*
G01X102143Y1003071D02*
X102124Y1003065D01*
G01X102109Y1006201D02*
X102104Y1006181D01*
G01X102124Y1006215D02*
X102109Y1006201D01*
G01X102143Y1006220D02*
X102124Y1006215D01*
G01X102109Y1009350D02*
X102104Y1009331D01*
G01X102124Y1009365D02*
X102109Y1009350D01*
G01X102143Y1009370D02*
X102124Y1009365D01*
G01X103084Y989311D02*
X103089Y989331D01*
G01X103069Y989296D02*
X103084Y989311D01*
G01X103050Y989291D02*
X103069Y989296D01*
G01X103084Y992461D02*
X103089Y992480D01*
G01X103069Y992446D02*
X103084Y992461D01*
G01X103050Y992441D02*
X103069Y992446D01*
G01X103084Y995610D02*
X103089Y995630D01*
G01X103069Y995596D02*
X103084Y995610D01*
G01X103050Y995591D02*
X103069Y995596D01*
G01X103084Y998760D02*
X103089Y998780D01*
G01X103069Y998745D02*
X103084Y998760D01*
G01X103050Y998740D02*
X103069Y998745D01*
G01X103084Y1001909D02*
X103089Y1001929D01*
G01X103069Y1001895D02*
X103084Y1001909D01*
G01X103050Y1001890D02*
X103069Y1001895D01*
G01X103084Y1005059D02*
X103089Y1005079D01*
G01X103069Y1005044D02*
X103084Y1005059D01*
G01X103050Y1005039D02*
X103069Y1005044D01*
G01X103084Y1008209D02*
X103089Y1008228D01*
G01X103069Y1008194D02*
X103084Y1008209D01*
G01X103050Y1008189D02*
X103069Y1008194D01*
G01X120866Y1046142D02*
X115533D01*
G01X115531Y1045650D02*
X116516D01*
G01Y1043012D02*
X115531D01*
G01X115533Y1042520D02*
X120866D01*
G01Y1042480D02*
X116518D01*
G01X120866Y1041142D02*
X115533D01*
G01X115531Y1040650D02*
X116516D01*
G01Y1038012D02*
X115531D01*
G01X115533Y1037520D02*
X120866D01*
G01Y1037480D02*
X116518D01*
G01X120866Y1036142D02*
X115533D01*
G01X115531Y1035650D02*
X116516D01*
G01Y1033012D02*
X115531D01*
G01X115533Y1032520D02*
X120866D01*
G01Y1032480D02*
X116518D01*
G01X120866Y1031142D02*
X115533D01*
G01X115531Y1030650D02*
X116516D01*
G01Y1028012D02*
X115531D01*
G01X115533Y1027520D02*
X120866D01*
G01Y1027480D02*
X116518D01*
G01X120866Y1026142D02*
X115533D01*
G01X115531Y1025650D02*
X116516D01*
G01Y1023012D02*
X115531D01*
G01X115533Y1022520D02*
X120866D01*
G01Y1022480D02*
X116518D01*
G01X120866Y1021142D02*
X115533D01*
G01X116516Y1045946D02*
X115531Y1045945D01*
G01Y1042715D02*
X116487Y1042717D01*
G01X116516Y1040946D02*
X115531Y1040945D01*
G01Y1037715D02*
X116487Y1037717D01*
G01X116516Y1035946D02*
X115531Y1035945D01*
G01Y1032715D02*
X116487Y1032717D01*
G01X116516Y1030946D02*
X115531Y1030945D01*
G01Y1027715D02*
X116487Y1027717D01*
G01X116516Y1025946D02*
X115531Y1025945D01*
G01Y1022715D02*
X116487Y1022717D01*
G01X116516Y1020946D02*
X115531Y1020945D01*
G01X101993Y1008228D02*
X102105Y1008220D01*
G01X102104Y998775D02*
X101993Y998780D01*
G01X102104Y992477D02*
X101993Y992480D01*
G01X102104Y1001926D02*
X101993Y1001929D01*
G01X115531Y1020650D02*
X116516D01*
G01Y1018012D02*
X115531D01*
G01X115533Y1017520D02*
X120866D01*
G01Y1017480D02*
X116518D01*
G01X120866Y1016142D02*
X115533D01*
G01X115531Y1015650D02*
X116516D01*
G01Y1013012D02*
X115531D01*
G01X115533Y1012520D02*
X120866D01*
G01Y1012480D02*
X116518D01*
G01X103543Y1011535D02*
X100197D01*
G01X120866Y1011142D02*
X115533D01*
G01X115531Y1010650D02*
X116516D01*
G01X113189Y1010374D02*
X117126D01*
G01X103051Y1009567D02*
X102146D01*
G01X103091Y1009528D02*
X102106D01*
G01X112008Y1009193D02*
X115945D01*
G01X102106Y1008031D02*
X103091D01*
G01X102146Y1007992D02*
X103051D01*
G01Y1006417D02*
X102146D01*
G01X103091Y1006378D02*
X102106D01*
G01Y1004882D02*
X103091D01*
G01X102146Y1004843D02*
X103051D01*
G01Y1003268D02*
X102146D01*
G01X103091Y1003228D02*
X102106D01*
G01Y1001732D02*
X103091D01*
G01X102146Y1001693D02*
X103051D01*
G01Y1000118D02*
X102146D01*
G01X103091Y1000079D02*
X102106D01*
G01Y998583D02*
X103091D01*
G01X102146Y998543D02*
X103051D01*
G01Y996969D02*
X102146D01*
G01X103091Y996929D02*
X102106D01*
G01Y995433D02*
X103091D01*
G01X102146Y995394D02*
X103051D01*
G01Y993819D02*
X102146D01*
G01X103091Y993780D02*
X102106D01*
G01Y992283D02*
X103091D01*
G01X102146Y992244D02*
X103051D01*
G01Y990669D02*
X102146D01*
G01X103091Y990630D02*
X102106D01*
G01X115945Y989469D02*
X112008D01*
G01X102106Y989134D02*
X103091D01*
G01X102146Y989094D02*
X103051D01*
G01X117126Y988287D02*
X113189D01*
G01X116516Y988012D02*
X115531D01*
G01X115533Y987520D02*
X120866D01*
G01Y987480D02*
X116518D01*
G01X103543Y987126D02*
X100197D01*
G01X120866Y986142D02*
X115533D01*
G01X115531Y985650D02*
X116516D01*
G01Y983012D02*
X115531D01*
G01X115533Y982520D02*
X120866D01*
G01Y982480D02*
X116518D01*
G01X120866Y981142D02*
X115533D01*
G01X115531Y980650D02*
X116516D01*
G01Y978012D02*
X115531D01*
G01X115533Y977520D02*
X120866D01*
G01Y977480D02*
X116518D01*
G01X120866Y976142D02*
X115533D01*
G01X115531Y975650D02*
X116516D01*
G01Y973012D02*
X115531D01*
G01X115533Y972520D02*
X120866D01*
G01Y972480D02*
X116518D01*
G01X120866Y971142D02*
X115533D01*
G01X115531Y970650D02*
X116516D01*
G01Y968012D02*
X115531D01*
G01X115533Y967520D02*
X120866D01*
G01Y967480D02*
X116518D01*
G01X120866Y966142D02*
X115533D01*
G01X115531Y965650D02*
X116516D01*
G01Y963012D02*
X115531D01*
G01X115533Y962520D02*
X120866D01*
G01Y962480D02*
X116518D01*
G01X120866Y961142D02*
X115533D01*
G01X115531Y960650D02*
X116516D01*
G01Y958012D02*
X115531D01*
G01X115533Y957520D02*
X120866D01*
G01Y957480D02*
X116518D01*
G01X120866Y956142D02*
X115533D01*
G01X115531Y955650D02*
X116516D01*
G01X112008Y953012D02*
X106496D01*
G01X115531Y1017715D02*
X116487Y1017717D01*
G01X116516Y1015946D02*
X115531Y1015945D01*
G01Y1012715D02*
X116487Y1012717D01*
G01X116516Y1010946D02*
X115531Y1010945D01*
G01Y987715D02*
X116487Y987717D01*
G01X116516Y985946D02*
X115531Y985945D01*
G01Y982715D02*
X116487Y982717D01*
G01X116516Y980946D02*
X115531Y980945D01*
G01Y977715D02*
X116487Y977717D01*
G01X116516Y975946D02*
X115531Y975945D01*
G01Y972715D02*
X116487Y972717D01*
G01X116516Y970946D02*
X115531Y970945D01*
G01Y967715D02*
X116487Y967717D01*
G01X116516Y965946D02*
X115531Y965945D01*
G01Y962715D02*
X116487Y962717D01*
G01X116516Y960946D02*
X115531Y960945D01*
G01Y957715D02*
X116487Y957717D01*
G01X116516Y955946D02*
X115531Y955945D01*
G01X115945Y989469D02*
X117126Y988287D01*
G01X112008Y989469D02*
X113189Y988287D01*
G01X103050Y1005039D02*
X103053Y1005028D01*
G01X115945Y1009193D02*
X117126Y1010374D01*
G01X112008Y1009193D02*
X113189Y1010374D01*
G01X103090Y990435D02*
X103091Y990446D01*
G01X103090Y993585D02*
X103091Y993596D01*
G01X103090Y996734D02*
X103091Y996746D01*
G01X103090Y999884D02*
X103091Y999895D01*
G01X103090Y1003033D02*
X103091Y1003045D01*
G01X103090Y1006183D02*
X103091Y1006194D01*
G01X103090Y1009333D02*
X103091Y1009344D01*
G01X116516Y957494D02*
Y957502D01*
G01Y962494D02*
Y962502D01*
G01Y967494D02*
Y967502D01*
G01Y972494D02*
Y972502D01*
G01Y977494D02*
Y977502D01*
G01Y982494D02*
Y982502D01*
G01Y987494D02*
Y987502D01*
G01Y1012494D02*
Y1012502D01*
G01Y1017494D02*
Y1017502D01*
G01Y1022494D02*
Y1022502D01*
G01Y1027494D02*
Y1027502D01*
G01Y1032494D02*
Y1032502D01*
G01Y1037494D02*
Y1037502D01*
G01Y1042494D02*
Y1042502D01*
G01X120866Y1046142D02*
Y1047520D01*
G01Y1041142D02*
Y1042520D01*
G01Y1036142D02*
Y1037520D01*
G01Y1031142D02*
Y1032520D01*
G01Y1026142D02*
Y1027520D01*
G01Y1021142D02*
Y1022520D01*
G01Y1016142D02*
Y1017520D01*
G01Y1011142D02*
Y1012520D01*
G01Y986142D02*
Y987520D01*
G01Y981142D02*
Y982520D01*
G01Y976142D02*
Y977520D01*
G01Y971142D02*
Y972520D01*
G01Y966142D02*
Y967520D01*
G01Y961142D02*
Y962520D01*
G01Y956142D02*
Y957520D01*
G01X117697D02*
Y956142D01*
G01Y962520D02*
Y961142D01*
G01Y967520D02*
Y966142D01*
G01Y972520D02*
Y971142D01*
G01Y977520D02*
Y976142D01*
G01Y982520D02*
Y981142D01*
G01Y987520D02*
Y986142D01*
G01Y1012520D02*
Y1011142D01*
G01Y1017520D02*
Y1016142D01*
G01Y1022520D02*
Y1021142D01*
G01Y1027520D02*
Y1026142D01*
G01Y1032520D02*
Y1031142D01*
G01Y1037520D02*
Y1036142D01*
G01Y1042520D02*
Y1041142D01*
G01Y1047520D02*
Y1046142D01*
G01X117126Y1010374D02*
Y988287D01*
G01X116516Y1045650D02*
Y1048012D01*
G01Y1040650D02*
Y1043012D01*
G01Y1035650D02*
Y1038012D01*
G01Y1030650D02*
Y1033012D01*
G01Y1025650D02*
Y1028012D01*
G01Y1020650D02*
Y1023012D01*
G01Y1015650D02*
Y1018012D01*
G01Y1010650D02*
Y1013012D01*
G01Y985650D02*
Y988012D01*
G01Y980650D02*
Y983012D01*
G01Y975650D02*
Y978012D01*
G01Y970650D02*
Y973012D01*
G01Y965650D02*
Y968012D01*
G01Y960650D02*
Y963012D01*
G01Y955650D02*
Y958012D01*
G01Y962494D02*
Y962637D01*
G01Y957494D02*
Y957637D01*
G01Y972494D02*
Y972637D01*
G01Y967494D02*
Y967637D01*
G01Y982494D02*
Y982637D01*
G01Y977494D02*
Y977637D01*
G01Y987494D02*
Y987637D01*
G01Y1012494D02*
Y1012637D01*
G01Y1022494D02*
Y1022637D01*
G01Y1017494D02*
Y1017637D01*
G01Y1032494D02*
Y1032637D01*
G01Y1027494D02*
Y1027637D01*
G01Y1042494D02*
Y1042637D01*
G01Y1037494D02*
Y1037637D01*
G01X115945Y1009193D02*
Y989469D01*
G01X115531Y958012D02*
Y955650D01*
G01Y963012D02*
Y960650D01*
G01Y968012D02*
Y965650D01*
G01Y973012D02*
Y970650D01*
G01Y978012D02*
Y975650D01*
G01Y983012D02*
Y980650D01*
G01Y988012D02*
Y985650D01*
G01Y1013012D02*
Y1010650D01*
G01Y1018012D02*
Y1015650D01*
G01Y1023012D02*
Y1020650D01*
G01Y1028012D02*
Y1025650D01*
G01Y1033012D02*
Y1030650D01*
G01Y1038012D02*
Y1035650D01*
G01Y1043012D02*
Y1040650D01*
G01Y1048012D02*
Y1045650D01*
G01X113189Y1086831D02*
Y1010374D01*
G01X112008Y989469D02*
Y953012D01*
G01Y1085650D02*
Y1009193D01*
G01X106496Y953012D02*
Y1085650D01*
G01X103543Y1090571D02*
Y1011535D01*
G01X103091Y1008031D02*
Y1009528D01*
G01Y1004881D02*
Y1006378D01*
G01Y1001732D02*
Y1003228D01*
G01Y998582D02*
Y1000079D01*
G01Y995433D02*
Y996929D01*
G01Y992283D02*
Y993780D01*
G01Y989133D02*
Y990630D01*
G01X103051Y989280D02*
Y989133D01*
G01Y990630D02*
Y990483D01*
G01Y995579D02*
Y995432D01*
G01Y992430D02*
Y992283D01*
G01Y993780D02*
Y993633D01*
G01Y998729D02*
Y998582D01*
G01Y1000079D02*
Y999932D01*
G01Y996930D02*
Y996783D01*
G01Y1001878D02*
Y1001731D01*
G01Y1003229D02*
Y1003082D01*
G01Y1008178D02*
Y1008031D01*
G01Y1009528D02*
Y1009381D01*
G01Y1005028D02*
Y1004881D01*
G01Y1006378D02*
Y1006231D01*
G01X102146Y1008031D02*
Y1008178D01*
G01Y1009381D02*
Y1009528D01*
G01Y1004881D02*
Y1005028D01*
G01Y1006231D02*
Y1006378D01*
G01Y1001731D02*
Y1001878D01*
G01Y1003082D02*
Y1003229D01*
G01Y998582D02*
Y998729D01*
G01Y999932D02*
Y1000079D01*
G01Y996783D02*
Y996930D01*
G01Y995432D02*
Y995579D01*
G01Y992283D02*
Y992430D01*
G01Y993633D02*
Y993780D01*
G01Y989133D02*
Y989280D01*
G01Y990483D02*
Y990630D01*
G01X102106D02*
Y989134D01*
G01Y993780D02*
Y992283D01*
G01Y1000079D02*
Y998583D01*
G01Y996929D02*
Y995433D01*
G01Y1003228D02*
Y1001732D01*
G01Y1009528D02*
Y1008031D01*
G01Y1006378D02*
Y1004882D01*
G01X100925Y990472D02*
Y989291D01*
G01Y996772D02*
Y995591D01*
G01Y993622D02*
Y992441D01*
G01Y999921D02*
Y998740D01*
G01Y1003071D02*
Y1001890D01*
G01Y1009370D02*
Y1008189D01*
G01Y1006220D02*
Y1005039D01*
G01X100591Y1011535D02*
Y987126D01*
G01X100197D02*
Y1011535D01*
G01X103091Y1008215D02*
X103090Y1008226D01*
G01X103091Y1005065D02*
X103090Y1005076D01*
G01X103091Y1001916D02*
X103090Y1001926D01*
G01X103091Y998766D02*
X103090Y998777D01*
G01X103091Y995617D02*
X103090Y995627D01*
G01X103091Y992467D02*
X103090Y992478D01*
G01X103091Y989317D02*
X103090Y989328D01*
G01X116483Y1047618D02*
X116487Y1047717D01*
G01X116477Y1047546D02*
X116483Y1047618D01*
G01X116479Y1047520D02*
X116477Y1047546D01*
G01X116483Y1052618D02*
X116487Y1052717D01*
G01X116477Y1052546D02*
X116483Y1052618D01*
G01X116479Y1052520D02*
X116477Y1052546D01*
G01X116483Y1057618D02*
X116487Y1057717D01*
G01X116477Y1057546D02*
X116483Y1057618D01*
G01X116479Y1057520D02*
X116477Y1057546D01*
G01X116483Y1062618D02*
X116487Y1062717D01*
G01X116477Y1062546D02*
X116483Y1062618D01*
G01X116479Y1062520D02*
X116477Y1062546D01*
G01X116483Y1067618D02*
X116487Y1067717D01*
G01X116477Y1067546D02*
X116483Y1067618D01*
G01X116479Y1067520D02*
X116477Y1067546D01*
G01X116483Y1072618D02*
X116487Y1072717D01*
G01X116477Y1072546D02*
X116483Y1072618D01*
G01X116479Y1072520D02*
X116477Y1072546D01*
G01X116483Y1077618D02*
X116487Y1077717D01*
G01X116477Y1077546D02*
X116483Y1077618D01*
G01X116479Y1077520D02*
X116477Y1077546D01*
G01X116483Y1082618D02*
X116487Y1082717D01*
G01X116477Y1082546D02*
X116483Y1082618D01*
G01X116479Y1082520D02*
X116477Y1082546D01*
G01X115532Y1081140D02*
X115533Y1081142D01*
G01X115531Y1081134D02*
X115532Y1081140D01*
G01X115531Y1081126D02*
Y1081134D01*
G01X115532Y1076140D02*
X115533Y1076142D01*
G01X115531Y1076134D02*
X115532Y1076140D01*
G01X115531Y1076126D02*
Y1076134D01*
G01X115532Y1071140D02*
X115533Y1071142D01*
G01X115531Y1071134D02*
X115532Y1071140D01*
G01X115531Y1071126D02*
Y1071134D01*
G01X115532Y1066140D02*
X115533Y1066142D01*
G01X115531Y1066134D02*
X115532Y1066140D01*
G01X115531Y1066126D02*
Y1066134D01*
G01X115532Y1061140D02*
X115533Y1061142D01*
G01X115531Y1061134D02*
X115532Y1061140D01*
G01X115531Y1061126D02*
Y1061134D01*
G01X115532Y1056140D02*
X115533Y1056142D01*
G01X115531Y1056134D02*
X115532Y1056140D01*
G01X115531Y1056126D02*
Y1056134D01*
G01X115532Y1051140D02*
X115533Y1051142D01*
G01X115531Y1051134D02*
X115532Y1051140D01*
G01X115531Y1051126D02*
Y1051134D01*
G01X116516Y1081134D02*
Y1081125D01*
G01X116517Y1081140D02*
X116516Y1081134D01*
G01X116519Y1081142D02*
X116517Y1081140D01*
G01X116516Y1076134D02*
Y1076125D01*
G01X116517Y1076140D02*
X116516Y1076134D01*
G01X116519Y1076142D02*
X116517Y1076140D01*
G01X116516Y1071134D02*
Y1071125D01*
G01X116517Y1071140D02*
X116516Y1071134D01*
G01X116519Y1071142D02*
X116517Y1071140D01*
G01X116516Y1066134D02*
Y1066125D01*
G01X116517Y1066140D02*
X116516Y1066134D01*
G01X116519Y1066142D02*
X116517Y1066140D01*
G01X116516Y1061134D02*
Y1061125D01*
G01X116517Y1061140D02*
X116516Y1061134D01*
G01X116519Y1061142D02*
X116517Y1061140D01*
G01X116516Y1056134D02*
Y1056125D01*
G01X116517Y1056140D02*
X116516Y1056134D01*
G01X116519Y1056142D02*
X116517Y1056140D01*
G01X116516Y1051134D02*
Y1051125D01*
G01X116517Y1051140D02*
X116516Y1051134D01*
G01X116519Y1051142D02*
X116517Y1051140D01*
G01X116498Y1052515D02*
X116479Y1052520D01*
G01X116513Y1052500D02*
X116498Y1052515D01*
G01X116518Y1052480D02*
X116513Y1052500D01*
G01X116498Y1057515D02*
X116479Y1057520D01*
G01X116513Y1057500D02*
X116498Y1057515D01*
G01X116518Y1057480D02*
X116513Y1057500D01*
G01X116498Y1062515D02*
X116479Y1062520D01*
G01X116513Y1062500D02*
X116498Y1062515D01*
G01X116518Y1062480D02*
X116513Y1062500D01*
G01X116498Y1067515D02*
X116479Y1067520D01*
G01X116513Y1067500D02*
X116498Y1067515D01*
G01X116518Y1067480D02*
X116513Y1067500D01*
G01X116498Y1072515D02*
X116479Y1072520D01*
G01X116513Y1072500D02*
X116498Y1072515D01*
G01X116518Y1072480D02*
X116513Y1072500D01*
G01X116498Y1077515D02*
X116479Y1077520D01*
G01X116513Y1077500D02*
X116498Y1077515D01*
G01X116518Y1077480D02*
X116513Y1077500D01*
G01X116498Y1082515D02*
X116479Y1082520D01*
G01X116513Y1082500D02*
X116498Y1082515D01*
G01X116518Y1082480D02*
X116513Y1082500D01*
G01X115531Y1047527D02*
Y1047536D01*
G01X115532Y1047521D02*
X115531Y1047527D01*
G01Y1052527D02*
Y1052536D01*
G01X115532Y1052521D02*
X115531Y1052527D01*
G01X115533Y1052520D02*
X115532Y1052521D01*
G01X115531Y1057527D02*
Y1057536D01*
G01X115532Y1057521D02*
X115531Y1057527D01*
G01X115533Y1057520D02*
X115532Y1057521D01*
G01X115531Y1062527D02*
Y1062536D01*
G01X115532Y1062521D02*
X115531Y1062527D01*
G01X115533Y1062520D02*
X115532Y1062521D01*
G01X115531Y1067527D02*
Y1067536D01*
G01X115532Y1067521D02*
X115531Y1067527D01*
G01X115533Y1067520D02*
X115532Y1067521D01*
G01X115531Y1072527D02*
Y1072536D01*
G01X115532Y1072521D02*
X115531Y1072527D01*
G01X115533Y1072520D02*
X115532Y1072521D01*
G01X115531Y1077527D02*
Y1077536D01*
G01X115532Y1077521D02*
X115531Y1077527D01*
G01X115533Y1077520D02*
X115532Y1077521D01*
G01X115531Y1082527D02*
Y1082536D01*
G01X115532Y1082521D02*
X115531Y1082527D01*
G01X115533Y1082520D02*
X115532Y1082521D01*
G01X116508Y1047663D02*
X116516Y1047637D01*
G01X116498Y1047690D02*
X116508Y1047663D01*
G01X116487Y1047717D02*
X116498Y1047690D01*
G01X116508Y1052663D02*
X116516Y1052637D01*
G01X116498Y1052690D02*
X116508Y1052663D01*
G01X116487Y1052717D02*
X116498Y1052690D01*
G01X116508Y1057663D02*
X116516Y1057637D01*
G01X116498Y1057690D02*
X116508Y1057663D01*
G01X116487Y1057717D02*
X116498Y1057690D01*
G01X116508Y1062663D02*
X116516Y1062637D01*
G01X116498Y1062690D02*
X116508Y1062663D01*
G01X116487Y1062717D02*
X116498Y1062690D01*
G01X116508Y1067663D02*
X116516Y1067637D01*
G01X116498Y1067690D02*
X116508Y1067663D01*
G01X116487Y1067717D02*
X116498Y1067690D01*
G01X116508Y1072663D02*
X116516Y1072637D01*
G01X116498Y1072690D02*
X116508Y1072663D01*
G01X116487Y1072717D02*
X116498Y1072690D01*
G01X116508Y1077663D02*
X116516Y1077637D01*
G01X116498Y1077690D02*
X116508Y1077663D01*
G01X116487Y1077717D02*
X116498Y1077690D01*
G01X116508Y1082663D02*
X116516Y1082637D01*
G01X116498Y1082690D02*
X116508Y1082663D01*
G01X116487Y1082717D02*
X116498Y1082690D01*
G01X116516Y1047487D02*
Y1047494D01*
G01Y1052487D02*
Y1052494D01*
G01X116517Y1052482D02*
X116516Y1052487D01*
G01X116518Y1052480D02*
X116517Y1052482D01*
G01X116516Y1057487D02*
Y1057494D01*
G01X116517Y1057482D02*
X116516Y1057487D01*
G01X116518Y1057480D02*
X116517Y1057482D01*
G01X116516Y1062487D02*
Y1062494D01*
G01X116517Y1062482D02*
X116516Y1062487D01*
G01X116518Y1062480D02*
X116517Y1062482D01*
G01X116516Y1067487D02*
Y1067494D01*
G01X116517Y1067482D02*
X116516Y1067487D01*
G01X116518Y1067480D02*
X116517Y1067482D01*
G01X116516Y1072487D02*
Y1072494D01*
G01X116517Y1072482D02*
X116516Y1072487D01*
G01X116518Y1072480D02*
X116517Y1072482D01*
G01X116516Y1077487D02*
Y1077494D01*
G01X116517Y1077482D02*
X116516Y1077487D01*
G01X116518Y1077480D02*
X116517Y1077482D01*
G01X116516Y1082487D02*
Y1082494D01*
G01X116517Y1082482D02*
X116516Y1082487D01*
G01X116518Y1082480D02*
X116517Y1082482D01*
G01X116503Y1052511D02*
X116514Y1052496D01*
G01X116479Y1052520D02*
X116503Y1052511D01*
G01Y1057511D02*
X116514Y1057496D01*
G01X116479Y1057520D02*
X116503Y1057511D01*
G01Y1062511D02*
X116514Y1062496D01*
G01X116479Y1062520D02*
X116503Y1062511D01*
G01Y1067511D02*
X116514Y1067496D01*
G01X116479Y1067520D02*
X116503Y1067511D01*
G01Y1072511D02*
X116514Y1072496D01*
G01X116479Y1072520D02*
X116503Y1072511D01*
G01Y1077511D02*
X116514Y1077496D01*
G01X116479Y1077520D02*
X116503Y1077511D01*
G01Y1082511D02*
X116514Y1082496D01*
G01X116479Y1082520D02*
X116503Y1082511D01*
G01X114295Y1170224D02*
G03X148106I16905J-13531D01*
G01X114295D02*
G03X148106I16905J-13531D01*
G01X114961Y1108012D02*
G03X114370Y1108602I-591J-1D01*
G01X107677D02*
G03X107087Y1108012I0J-590D01*
G01X109843Y1106831D02*
G03Y1104862I0J-985D01*
G01X112205D02*
G03Y1106831I0J984D01*
G01X108465Y1098917D02*
G03X107283Y1097736I-1J-1181D01*
G01X114764D02*
G03X113583Y1098917I-1181J0D01*
G01X112913Y1093642D02*
G03I-1889J0D01*
G01X121850Y1107421D02*
G03X119882Y1109390I-1968J1D01*
G01X102165D02*
G03X100197Y1107421I1J-1969D01*
G01X113386Y1093642D02*
G03I-2362J0D01*
G01X119882Y1109390D02*
X102165D01*
G01X114370Y1108602D02*
X107677D01*
G01X112205Y1106831D02*
X109843D01*
G01Y1104862D02*
X112205D01*
G01X114961Y1103484D02*
X107087D01*
G01Y1101909D02*
X114961D01*
G01X121850Y1098957D02*
X100197D01*
G01X108465Y1098917D02*
X113583D01*
G01X109843Y1094232D02*
X112205D01*
G01X109843Y1092539D02*
X112205D01*
G01X103543Y1090571D02*
X117913D01*
G01X103543Y1089193D02*
X107283D01*
G01X117913D02*
X114764D01*
G01X103543Y1088327D02*
X118504D01*
G01X105315Y1086831D02*
X113189D01*
G01X106496Y1085650D02*
X112008D01*
G01X116516Y1083012D02*
X115531D01*
G01X115533Y1082520D02*
X120866D01*
G01Y1082480D02*
X116518D01*
G01X120866Y1081142D02*
X115533D01*
G01X115531Y1080650D02*
X116516D01*
G01Y1078012D02*
X115531D01*
G01X115533Y1077520D02*
X120866D01*
G01Y1077480D02*
X116518D01*
G01X120866Y1076142D02*
X115533D01*
G01X115531Y1075650D02*
X116516D01*
G01Y1073012D02*
X115531D01*
G01X115533Y1072520D02*
X120866D01*
G01Y1072480D02*
X116518D01*
G01X120866Y1071142D02*
X115533D01*
G01X115531Y1070650D02*
X116516D01*
G01Y1068012D02*
X115531D01*
G01X115533Y1067520D02*
X120866D01*
G01Y1067480D02*
X116518D01*
G01X120866Y1066142D02*
X115533D01*
G01X115531Y1065650D02*
X116516D01*
G01Y1063012D02*
X115531D01*
G01X115533Y1062520D02*
X120866D01*
G01Y1062480D02*
X116518D01*
G01X120866Y1061142D02*
X115533D01*
G01X115531Y1060650D02*
X116516D01*
G01Y1058012D02*
X115531D01*
G01X115533Y1057520D02*
X120866D01*
G01Y1057480D02*
X116518D01*
G01X120866Y1056142D02*
X115533D01*
G01X115531Y1055650D02*
X116516D01*
G01Y1053012D02*
X115531D01*
G01X115533Y1052520D02*
X120866D01*
G01Y1052480D02*
X116518D01*
G01X120866Y1051142D02*
X115533D01*
G01X115531Y1050650D02*
X116516D01*
G01Y1048012D02*
X115531D01*
G01X115533Y1047520D02*
X120866D01*
G01Y1047480D02*
X116518D01*
G01X115531Y1082715D02*
X116487Y1082717D01*
G01X116516Y1080946D02*
X115531Y1080945D01*
G01Y1077715D02*
X116487Y1077717D01*
G01X116516Y1075946D02*
X115531Y1075945D01*
G01Y1072715D02*
X116487Y1072717D01*
G01X116516Y1070946D02*
X115531Y1070945D01*
G01Y1067715D02*
X116487Y1067717D01*
G01X116516Y1065946D02*
X115531Y1065945D01*
G01Y1062715D02*
X116487Y1062717D01*
G01X116516Y1060946D02*
X115531Y1060945D01*
G01Y1057715D02*
X116487Y1057717D01*
G01X116516Y1055946D02*
X115531Y1055945D01*
G01Y1052715D02*
X116487Y1052717D01*
G01X116516Y1050946D02*
X115531Y1050945D01*
G01Y1047715D02*
X116487Y1047717D01*
G01X105315Y1086831D02*
X106496Y1085650D01*
G01X100197Y1091673D02*
X103543Y1088327D01*
G01X112205Y1092539D02*
X113508Y1090571D01*
G01X109843Y1094232D02*
X107532Y1098461D01*
G01X121850Y1091673D02*
X118504Y1088327D01*
G01X112008Y1085650D02*
X113189Y1086831D01*
G01X116516Y1047494D02*
Y1047502D01*
G01Y1052494D02*
Y1052502D01*
G01Y1057494D02*
Y1057502D01*
G01Y1062494D02*
Y1062502D01*
G01Y1067494D02*
Y1067502D01*
G01Y1072494D02*
Y1072502D01*
G01Y1077494D02*
Y1077502D01*
G01Y1082494D02*
Y1082502D01*
G01X121850Y1091673D02*
Y1107421D01*
G01X120866Y1081142D02*
Y1082520D01*
G01Y1076142D02*
Y1077520D01*
G01Y1071142D02*
Y1072520D01*
G01Y1066142D02*
Y1067520D01*
G01Y1061142D02*
Y1062520D01*
G01Y1056142D02*
Y1057520D01*
G01Y1051142D02*
Y1052520D01*
G01X117697D02*
Y1051142D01*
G01Y1057520D02*
Y1056142D01*
G01Y1062520D02*
Y1061142D01*
G01Y1067520D02*
Y1066142D01*
G01Y1072520D02*
Y1071142D01*
G01Y1077520D02*
Y1076142D01*
G01Y1082520D02*
Y1081142D01*
G01X116516Y1080650D02*
Y1083012D01*
G01Y1075650D02*
Y1078012D01*
G01Y1070650D02*
Y1073012D01*
G01Y1065650D02*
Y1068012D01*
G01Y1060650D02*
Y1063012D01*
G01Y1055650D02*
Y1058012D01*
G01Y1050650D02*
Y1053012D01*
G01Y1052494D02*
Y1052637D01*
G01Y1047494D02*
Y1047637D01*
G01Y1062494D02*
Y1062637D01*
G01Y1057494D02*
Y1057637D01*
G01Y1072494D02*
Y1072637D01*
G01Y1067494D02*
Y1067637D01*
G01Y1082494D02*
Y1082637D01*
G01Y1077494D02*
Y1077637D01*
G01X115531Y1053012D02*
Y1050650D01*
G01Y1058012D02*
Y1055650D01*
G01Y1063012D02*
Y1060650D01*
G01Y1068012D02*
Y1065650D01*
G01Y1073012D02*
Y1070650D01*
G01Y1078012D02*
Y1075650D01*
G01Y1083012D02*
Y1080650D01*
G01X114961Y1101909D02*
Y1108012D01*
G01X114764Y1097736D02*
Y1089193D01*
G01X112205Y1094232D02*
Y1092539D01*
G01X109843D02*
Y1094232D01*
G01X107283Y1089193D02*
Y1097736D01*
G01X107087Y1101909D02*
Y1108012D01*
G01X100197Y1107421D02*
Y1091673D01*
G01X108539Y1090571D02*
X109843Y1092539D01*
G01X114515Y1098461D02*
X112205Y1094232D01*
G01X141181Y1183355D02*
G03X148106Y1170224I37662J11471D01*
G01X141181Y1183355D02*
G03X121220I-9980J-3040D01*
G01X114295Y1170224D02*
G03X121220Y1183355I-30737J24602D01*
G01X141181D02*
G03X121220I-9980J-3040D01*
G01X141181D02*
G03X148106Y1170224I37662J11471D01*
G01X114295D02*
G03X121220Y1183355I-30737J24601D01*
G01X280709Y1519685D02*
X101378D01*
G01X167717Y1494280D02*
G03Y1497059I0J1389D01*
G01Y1492575D02*
G03Y1498764I0J3094D01*
G01X168977Y1491732D02*
G03Y1499606I-1260J3937D01*
G01X171850Y1491732D02*
G03Y1499606I-4134J3937D01*
G01X184252Y1523622D02*
X217323D01*
G01X146457D02*
X180315D01*
G01X150000Y1521654D02*
X146457D01*
G01X184252Y1520210D02*
X167717D01*
G01X280709Y1519685D02*
X101378D01*
G01X184252Y1518110D02*
X217323D01*
G01X240945Y1516929D02*
X160630D01*
G01X240945Y1512992D02*
X160630D01*
G01X184252Y1512598D02*
X217323D01*
G01X155707D02*
X155472D01*
G01X188189Y1510954D02*
X198819D01*
G01X157087D02*
X180315D01*
G01Y1509843D02*
X221260D01*
G01X182185Y1505512D02*
X186319D01*
G01X165650D02*
X169783D01*
G01X184252Y1505210D02*
X188189D01*
G01X171850Y1499606D02*
X167717D01*
G01X146457Y1492913D02*
X157087D01*
G01X171850Y1491732D02*
X167717D01*
G01X174803Y1485827D02*
X160630D01*
G01X191339D02*
X177165D01*
G01X207874D02*
X193701D01*
G01X155472Y1471260D02*
X244488D01*
G01X169783Y1469783D02*
X165650D01*
G01X186319D02*
X182185D01*
G01X169783Y1468996D02*
X165650D01*
G01X186319D02*
X182185D01*
G01X169783Y1464862D02*
X165650D01*
G01X186319D02*
X182185D01*
G01X169783Y1448130D02*
X165650D01*
G01X186319D02*
X182185D01*
G01X169783Y1447343D02*
X165650D01*
G01X186319D02*
X182185D01*
G01X169783Y1443209D02*
X165650D01*
G01X186319D02*
X182185D01*
G01X160630Y1516929D02*
X150000Y1521654D01*
G01Y1526772D02*
X160630Y1516929D01*
G01X146457Y1523622D02*
X157087Y1510954D01*
G01X193701Y1485827D02*
Y1512992D01*
G01X191339Y1485827D02*
Y1512992D01*
G01X188189Y1523622D02*
Y1505210D01*
G01X187402Y1485827D02*
Y1512992D01*
G01X186319Y1443209D02*
Y1471260D01*
G01Y1505512D02*
Y1485827D01*
G01X184252Y1505210D02*
Y1526772D01*
G01X182185Y1471260D02*
Y1443209D01*
G01Y1505512D02*
Y1485827D01*
G01X181102D02*
Y1512992D01*
G01X180315Y1509843D02*
Y1523622D01*
G01X177165Y1485827D02*
Y1512992D01*
G01X174803Y1485827D02*
Y1512992D01*
G01X170866Y1485827D02*
Y1512992D01*
G01X169783Y1443209D02*
Y1471260D01*
G01Y1505512D02*
Y1485827D01*
G01X167717Y1492574D02*
Y1494279D01*
G01Y1510954D02*
Y1526772D01*
G01Y1499606D02*
Y1491732D01*
G01Y1497059D02*
Y1498764D01*
G01X165650Y1471260D02*
Y1443209D01*
G01Y1505512D02*
Y1485827D01*
G01X165354Y1523622D02*
Y1471260D01*
G01X164567Y1485827D02*
Y1512992D01*
G01X161850Y1523622D02*
Y1471260D01*
G01X160630Y1516929D02*
Y1485827D01*
G01X157087Y1510954D02*
Y1471260D01*
G01X157047Y1511001D02*
Y1471260D01*
G01X155472Y1512598D02*
Y1471260D01*
G01X150000Y1526772D02*
Y1521654D01*
G01X148150Y1519685D02*
Y1521604D01*
G01X146457Y1526772D02*
Y1492913D01*
G01Y1526772D02*
X255118D01*
G01X258597Y-369410D02*
Y-388347D01*
G01X227272Y84959D02*
X227262Y84961D01*
G01X227281Y84956D02*
X227272Y84959D01*
G01X227288Y84951D02*
X227281Y84956D01*
G01X227272Y88109D02*
X227262Y88110D01*
G01X227281Y88106D02*
X227272Y88109D01*
G01X227288Y88100D02*
X227281Y88106D01*
G01X226358Y83774D02*
Y83768D01*
G01X226357Y83778D02*
X226358Y83774D01*
G01X226356Y83780D02*
X226357Y83778D01*
G01X226358Y86924D02*
Y86918D01*
G01X226357Y86928D02*
X226358Y86924D01*
G01X226356Y86929D02*
X226357Y86928D01*
G01X226358Y90074D02*
Y90067D01*
G01X226357Y90078D02*
X226358Y90074D01*
G01X226356Y90079D02*
X226357Y90078D01*
G01X226358Y93223D02*
Y93217D01*
G01X226357Y93227D02*
X226358Y93223D01*
G01X226356Y93228D02*
X226357Y93227D01*
G01X240729Y51975D02*
X240728Y51982D01*
G01X240730Y51970D02*
X240729Y51975D01*
G01X240731Y51969D02*
X240730Y51970D01*
G01X240729Y56975D02*
X240728Y56982D01*
G01X240730Y56970D02*
X240729Y56975D01*
G01X240731Y56969D02*
X240730Y56970D01*
G01X240729Y61975D02*
X240728Y61982D01*
G01X240730Y61970D02*
X240729Y61975D01*
G01X240731Y61969D02*
X240730Y61970D01*
G01X240729Y66975D02*
X240728Y66982D01*
G01X240730Y66970D02*
X240729Y66975D01*
G01X240731Y66969D02*
X240730Y66970D01*
G01X240729Y71975D02*
X240728Y71982D01*
G01X240730Y71970D02*
X240729Y71975D01*
G01X240731Y71969D02*
X240730Y71970D01*
G01X240729Y76975D02*
X240728Y76982D01*
G01X240730Y76970D02*
X240729Y76975D01*
G01X240731Y76969D02*
X240730Y76970D01*
G01X240729Y81975D02*
X240728Y81982D01*
G01X240730Y81970D02*
X240729Y81975D01*
G01X240731Y81969D02*
X240730Y81970D01*
G01X226342Y86931D02*
X226356Y86929D01*
G01X226330Y86939D02*
X226342Y86931D01*
G01X226318Y86957D02*
X226330Y86939D01*
G01X226341Y90081D02*
X226356Y90079D01*
G01X226329Y90089D02*
X226341Y90081D01*
G01X226317Y90109D02*
X226329Y90089D01*
G01X227303Y83813D02*
Y83805D01*
G01X227302Y83817D02*
X227303Y83813D01*
G01X227302Y83819D02*
Y83817D01*
G01X227303Y86963D02*
Y86955D01*
G01X227302Y86967D02*
X227303Y86963D01*
G01X227302Y86969D02*
Y86967D01*
G01X227303Y90112D02*
Y90104D01*
G01X227302Y90117D02*
X227303Y90112D01*
G01X227302Y90118D02*
Y90117D01*
G01X227303Y93262D02*
Y93254D01*
G01X227302Y93266D02*
X227303Y93262D01*
G01X227302Y93268D02*
Y93266D01*
G01X226341Y83782D02*
X226356Y83780D01*
G01X226328Y83791D02*
X226341Y83782D01*
G01X226317Y83811D02*
X226328Y83791D01*
G01X240716Y51999D02*
X240727Y51984D01*
G01X240691Y52008D02*
X240716Y51999D01*
G01Y56999D02*
X240727Y56984D01*
G01X240691Y57008D02*
X240716Y56999D01*
G01Y61999D02*
X240727Y61984D01*
G01X240691Y62008D02*
X240716Y61999D01*
G01Y66999D02*
X240727Y66984D01*
G01X240691Y67008D02*
X240716Y66999D01*
G01Y71999D02*
X240727Y71984D01*
G01X240691Y72008D02*
X240716Y71999D01*
G01X226319Y93258D02*
Y93254D01*
G01X226320Y93252D02*
X226319Y93258D01*
G01X226331Y93238D02*
X226320Y93252D01*
G01X226354Y93228D02*
X226331Y93238D01*
G01X227272Y91259D02*
X227262Y91260D01*
G01X227280Y91256D02*
X227272Y91259D01*
G01X227288Y91250D02*
X227280Y91256D01*
G01X227302Y84941D02*
X227303Y84935D01*
G01X227301Y84948D02*
X227302Y84941D01*
G01X227298Y84954D02*
X227301Y84948D01*
G01X227302Y88091D02*
X227303Y88084D01*
G01X227301Y88097D02*
X227302Y88091D01*
G01X227298Y88103D02*
X227301Y88097D01*
G01X227302Y91241D02*
X227303Y91234D01*
G01X227301Y91247D02*
X227302Y91241D01*
G01X227298Y91253D02*
X227301Y91247D01*
G01X227264Y83774D02*
X227265Y83768D01*
G01X227263Y83778D02*
X227264Y83774D01*
G01X227262Y83780D02*
X227263Y83778D01*
G01X227264Y86924D02*
X227265Y86918D01*
G01X227263Y86928D02*
X227264Y86924D01*
G01X227262Y86929D02*
X227263Y86928D01*
G01X227264Y90074D02*
X227265Y90067D01*
G01X227263Y90077D02*
X227264Y90074D01*
G01X227262Y90079D02*
X227263Y90077D01*
G01X227264Y93223D02*
X227265Y93217D01*
G01X227263Y93227D02*
X227264Y93223D01*
G01X227262Y93228D02*
X227263Y93227D01*
G01X239744Y52015D02*
Y52024D01*
G01X239745Y52009D02*
X239744Y52015D01*
G01X239746Y52008D02*
X239745Y52009D01*
G01X239744Y57015D02*
Y57024D01*
G01X239745Y57009D02*
X239744Y57015D01*
G01X239746Y57008D02*
X239745Y57009D01*
G01X239744Y62015D02*
Y62024D01*
G01X239745Y62009D02*
X239744Y62015D01*
G01X239746Y62008D02*
X239745Y62009D01*
G01X239744Y67015D02*
Y67024D01*
G01X239745Y67009D02*
X239744Y67015D01*
G01X239746Y67008D02*
X239745Y67009D01*
G01X239744Y72015D02*
Y72024D01*
G01X239745Y72009D02*
X239744Y72015D01*
G01X239746Y72008D02*
X239745Y72009D01*
G01X239744Y77015D02*
Y77024D01*
G01X239745Y77009D02*
X239744Y77015D01*
G01X239746Y77008D02*
X239745Y77009D01*
G01X239744Y82015D02*
Y82024D01*
G01X239745Y82009D02*
X239744Y82015D01*
G01X239746Y82008D02*
X239745Y82009D01*
G01X240720Y52152D02*
X240728Y52125D01*
G01X240711Y52178D02*
X240720Y52152D01*
G01X240699Y52205D02*
X240711Y52178D01*
G01X240720Y57152D02*
X240728Y57125D01*
G01X240711Y57178D02*
X240720Y57152D01*
G01X240699Y57205D02*
X240711Y57178D01*
G01X240720Y62152D02*
X240728Y62125D01*
G01X240711Y62178D02*
X240720Y62152D01*
G01X240699Y62205D02*
X240711Y62178D01*
G01X240720Y67152D02*
X240728Y67125D01*
G01X240711Y67178D02*
X240720Y67152D01*
G01X240699Y67205D02*
X240711Y67178D01*
G01X240720Y72152D02*
X240728Y72125D01*
G01X240711Y72178D02*
X240720Y72152D01*
G01X240699Y72205D02*
X240711Y72178D01*
G01X240720Y77152D02*
X240728Y77125D01*
G01X240711Y77178D02*
X240720Y77152D01*
G01X240699Y77205D02*
X240711Y77178D01*
G01X240720Y82152D02*
X240728Y82125D01*
G01X240711Y82178D02*
X240720Y82152D01*
G01X240699Y82205D02*
X240711Y82178D01*
G01X226337Y93233D02*
X226356Y93228D01*
G01X226323Y93246D02*
X226337Y93233D01*
G01X226317Y93263D02*
X226323Y93246D01*
G01X226319Y86959D02*
Y86955D01*
G01X226320Y86952D02*
X226319Y86959D01*
G01X226332Y86937D02*
X226320Y86952D01*
G01X226357Y86929D02*
X226332Y86937D01*
G01X226319Y90108D02*
Y90104D01*
G01X226320Y90102D02*
X226319Y90108D01*
G01X226332Y90087D02*
X226320Y90102D01*
G01X226356Y90079D02*
X226332Y90087D01*
G01X226319Y83809D02*
Y83806D01*
G01X226320Y83803D02*
X226319Y83809D01*
G01X226332Y83788D02*
X226320Y83803D01*
G01X226356Y83780D02*
X226332Y83788D01*
G01X240716Y76999D02*
X240727Y76984D01*
G01X240691Y77008D02*
X240716Y76999D01*
G01Y81999D02*
X240727Y81984D01*
G01X240691Y82008D02*
X240716Y81999D01*
G01X240711Y52003D02*
X240692Y52008D01*
G01X240726Y51988D02*
X240711Y52003D01*
G01X240731Y51969D02*
X240726Y51988D01*
G01X240711Y57003D02*
X240692Y57008D01*
G01X240726Y56988D02*
X240711Y57003D01*
G01X240731Y56969D02*
X240726Y56988D01*
G01X240711Y62003D02*
X240692Y62008D01*
G01X240726Y61988D02*
X240711Y62003D01*
G01X240731Y61969D02*
X240726Y61988D01*
G01X240711Y67003D02*
X240692Y67008D01*
G01X240726Y66988D02*
X240711Y67003D01*
G01X240731Y66969D02*
X240726Y66988D01*
G01X240711Y72003D02*
X240692Y72008D01*
G01X240726Y71988D02*
X240711Y72003D01*
G01X240731Y71969D02*
X240726Y71988D01*
G01X240711Y77003D02*
X240692Y77008D01*
G01X240726Y76988D02*
X240711Y77003D01*
G01X240731Y76969D02*
X240726Y76988D01*
G01X240711Y82003D02*
X240692Y82008D01*
G01X240726Y81988D02*
X240711Y82003D01*
G01X240731Y81969D02*
X240726Y81988D01*
G01X227296Y91242D02*
X227288Y91250D01*
G01X227300Y91231D02*
X227296Y91242D01*
G01X227302Y91220D02*
X227300Y91231D01*
G01X227296Y84943D02*
X227288Y84951D01*
G01X227300Y84932D02*
X227296Y84943D01*
G01X227302Y84921D02*
X227300Y84932D01*
G01X227296Y88092D02*
X227288Y88100D01*
G01X227300Y88082D02*
X227296Y88092D01*
G01X227302Y88071D02*
X227300Y88082D01*
G01X240695Y52106D02*
X240699Y52205D01*
G01X240690Y52034D02*
X240695Y52106D01*
G01X240692Y52008D02*
X240690Y52034D01*
G01X240695Y57106D02*
X240699Y57205D01*
G01X240690Y57034D02*
X240695Y57106D01*
G01X240692Y57008D02*
X240690Y57034D01*
G01X240695Y62106D02*
X240699Y62205D01*
G01X240690Y62034D02*
X240695Y62106D01*
G01X240692Y62008D02*
X240690Y62034D01*
G01X240695Y67106D02*
X240699Y67205D01*
G01X240690Y67034D02*
X240695Y67106D01*
G01X240692Y67008D02*
X240690Y67034D01*
G01X240695Y72106D02*
X240699Y72205D01*
G01X240690Y72034D02*
X240695Y72106D01*
G01X240692Y72008D02*
X240690Y72034D01*
G01X240695Y77106D02*
X240699Y77205D01*
G01X240690Y77034D02*
X240695Y77106D01*
G01X240692Y77008D02*
X240690Y77034D01*
G01X240695Y82106D02*
X240699Y82205D01*
G01X240690Y82034D02*
X240695Y82106D01*
G01X240692Y82008D02*
X240690Y82034D01*
G01X226359Y91444D02*
X226358Y91457D01*
G01X226356Y91431D02*
X226359Y91444D01*
G01X226356Y91417D02*
Y91431D01*
G01X226359Y88294D02*
X226358Y88307D01*
G01X226356Y88281D02*
X226359Y88294D01*
G01X226356Y88268D02*
Y88281D01*
G01X226359Y85145D02*
X226358Y85157D01*
G01X226356Y85132D02*
X226359Y85145D01*
G01X226356Y85118D02*
Y85132D01*
G01X227294Y84959D02*
X227298Y84954D01*
G01X227289Y84963D02*
X227294Y84959D01*
G01X227283Y84967D02*
X227289Y84963D01*
G01X227277Y84970D02*
X227283Y84967D01*
G01X227270Y84971D02*
X227277Y84970D01*
G01X227264Y84972D02*
X227270Y84971D01*
G01X227294Y88109D02*
X227298Y88103D01*
G01X227289Y88113D02*
X227294Y88109D01*
G01X227283Y88117D02*
X227289Y88113D01*
G01X227277Y88119D02*
X227283Y88117D01*
G01X227270Y88121D02*
X227277Y88119D01*
G01X227264Y88121D02*
X227270D01*
G01X227294Y91258D02*
X227298Y91253D01*
G01X227289Y91263D02*
X227294Y91258D01*
G01X227283Y91266D02*
X227289Y91263D01*
G01X227277Y91269D02*
X227283Y91266D01*
G01X227270Y91270D02*
X227277Y91269D01*
G01X227264Y91271D02*
X227270Y91270D01*
G01X226320Y83798D02*
X226319Y83805D01*
G01X226322Y83791D02*
X226320Y83798D01*
G01X226326Y83785D02*
X226322Y83791D01*
G01X226330Y83779D02*
X226326Y83785D01*
G01X226337Y83774D02*
X226330Y83779D01*
G01X226343Y83771D02*
X226337Y83774D01*
G01X226351Y83769D02*
X226343Y83771D01*
G01X226358Y83768D02*
X226351Y83769D01*
G01X226320Y86948D02*
X226319Y86955D01*
G01X226322Y86941D02*
X226320Y86948D01*
G01X226326Y86934D02*
X226322Y86941D01*
G01X226330Y86929D02*
X226326Y86934D01*
G01X226337Y86924D02*
X226330Y86929D01*
G01X226343Y86920D02*
X226337Y86924D01*
G01X226351Y86919D02*
X226343Y86920D01*
G01X226358Y86918D02*
X226351Y86919D01*
G01X226320Y90097D02*
X226319Y90104D01*
G01X226322Y90090D02*
X226320Y90097D01*
G01X226326Y90084D02*
X226322Y90090D01*
G01X226330Y90078D02*
X226326Y90084D01*
G01X226337Y90074D02*
X226330Y90078D01*
G01X226343Y90070D02*
X226337Y90074D01*
G01X226351Y90068D02*
X226343Y90070D01*
G01X226358Y90067D02*
X226351Y90068D01*
G01X226320Y93247D02*
X226319Y93254D01*
G01X226322Y93240D02*
X226320Y93247D01*
G01X226326Y93233D02*
X226322Y93240D01*
G01X226330Y93228D02*
X226326Y93233D01*
G01X226337Y93223D02*
X226330Y93228D01*
G01X226343Y93220D02*
X226337Y93223D01*
G01X226351Y93218D02*
X226343Y93220D01*
G01X226358Y93217D02*
X226351Y93218D01*
G01X227273Y84959D02*
X227282Y84955D01*
G01X227262Y84961D02*
X227273Y84959D01*
G01Y88109D02*
X227282Y88105D01*
G01X227262Y88110D02*
X227273Y88109D01*
G01Y91258D02*
X227282Y91254D01*
G01X227262Y91260D02*
X227273Y91258D01*
G01X239745Y80628D02*
X239746Y80630D01*
G01X239744Y80622D02*
X239745Y80628D01*
G01X239744Y80614D02*
Y80622D01*
G01X239745Y75628D02*
X239746Y75630D01*
G01X239744Y75622D02*
X239745Y75628D01*
G01X239744Y75614D02*
Y75622D01*
G01X239745Y70628D02*
X239746Y70630D01*
G01X239744Y70622D02*
X239745Y70628D01*
G01X239744Y70614D02*
Y70622D01*
G01X239745Y65628D02*
X239746Y65630D01*
G01X239744Y65622D02*
X239745Y65628D01*
G01X239744Y65614D02*
Y65622D01*
G01X239745Y60628D02*
X239746Y60630D01*
G01X239744Y60622D02*
X239745Y60628D01*
G01X239744Y60614D02*
Y60622D01*
G01X239745Y55628D02*
X239746Y55630D01*
G01X239744Y55622D02*
X239745Y55628D01*
G01X239744Y55614D02*
Y55622D01*
G01X239745Y50628D02*
X239746Y50630D01*
G01X239744Y50622D02*
X239745Y50628D01*
G01X239744Y50614D02*
Y50622D01*
G01X226356Y93057D02*
X226355Y93070D01*
G01X226359Y93044D02*
X226356Y93057D01*
G01X226358Y93031D02*
X226359Y93044D01*
G01X226356Y89907D02*
X226355Y89921D01*
G01X226359Y89894D02*
X226356Y89907D01*
G01X226358Y89882D02*
X226359Y89894D01*
G01X226356Y86757D02*
X226355Y86771D01*
G01X226359Y86745D02*
X226356Y86757D01*
G01X226358Y86732D02*
X226359Y86745D01*
G01X226356Y83608D02*
X226355Y83622D01*
G01X226359Y83595D02*
X226356Y83608D01*
G01X226358Y83583D02*
X226359Y83595D01*
G01X227266Y91431D02*
X227267Y91417D01*
G01X227263Y91444D02*
X227266Y91431D01*
G01X227264Y91457D02*
X227263Y91444D01*
G01X227266Y88281D02*
X227267Y88268D01*
G01X227263Y88294D02*
X227266Y88281D01*
G01X227264Y88307D02*
X227263Y88294D01*
G01X227266Y85132D02*
X227267Y85118D01*
G01X227263Y85145D02*
X227266Y85132D01*
G01X227264Y85157D02*
X227263Y85145D01*
G01X226319Y90112D02*
Y90105D01*
G01X226318Y90117D02*
X226319Y90112D01*
G01X226317Y90109D02*
X226318Y90117D01*
G01X227263Y93044D02*
X227264Y93031D01*
G01X227266Y93057D02*
X227263Y93044D01*
G01X227267Y93070D02*
X227266Y93057D01*
G01X227263Y89894D02*
X227264Y89882D01*
G01X227266Y89907D02*
X227263Y89894D01*
G01X227267Y89921D02*
X227266Y89907D01*
G01X227263Y86745D02*
X227264Y86732D01*
G01X227266Y86757D02*
X227263Y86745D01*
G01X227267Y86771D02*
X227266Y86757D01*
G01X227263Y83595D02*
X227264Y83583D01*
G01X227266Y83608D02*
X227263Y83595D01*
G01X227267Y83622D02*
X227266Y83608D01*
G01X226319Y83813D02*
Y83806D01*
G01X226318Y83817D02*
X226319Y83813D01*
G01X226317Y83811D02*
X226318Y83817D01*
G01X227281Y83772D02*
X227284Y83774D01*
G01X227278Y83770D02*
X227281Y83772D01*
G01X227274Y83770D02*
X227278D01*
G01X227271Y83769D02*
X227274Y83770D01*
G01X227267Y83769D02*
X227271D01*
G01X227264Y83768D02*
X227267Y83769D01*
G01X226341Y84968D02*
X226338Y84967D01*
G01X226344Y84969D02*
X226341Y84968D01*
G01X226348Y84970D02*
X226344Y84969D01*
G01X226351Y84971D02*
X226348Y84970D01*
G01X226355Y84972D02*
X226351Y84971D01*
G01X226358Y84972D02*
X226355D01*
G01X225572Y86969D02*
X225138D01*
G01X225945D02*
X225572D01*
G01Y93268D02*
X225138D01*
G01X225945D02*
X225572D01*
G01X227281Y86921D02*
X227284Y86923D01*
G01X227278Y86920D02*
X227281Y86921D01*
G01X227274Y86919D02*
X227278Y86920D01*
G01X227271Y86919D02*
X227274D01*
G01X227267Y86918D02*
X227271Y86919D01*
G01X227264Y86918D02*
X227267D01*
G01X226341Y88118D02*
X226338Y88116D01*
G01X226344Y88119D02*
X226341Y88118D01*
G01X226348Y88120D02*
X226344Y88119D01*
G01X226351Y88121D02*
X226348Y88120D01*
G01X226355Y88121D02*
X226351D01*
G01X226358D02*
X226355D01*
G01X227281Y90071D02*
X227284Y90073D01*
G01X227278Y90070D02*
X227281Y90071D01*
G01X227274Y90069D02*
X227278Y90070D01*
G01X227271Y90068D02*
X227274Y90069D01*
G01X227267Y90068D02*
X227271D01*
G01X227264Y90067D02*
X227267Y90068D01*
G01X226341Y91267D02*
X226338Y91266D01*
G01X226344Y91269D02*
X226341Y91267D01*
G01X226348Y91270D02*
X226344Y91269D01*
G01X226351Y91270D02*
X226348D01*
G01X226355Y91271D02*
X226351Y91270D01*
G01X226358Y91271D02*
X226355D01*
G01X227281Y93220D02*
X227284Y93222D01*
G01X227278Y93219D02*
X227281Y93220D01*
G01X227274Y93219D02*
X227278D01*
G01X227271Y93218D02*
X227274Y93219D01*
G01X227267Y93217D02*
X227271Y93218D01*
G01X227264Y93217D02*
X227267D01*
G01X226332Y91251D02*
X226356Y91260D01*
G01X226321Y91237D02*
X226332Y91251D01*
G01X226319Y91230D02*
X226321Y91237D01*
G01X226332Y88102D02*
X226356Y88110D01*
G01X226321Y88087D02*
X226332Y88102D01*
G01X226319Y88080D02*
X226321Y88087D01*
G01X226332Y84952D02*
X226356Y84961D01*
G01X226321Y84937D02*
X226332Y84952D01*
G01X226319Y84931D02*
X226321Y84937D01*
G01X227303Y91227D02*
Y91234D01*
G01Y91222D02*
Y91227D01*
G01X227302Y91220D02*
X227303Y91222D01*
G01Y88077D02*
Y88084D01*
G01Y88072D02*
Y88077D01*
G01X227302Y88071D02*
X227303Y88072D01*
G01Y84928D02*
Y84935D01*
G01Y84923D02*
Y84928D01*
G01X227302Y84921D02*
X227303Y84923D01*
G01X226319Y93262D02*
Y93254D01*
G01X226318Y93266D02*
X226319Y93262D01*
G01X226317Y93263D02*
X226318Y93266D01*
G01X226322Y84941D02*
X226317Y84921D01*
G01X226336Y84955D02*
X226322Y84941D01*
G01X226356Y84961D02*
X226336Y84955D01*
G01X226322Y88091D02*
X226317Y88071D01*
G01X226336Y88105D02*
X226322Y88091D01*
G01X226356Y88110D02*
X226336Y88105D01*
G01X226322Y91240D02*
X226317Y91220D01*
G01X226336Y91254D02*
X226322Y91240D01*
G01X226356Y91260D02*
X226336Y91254D01*
G01X227296Y83799D02*
X227302Y83819D01*
G01X227282Y83785D02*
X227296Y83799D01*
G01X227262Y83780D02*
X227282Y83785D01*
G01X227296Y86949D02*
X227302Y86969D01*
G01X227282Y86934D02*
X227296Y86949D01*
G01X227262Y86929D02*
X227282Y86934D01*
G01X227296Y90098D02*
X227302Y90118D01*
G01X227282Y90084D02*
X227296Y90098D01*
G01X227262Y90079D02*
X227282Y90084D01*
G01X227296Y93248D02*
X227302Y93268D01*
G01X227282Y93233D02*
X227296Y93248D01*
G01X227262Y93228D02*
X227282Y93233D01*
G01X226319Y86963D02*
Y86955D01*
G01X226318Y86967D02*
X226319Y86963D01*
G01X226317Y86965D02*
X226318Y86967D01*
G01X227264Y91265D02*
Y91271D01*
G01X227263Y91261D02*
X227264Y91265D01*
G01X227262Y91260D02*
X227263Y91261D01*
G01X227264Y88115D02*
Y88121D01*
G01X227263Y88111D02*
X227264Y88115D01*
G01X227262Y88110D02*
X227263Y88111D01*
G01X227264Y84966D02*
Y84972D01*
G01X227263Y84962D02*
X227264Y84966D01*
G01X227262Y84961D02*
X227263Y84962D01*
G01X240729Y80622D02*
X240728Y80613D01*
G01X240730Y80628D02*
X240729Y80622D01*
G01X240731Y80630D02*
X240730Y80628D01*
G01X240729Y75622D02*
X240728Y75613D01*
G01X240730Y75628D02*
X240729Y75622D01*
G01X240731Y75630D02*
X240730Y75628D01*
G01X240729Y70622D02*
X240728Y70613D01*
G01X240730Y70628D02*
X240729Y70622D01*
G01X240731Y70630D02*
X240730Y70628D01*
G01X240729Y65622D02*
X240728Y65613D01*
G01X240730Y65628D02*
X240729Y65622D01*
G01X240731Y65630D02*
X240730Y65628D01*
G01X240729Y60622D02*
X240728Y60613D01*
G01X240730Y60628D02*
X240729Y60622D01*
G01X240731Y60630D02*
X240730Y60628D01*
G01X240729Y55622D02*
X240728Y55613D01*
G01X240730Y55628D02*
X240729Y55622D01*
G01X240731Y55630D02*
X240730Y55628D01*
G01X240729Y50622D02*
X240728Y50613D01*
G01X240730Y50628D02*
X240729Y50622D01*
G01X240731Y50630D02*
X240730Y50628D01*
G01X226319Y91226D02*
Y91234D01*
G01X226318Y91222D02*
X226319Y91226D01*
G01X226317Y91220D02*
X226318Y91222D01*
G01X226319Y88077D02*
Y88084D01*
G01X226318Y88072D02*
X226319Y88077D01*
G01X226317Y88071D02*
X226318Y88072D01*
G01X226319Y84927D02*
Y84935D01*
G01X226318Y84923D02*
X226319Y84927D01*
G01X226317Y84921D02*
X226318Y84923D01*
G01X227301Y93242D02*
X227303Y93254D01*
G01X227294Y93230D02*
X227301Y93242D01*
G01X227284Y93222D02*
X227294Y93230D01*
G01X227301Y90092D02*
X227303Y90104D01*
G01X227294Y90081D02*
X227301Y90092D01*
G01X227284Y90073D02*
X227294Y90081D01*
G01X227301Y86943D02*
X227303Y86955D01*
G01X227294Y86931D02*
X227301Y86943D01*
G01X227284Y86923D02*
X227294Y86931D01*
G01X227301Y83793D02*
X227303Y83805D01*
G01X227294Y83781D02*
X227301Y83793D01*
G01X227284Y83774D02*
X227294Y83781D01*
G01X226357Y91265D02*
Y91271D01*
G01Y91261D02*
Y91265D01*
G01X226356Y91260D02*
X226357Y91261D01*
G01Y88115D02*
Y88121D01*
G01Y88111D02*
Y88115D01*
G01X226356Y88110D02*
X226357Y88111D01*
G01Y84965D02*
Y84972D01*
G01Y84962D02*
Y84965D01*
G01X226356Y84961D02*
X226357Y84962D01*
G01X226320Y91240D02*
X226319Y91234D01*
G01X226321Y91246D02*
X226320Y91240D01*
G01X226324Y91252D02*
X226321Y91246D01*
G01X226328Y91257D02*
X226324Y91252D01*
G01X226333Y91262D02*
X226328Y91257D01*
G01X226338Y91266D02*
X226333Y91262D01*
G01X226320Y88091D02*
X226319Y88084D01*
G01X226321Y88097D02*
X226320Y88091D01*
G01X226324Y88103D02*
X226321Y88097D01*
G01X226328Y88108D02*
X226324Y88103D01*
G01X226333Y88113D02*
X226328Y88108D01*
G01X226338Y88116D02*
X226333Y88113D01*
G01X226320Y84941D02*
X226319Y84935D01*
G01X226321Y84947D02*
X226320Y84941D01*
G01X226324Y84953D02*
X226321Y84947D01*
G01X226328Y84958D02*
X226324Y84953D01*
G01X226333Y84963D02*
X226328Y84958D01*
G01X226338Y84967D02*
X226333Y84963D01*
G01X227274Y93230D02*
X227262Y93228D01*
G01X227285Y93235D02*
X227274Y93230D01*
G01Y90081D02*
X227262Y90079D01*
G01X227285Y90085D02*
X227274Y90081D01*
G01Y86931D02*
X227262Y86929D01*
G01X227285Y86936D02*
X227274Y86931D01*
G01Y83781D02*
X227262Y83780D01*
G01X227285Y83786D02*
X227274Y83781D01*
G01X244094Y23760D02*
G03X246063Y25728I1J1968D01*
G01X231299Y25138D02*
G03X231890Y24547I591J0D01*
G01X238583D02*
G03X239173Y25138I-1J591D01*
G01X236417Y26319D02*
G03Y28287I0J984D01*
G01X234055D02*
G03Y26319I0J-984D01*
G01X236339Y39508D02*
G03I-1103J0D01*
G01X237795Y34232D02*
G03X238976Y35413I0J1181D01*
G01X231496D02*
G03X232677Y34232I1181J0D01*
G01X236811Y39508D02*
G03I-1575J0D01*
G01X224409Y25728D02*
G03X226378Y23760I1969J1D01*
G01X230709Y47500D02*
X229528Y46319D01*
G01X227756Y44823D02*
X224409Y41476D01*
G01X237721Y42579D02*
X236417Y40610D01*
G01X231745Y34688D02*
X234055Y38917D01*
G01X226317Y93263D02*
X226206Y93268D01*
G01X226317Y86965D02*
X226206Y86969D01*
G01X227302Y93268D02*
X221378D01*
G01X227262Y93228D02*
X221378D01*
G01X226319Y93071D02*
X227303D01*
G01X226358Y93031D02*
X227264D01*
G01Y91457D02*
X226358D01*
G01X227303Y91417D02*
X226319D01*
G01X227262Y91260D02*
X221378D01*
G01Y91220D02*
X227302D01*
G01Y90118D02*
X221378D01*
G01X227262Y90079D02*
X221378D01*
G01X226319Y89921D02*
X227303D01*
G01X226358Y89882D02*
X227264D01*
G01Y88307D02*
X226358D01*
G01X227303Y88268D02*
X226319D01*
G01X227262Y88110D02*
X221378D01*
G01Y88071D02*
X227302D01*
G01Y86969D02*
X221378D01*
G01X227262Y86929D02*
X221378D01*
G01X226319Y86772D02*
X227303D01*
G01X226358Y86732D02*
X227264D01*
G01Y85157D02*
X226358D01*
G01X227303Y85118D02*
X226319D01*
G01X227262Y84961D02*
X221378D01*
G01Y84921D02*
X227302D01*
G01X240157Y83957D02*
X236220D01*
G01X227302Y83819D02*
X221378D01*
G01X227262Y83780D02*
X221378D01*
G01X226319Y83622D02*
X227303D01*
G01X226358Y83583D02*
X227264D01*
G01X241339Y82776D02*
X237402D01*
G01X240728Y82500D02*
X239744D01*
G01X239746Y82008D02*
X245079D01*
G01Y81969D02*
X240731D01*
G01X227756Y81614D02*
X224409D01*
G01X245079Y80630D02*
X239746D01*
G01X239744Y80138D02*
X240728D01*
G01Y77500D02*
X239744D01*
G01X239746Y77008D02*
X245079D01*
G01Y76969D02*
X240731D01*
G01X245079Y75630D02*
X239746D01*
G01X239744Y75138D02*
X240728D01*
G01Y72500D02*
X239744D01*
G01X239746Y72008D02*
X245079D01*
G01Y71969D02*
X240731D01*
G01X245079Y70630D02*
X239746D01*
G01X239744Y70138D02*
X240728D01*
G01Y67500D02*
X239744D01*
G01X239746Y67008D02*
X245079D01*
G01Y66969D02*
X240731D01*
G01X245079Y65630D02*
X239746D01*
G01X239744Y65138D02*
X240728D01*
G01Y62500D02*
X239744D01*
G01X239746Y62008D02*
X245079D01*
G01Y61969D02*
X240731D01*
G01X245079Y60630D02*
X239746D01*
G01X239744Y60138D02*
X240728D01*
G01Y57500D02*
X239744D01*
G01X239746Y57008D02*
X245079D01*
G01Y56969D02*
X240731D01*
G01X245079Y55630D02*
X239746D01*
G01X239744Y55138D02*
X240728D01*
G01Y52500D02*
X239744D01*
G01X239746Y52008D02*
X245079D01*
G01Y51969D02*
X240731D01*
G01X245079Y50630D02*
X239746D01*
G01X239744Y50138D02*
X240728D01*
G01X236220Y47500D02*
X230709D01*
G01X237402Y46319D02*
X229528D01*
G01X242717Y44823D02*
X227756D01*
G01X238976Y43957D02*
X242126D01*
G01X231496D02*
X227756D01*
G01Y42579D02*
X242126D01*
G01X236417Y40610D02*
X234055D01*
G01X236417Y38917D02*
X234055D01*
G01X239744Y82204D02*
X240699Y82205D01*
G01X240728Y80434D02*
X239744Y80433D01*
G01Y77204D02*
X240699Y77205D01*
G01X240728Y75434D02*
X239744Y75433D01*
G01Y72204D02*
X240699Y72205D01*
G01X240728Y70434D02*
X239744Y70433D01*
G01Y67204D02*
X240699Y67205D01*
G01X240728Y65434D02*
X239744Y65433D01*
G01Y62204D02*
X240699Y62205D01*
G01X240728Y60434D02*
X239744Y60433D01*
G01Y57204D02*
X240699Y57205D01*
G01X240728Y55434D02*
X239744Y55433D01*
G01Y52204D02*
X240699Y52205D01*
G01X240728Y50434D02*
X239744Y50433D01*
G01X227303Y84923D02*
Y84935D01*
G01Y88073D02*
Y88084D01*
G01Y91222D02*
Y91234D01*
G01X240728Y51982D02*
X240729Y51991D01*
G01X240728Y56982D02*
X240729Y56991D01*
G01X240728Y61982D02*
X240729Y61991D01*
G01X240728Y66982D02*
X240729Y66991D01*
G01X240728Y71982D02*
X240729Y71991D01*
G01X240728Y76982D02*
X240729Y76991D01*
G01X240728Y81982D02*
X240729Y81991D01*
G01X246063Y25728D02*
Y41476D01*
G01X245079Y80630D02*
Y82008D01*
G01Y75630D02*
Y77008D01*
G01Y70630D02*
Y72008D01*
G01Y65630D02*
Y67008D01*
G01Y60630D02*
Y62008D01*
G01Y55630D02*
Y57008D01*
G01Y50630D02*
Y52008D01*
G01X242717Y182815D02*
Y44823D01*
G01X242126Y185059D02*
Y42579D01*
G01X241909Y52008D02*
Y50630D01*
G01Y57008D02*
Y55630D01*
G01Y62008D02*
Y60630D01*
G01Y67008D02*
Y65630D01*
G01Y72008D02*
Y70630D01*
G01Y77008D02*
Y75630D01*
G01Y82008D02*
Y80630D01*
G01X241339Y104862D02*
Y82776D01*
G01X240728Y51982D02*
Y52125D01*
G01Y61982D02*
Y62125D01*
G01Y56982D02*
Y57125D01*
G01Y71982D02*
Y72125D01*
G01Y66982D02*
Y67125D01*
G01Y81982D02*
Y82125D01*
G01Y76982D02*
Y77125D01*
G01Y80138D02*
Y82500D01*
G01Y75138D02*
Y77500D01*
G01Y70138D02*
Y72500D01*
G01Y65138D02*
Y67500D01*
G01Y60138D02*
Y62500D01*
G01Y55138D02*
Y57500D01*
G01Y50138D02*
Y52500D01*
G01X240157Y103681D02*
Y83957D01*
G01X239744Y52500D02*
Y50138D01*
G01Y57500D02*
Y55138D01*
G01Y62500D02*
Y60138D01*
G01Y67500D02*
Y65138D01*
G01Y72500D02*
Y70138D01*
G01Y77500D02*
Y75138D01*
G01Y82500D02*
Y80138D01*
G01X239173Y31240D02*
Y25138D01*
G01X237795Y34232D02*
X232677D01*
G01X246063Y34193D02*
X224409D01*
G01X239173Y31240D02*
X231299D01*
G01Y29665D02*
X239173D01*
G01X236417Y28287D02*
X234055D01*
G01Y26319D02*
X236417D01*
G01X238583Y24547D02*
X231890D01*
G01X244094Y23760D02*
X226378D01*
G01X238976Y43957D02*
Y35413D01*
G01X237402Y82776D02*
Y46319D01*
G01X236417Y40610D02*
Y38917D01*
G01X236220Y83957D02*
Y47500D01*
G01X234055Y38917D02*
Y40610D01*
G01X231496Y35413D02*
Y43957D01*
G01X231299Y31240D02*
Y25138D01*
G01X230709Y47500D02*
Y180138D01*
G01X229528Y46319D02*
Y181319D01*
G01X227756Y81614D02*
Y42579D01*
G01X227303Y93070D02*
Y94567D01*
G01Y89921D02*
Y91417D01*
G01Y86771D02*
Y88268D01*
G01Y83622D02*
Y85118D01*
G01X227264Y86918D02*
Y86771D01*
G01Y83768D02*
Y83621D01*
G01Y85119D02*
Y84972D01*
G01Y90067D02*
Y89920D01*
G01Y91418D02*
Y91271D01*
G01Y88268D02*
Y88121D01*
G01Y93217D02*
Y93070D01*
G01X226358D02*
Y93217D01*
G01Y89920D02*
Y90067D01*
G01Y91271D02*
Y91418D01*
G01Y88121D02*
Y88268D01*
G01Y86771D02*
Y86918D01*
G01Y83621D02*
Y83768D01*
G01Y84972D02*
Y85119D01*
G01X226319Y85118D02*
Y83622D01*
G01Y91417D02*
Y89921D01*
G01Y88268D02*
Y86772D01*
G01Y94567D02*
Y93071D01*
G01X225138Y88110D02*
Y86929D01*
G01Y84961D02*
Y83780D01*
G01Y91260D02*
Y90079D01*
G01Y94409D02*
Y93228D01*
G01X224803Y106024D02*
Y81614D01*
G01X224409D02*
Y106024D01*
G01Y41476D02*
Y25728D01*
G01X221378Y93228D02*
Y94409D01*
G01Y90079D02*
Y91260D01*
G01Y86929D02*
Y88110D01*
G01Y83780D02*
Y84961D01*
G01X227303Y93254D02*
Y93265D01*
G01Y90105D02*
Y90115D01*
G01Y86955D02*
Y86966D01*
G01Y83806D02*
Y83816D01*
G01X236417Y38917D02*
X238728Y34688D01*
G01X234055Y40610D02*
X232752Y42579D01*
G01X240157Y83957D02*
X241339Y82776D01*
G01X236220Y83957D02*
X237402Y82776D01*
G01X242717Y44823D02*
X246063Y41476D01*
G01X236220Y47500D02*
X237402Y46319D01*
G01X226358Y96373D02*
Y96367D01*
G01X226357Y96377D02*
X226358Y96373D01*
G01X226356Y96378D02*
X226357Y96377D01*
G01X226358Y99522D02*
Y99516D01*
G01X226357Y99526D02*
X226358Y99522D01*
G01X226356Y99528D02*
X226357Y99526D01*
G01X226358Y102672D02*
Y102666D01*
G01X226357Y102676D02*
X226358Y102672D01*
G01X226356Y102677D02*
X226357Y102676D01*
G01X240729Y106975D02*
X240728Y106982D01*
G01X240730Y106970D02*
X240729Y106975D01*
G01X240731Y106969D02*
X240730Y106970D01*
G01X226342Y96380D02*
X226356Y96378D01*
G01X226330Y96388D02*
X226342Y96380D01*
G01X226318Y96406D02*
X226330Y96388D01*
G01X227272Y94408D02*
X227262Y94409D01*
G01X227281Y94405D02*
X227272Y94408D01*
G01X227288Y94400D02*
X227281Y94405D01*
G01X227272Y97558D02*
X227262Y97559D01*
G01X227281Y97555D02*
X227272Y97558D01*
G01X227288Y97549D02*
X227281Y97555D01*
G01X227272Y100707D02*
X227262Y100709D01*
G01X227281Y100704D02*
X227272Y100707D01*
G01X227288Y100699D02*
X227281Y100704D01*
G01X227272Y103857D02*
X227262Y103858D01*
G01X227281Y103854D02*
X227272Y103857D01*
G01X227288Y103848D02*
X227281Y103854D01*
G01X240729Y111975D02*
X240728Y111982D01*
G01X240730Y111970D02*
X240729Y111975D01*
G01X240731Y111969D02*
X240730Y111970D01*
G01X240729Y116975D02*
X240728Y116982D01*
G01X240730Y116970D02*
X240729Y116975D01*
G01X240731Y116969D02*
X240730Y116970D01*
G01X240729Y121975D02*
X240728Y121982D01*
G01X240730Y121970D02*
X240729Y121975D01*
G01X240731Y121969D02*
X240730Y121970D01*
G01X240729Y126975D02*
X240728Y126982D01*
G01X240730Y126970D02*
X240729Y126975D01*
G01X240731Y126969D02*
X240730Y126970D01*
G01X240729Y131975D02*
X240728Y131982D01*
G01X240730Y131970D02*
X240729Y131975D01*
G01X240731Y131969D02*
X240730Y131970D01*
G01X240729Y136975D02*
X240728Y136982D01*
G01X240730Y136970D02*
X240729Y136975D01*
G01X240731Y136969D02*
X240730Y136970D01*
G01X240729Y141975D02*
X240728Y141982D01*
G01X240730Y141970D02*
X240729Y141975D01*
G01X240731Y141969D02*
X240730Y141970D01*
G01X240729Y146975D02*
X240728Y146982D01*
G01X240730Y146970D02*
X240729Y146975D01*
G01X240731Y146969D02*
X240730Y146970D01*
G01X240729Y151975D02*
X240728Y151982D01*
G01X240730Y151970D02*
X240729Y151975D01*
G01X240731Y151969D02*
X240730Y151970D01*
G01X240729Y156975D02*
X240728Y156982D01*
G01X240730Y156970D02*
X240729Y156975D01*
G01X240731Y156969D02*
X240730Y156970D01*
G01X240729Y161975D02*
X240728Y161982D01*
G01X240730Y161970D02*
X240729Y161975D01*
G01X240731Y161969D02*
X240730Y161970D01*
G01X240729Y166975D02*
X240728Y166982D01*
G01X240730Y166970D02*
X240729Y166975D01*
G01X240731Y166969D02*
X240730Y166970D01*
G01X240729Y171975D02*
X240728Y171982D01*
G01X240730Y171970D02*
X240729Y171975D01*
G01X240731Y171969D02*
X240730Y171970D01*
G01X240729Y176975D02*
X240728Y176982D01*
G01X240730Y176970D02*
X240729Y176975D01*
G01X240731Y176969D02*
X240730Y176970D01*
G01X226341Y99530D02*
X226356Y99528D01*
G01X226329Y99538D02*
X226341Y99530D01*
G01X226317Y99558D02*
X226329Y99538D01*
G01X227303Y96411D02*
Y96404D01*
G01X227302Y96416D02*
X227303Y96411D01*
G01X227302Y96417D02*
Y96416D01*
G01X227303Y99561D02*
Y99553D01*
G01X227302Y99565D02*
X227303Y99561D01*
G01X227302Y99567D02*
Y99565D01*
G01X227303Y102711D02*
Y102703D01*
G01X227302Y102715D02*
X227303Y102711D01*
G01X227302Y102717D02*
Y102715D01*
G01X226341Y102680D02*
X226356Y102677D01*
G01X226329Y102688D02*
X226341Y102680D01*
G01X226317Y102708D02*
X226329Y102688D01*
G01X227302Y94390D02*
X227303Y94383D01*
G01X227301Y94396D02*
X227302Y94390D01*
G01X227298Y94402D02*
X227301Y94396D01*
G01X227302Y97540D02*
X227303Y97533D01*
G01X227301Y97546D02*
X227302Y97540D01*
G01X227298Y97552D02*
X227301Y97546D01*
G01X227302Y100689D02*
X227303Y100683D01*
G01X227301Y100696D02*
X227302Y100689D01*
G01X227298Y100702D02*
X227301Y100696D01*
G01X227302Y103839D02*
X227303Y103832D01*
G01X227301Y103845D02*
X227302Y103839D01*
G01X227298Y103851D02*
X227301Y103845D01*
G01X227264Y96373D02*
X227265Y96367D01*
G01X227263Y96376D02*
X227264Y96373D01*
G01X227262Y96378D02*
X227263Y96376D01*
G01X227264Y102672D02*
X227265Y102666D01*
G01X227263Y102676D02*
X227264Y102672D01*
G01X227262Y102677D02*
X227263Y102676D01*
G01X239744Y107015D02*
Y107024D01*
G01X239745Y107009D02*
X239744Y107015D01*
G01X239746Y107008D02*
X239745Y107009D01*
G01X239744Y112015D02*
Y112024D01*
G01X239745Y112009D02*
X239744Y112015D01*
G01X239746Y112008D02*
X239745Y112009D01*
G01X239744Y117015D02*
Y117024D01*
G01X239745Y117009D02*
X239744Y117015D01*
G01X239746Y117008D02*
X239745Y117009D01*
G01X239744Y122015D02*
Y122024D01*
G01X239745Y122009D02*
X239744Y122015D01*
G01X239746Y122008D02*
X239745Y122009D01*
G01X239744Y127015D02*
Y127024D01*
G01X239745Y127009D02*
X239744Y127015D01*
G01X239746Y127008D02*
X239745Y127009D01*
G01X239744Y132015D02*
Y132024D01*
G01X239745Y132009D02*
X239744Y132015D01*
G01X239746Y132008D02*
X239745Y132009D01*
G01X239744Y137015D02*
Y137024D01*
G01X239745Y137009D02*
X239744Y137015D01*
G01X239746Y137008D02*
X239745Y137009D01*
G01X239744Y142015D02*
Y142024D01*
G01X239745Y142009D02*
X239744Y142015D01*
G01X239746Y142008D02*
X239745Y142009D01*
G01X239744Y147015D02*
Y147024D01*
G01X239745Y147009D02*
X239744Y147015D01*
G01X239746Y147008D02*
X239745Y147009D01*
G01X239744Y152015D02*
Y152024D01*
G01X239745Y152009D02*
X239744Y152015D01*
G01X239746Y152008D02*
X239745Y152009D01*
G01X239744Y157015D02*
Y157024D01*
G01X239745Y157009D02*
X239744Y157015D01*
G01X239746Y157008D02*
X239745Y157009D01*
G01X239744Y162015D02*
Y162024D01*
G01X239745Y162009D02*
X239744Y162015D01*
G01X239746Y162008D02*
X239745Y162009D01*
G01X239744Y167015D02*
Y167024D01*
G01X239745Y167009D02*
X239744Y167015D01*
G01X239746Y167008D02*
X239745Y167009D01*
G01X239744Y172015D02*
Y172024D01*
G01X239745Y172009D02*
X239744Y172015D01*
G01X239746Y172008D02*
X239745Y172009D01*
G01X239744Y177015D02*
Y177024D01*
G01X239745Y177009D02*
X239744Y177015D01*
G01X239746Y177008D02*
X239745Y177009D01*
G01X240720Y107152D02*
X240728Y107125D01*
G01X240711Y107178D02*
X240720Y107152D01*
G01X240699Y107205D02*
X240711Y107178D01*
G01X240720Y112152D02*
X240728Y112125D01*
G01X240711Y112178D02*
X240720Y112152D01*
G01X240699Y112205D02*
X240711Y112178D01*
G01X240720Y117152D02*
X240728Y117125D01*
G01X240711Y117178D02*
X240720Y117152D01*
G01X240699Y117205D02*
X240711Y117178D01*
G01X240720Y122152D02*
X240728Y122125D01*
G01X240711Y122178D02*
X240720Y122152D01*
G01X240699Y122205D02*
X240711Y122178D01*
G01X240720Y127152D02*
X240728Y127125D01*
G01X240711Y127178D02*
X240720Y127152D01*
G01X240699Y127205D02*
X240711Y127178D01*
G01X240720Y132152D02*
X240728Y132125D01*
G01X240711Y132178D02*
X240720Y132152D01*
G01X240699Y132205D02*
X240711Y132178D01*
G01X240720Y137152D02*
X240728Y137125D01*
G01X240711Y137178D02*
X240720Y137152D01*
G01X240699Y137205D02*
X240711Y137178D01*
G01X240720Y142152D02*
X240728Y142125D01*
G01X240711Y142178D02*
X240720Y142152D01*
G01X240699Y142205D02*
X240711Y142178D01*
G01X240720Y147152D02*
X240728Y147125D01*
G01X240711Y147178D02*
X240720Y147152D01*
G01X240699Y147205D02*
X240711Y147178D01*
G01X240720Y152152D02*
X240728Y152125D01*
G01X240711Y152178D02*
X240720Y152152D01*
G01X240699Y152205D02*
X240711Y152178D01*
G01X240720Y157152D02*
X240728Y157125D01*
G01X240711Y157178D02*
X240720Y157152D01*
G01X240699Y157205D02*
X240711Y157178D01*
G01X240720Y162152D02*
X240728Y162125D01*
G01X240711Y162178D02*
X240720Y162152D01*
G01X240699Y162205D02*
X240711Y162178D01*
G01X240720Y167152D02*
X240728Y167125D01*
G01X240711Y167178D02*
X240720Y167152D01*
G01X240699Y167205D02*
X240711Y167178D01*
G01X240720Y172152D02*
X240728Y172125D01*
G01X240711Y172178D02*
X240720Y172152D01*
G01X240699Y172205D02*
X240711Y172178D01*
G01X240720Y177152D02*
X240728Y177125D01*
G01X240711Y177178D02*
X240720Y177152D01*
G01X240699Y177205D02*
X240711Y177178D01*
G01X226319Y96407D02*
Y96404D01*
G01X226320Y96401D02*
X226319Y96407D01*
G01X226332Y96386D02*
X226320Y96401D01*
G01X226356Y96378D02*
X226332Y96386D01*
G01X226319Y99557D02*
Y99553D01*
G01X226320Y99551D02*
X226319Y99557D01*
G01X226332Y99536D02*
X226320Y99551D01*
G01X226356Y99528D02*
X226332Y99536D01*
G01X226319Y102707D02*
Y102703D01*
G01X226320Y102701D02*
X226319Y102707D01*
G01X226332Y102685D02*
X226320Y102701D01*
G01X226356Y102677D02*
X226332Y102685D01*
G01X240716Y106999D02*
X240727Y106984D01*
G01X240691Y107008D02*
X240716Y106999D01*
G01Y111999D02*
X240727Y111984D01*
G01X240691Y112008D02*
X240716Y111999D01*
G01Y116999D02*
X240727Y116984D01*
G01X240691Y117008D02*
X240716Y116999D01*
G01Y121999D02*
X240727Y121984D01*
G01X240691Y122008D02*
X240716Y121999D01*
G01Y126999D02*
X240727Y126984D01*
G01X240691Y127008D02*
X240716Y126999D01*
G01Y131999D02*
X240727Y131984D01*
G01X240691Y132008D02*
X240716Y131999D01*
G01Y136999D02*
X240727Y136984D01*
G01X240691Y137008D02*
X240716Y136999D01*
G01Y141999D02*
X240727Y141984D01*
G01X240691Y142008D02*
X240716Y141999D01*
G01Y146999D02*
X240727Y146984D01*
G01X240691Y147008D02*
X240716Y146999D01*
G01Y151999D02*
X240727Y151984D01*
G01X240691Y152008D02*
X240716Y151999D01*
G01Y156999D02*
X240727Y156984D01*
G01X240691Y157008D02*
X240716Y156999D01*
G01X240711Y107003D02*
X240692Y107008D01*
G01X240726Y106988D02*
X240711Y107003D01*
G01X240731Y106969D02*
X240726Y106988D01*
G01X240711Y112003D02*
X240692Y112008D01*
G01X240726Y111988D02*
X240711Y112003D01*
G01X240731Y111969D02*
X240726Y111988D01*
G01X240711Y117003D02*
X240692Y117008D01*
G01X240726Y116988D02*
X240711Y117003D01*
G01X240731Y116969D02*
X240726Y116988D01*
G01X240711Y122003D02*
X240692Y122008D01*
G01X240726Y121988D02*
X240711Y122003D01*
G01X240731Y121969D02*
X240726Y121988D01*
G01X240711Y127003D02*
X240692Y127008D01*
G01X240726Y126988D02*
X240711Y127003D01*
G01X240731Y126969D02*
X240726Y126988D01*
G01X240711Y132003D02*
X240692Y132008D01*
G01X240726Y131988D02*
X240711Y132003D01*
G01X240731Y131969D02*
X240726Y131988D01*
G01X240711Y137003D02*
X240692Y137008D01*
G01X240726Y136988D02*
X240711Y137003D01*
G01X240731Y136969D02*
X240726Y136988D01*
G01X240711Y142003D02*
X240692Y142008D01*
G01X240726Y141988D02*
X240711Y142003D01*
G01X240731Y141969D02*
X240726Y141988D01*
G01X240711Y147003D02*
X240692Y147008D01*
G01X240726Y146988D02*
X240711Y147003D01*
G01X240731Y146969D02*
X240726Y146988D01*
G01X240711Y152003D02*
X240692Y152008D01*
G01X240726Y151988D02*
X240711Y152003D01*
G01X240731Y151969D02*
X240726Y151988D01*
G01X240711Y157003D02*
X240692Y157008D01*
G01X240726Y156988D02*
X240711Y157003D01*
G01X240731Y156969D02*
X240726Y156988D01*
G01X240711Y162003D02*
X240692Y162008D01*
G01X240726Y161988D02*
X240711Y162003D01*
G01X240731Y161969D02*
X240726Y161988D01*
G01X240711Y167003D02*
X240692Y167008D01*
G01X240726Y166988D02*
X240711Y167003D01*
G01X240731Y166969D02*
X240726Y166988D01*
G01X240711Y172003D02*
X240692Y172008D01*
G01X240726Y171988D02*
X240711Y172003D01*
G01X240731Y171969D02*
X240726Y171988D01*
G01X240711Y177003D02*
X240692Y177008D01*
G01X240726Y176988D02*
X240711Y177003D01*
G01X240731Y176969D02*
X240726Y176988D01*
G01X227296Y94391D02*
X227288Y94400D01*
G01X227300Y94381D02*
X227296Y94391D01*
G01X227302Y94370D02*
X227300Y94381D01*
G01X227296Y97541D02*
X227288Y97549D01*
G01X227300Y97531D02*
X227296Y97541D01*
G01X227302Y97520D02*
X227300Y97531D01*
G01X227296Y100691D02*
X227288Y100699D01*
G01X227300Y100680D02*
X227296Y100691D01*
G01X227302Y100669D02*
X227300Y100680D01*
G01X227296Y103840D02*
X227288Y103848D01*
G01X227300Y103830D02*
X227296Y103840D01*
G01X227302Y103819D02*
X227300Y103830D01*
G01X240695Y107106D02*
X240699Y107205D01*
G01X240690Y107034D02*
X240695Y107106D01*
G01X240692Y107008D02*
X240690Y107034D01*
G01X240695Y112106D02*
X240699Y112205D01*
G01X240690Y112034D02*
X240695Y112106D01*
G01X240692Y112008D02*
X240690Y112034D01*
G01X240695Y117106D02*
X240699Y117205D01*
G01X240690Y117034D02*
X240695Y117106D01*
G01X240692Y117008D02*
X240690Y117034D01*
G01X240695Y122106D02*
X240699Y122205D01*
G01X240690Y122034D02*
X240695Y122106D01*
G01X240692Y122008D02*
X240690Y122034D01*
G01X240695Y127106D02*
X240699Y127205D01*
G01X240690Y127034D02*
X240695Y127106D01*
G01X240692Y127008D02*
X240690Y127034D01*
G01X240695Y132106D02*
X240699Y132205D01*
G01X240690Y132034D02*
X240695Y132106D01*
G01X240692Y132008D02*
X240690Y132034D01*
G01X240695Y137106D02*
X240699Y137205D01*
G01X240690Y137034D02*
X240695Y137106D01*
G01X240692Y137008D02*
X240690Y137034D01*
G01X240695Y142106D02*
X240699Y142205D01*
G01X240690Y142034D02*
X240695Y142106D01*
G01X240692Y142008D02*
X240690Y142034D01*
G01X240695Y147106D02*
X240699Y147205D01*
G01X240690Y147034D02*
X240695Y147106D01*
G01X240692Y147008D02*
X240690Y147034D01*
G01X240695Y152106D02*
X240699Y152205D01*
G01X240690Y152034D02*
X240695Y152106D01*
G01X240692Y152008D02*
X240690Y152034D01*
G01X240695Y157106D02*
X240699Y157205D01*
G01X240690Y157034D02*
X240695Y157106D01*
G01X240692Y157008D02*
X240690Y157034D01*
G01X240695Y162106D02*
X240699Y162205D01*
G01X240690Y162034D02*
X240695Y162106D01*
G01X240692Y162008D02*
X240690Y162034D01*
G01X240695Y167106D02*
X240699Y167205D01*
G01X240690Y167034D02*
X240695Y167106D01*
G01X240692Y167008D02*
X240690Y167034D01*
G01X240695Y172106D02*
X240699Y172205D01*
G01X240690Y172034D02*
X240695Y172106D01*
G01X240692Y172008D02*
X240690Y172034D01*
G01X240695Y177106D02*
X240699Y177205D01*
G01X240690Y177034D02*
X240695Y177106D01*
G01X240692Y177008D02*
X240690Y177034D01*
G01X226319Y96411D02*
Y96404D01*
G01X226318Y96416D02*
X226319Y96411D01*
G01X226318Y96406D02*
Y96416D01*
G01X226359Y104043D02*
X226358Y104055D01*
G01X226356Y104030D02*
X226359Y104043D01*
G01X226356Y104016D02*
Y104030D01*
G01X226359Y100893D02*
X226358Y100906D01*
G01X226356Y100880D02*
X226359Y100893D01*
G01X226356Y100866D02*
Y100880D01*
G01X226359Y97743D02*
X226358Y97756D01*
G01X226356Y97730D02*
X226359Y97743D01*
G01X226356Y97717D02*
Y97730D01*
G01X226359Y94594D02*
X226358Y94606D01*
G01X226356Y94581D02*
X226359Y94594D01*
G01X226356Y94567D02*
Y94581D01*
G01X226320Y96396D02*
X226319Y96404D01*
G01X226322Y96389D02*
X226320Y96396D01*
G01X226326Y96383D02*
X226322Y96389D01*
G01X226330Y96378D02*
X226326Y96383D01*
G01X226337Y96373D02*
X226330Y96378D01*
G01X226343Y96369D02*
X226337Y96373D01*
G01X226351Y96367D02*
X226343Y96369D01*
G01X226358Y96367D02*
X226351D01*
G01X226320Y99546D02*
X226319Y99553D01*
G01X226322Y99539D02*
X226320Y99546D01*
G01X226326Y99533D02*
X226322Y99539D01*
G01X226330Y99527D02*
X226326Y99533D01*
G01X226337Y99522D02*
X226330Y99527D01*
G01X226343Y99519D02*
X226337Y99522D01*
G01X226351Y99517D02*
X226343Y99519D01*
G01X226358Y99516D02*
X226351Y99517D01*
G01X227273Y94408D02*
X227282Y94404D01*
G01X227262Y94409D02*
X227273Y94408D01*
G01Y97557D02*
X227282Y97554D01*
G01X227262Y97559D02*
X227273Y97557D01*
G01Y100707D02*
X227282Y100703D01*
G01X227262Y100709D02*
X227273Y100707D01*
G01Y103857D02*
X227282Y103853D01*
G01X227262Y103858D02*
X227273Y103857D01*
G01X240716Y161999D02*
X240727Y161984D01*
G01X240691Y162008D02*
X240716Y161999D01*
G01Y166999D02*
X240727Y166984D01*
G01X240691Y167008D02*
X240716Y166999D01*
G01Y171999D02*
X240727Y171984D01*
G01X240691Y172008D02*
X240716Y171999D01*
G01Y176999D02*
X240727Y176984D01*
G01X240691Y177008D02*
X240716Y176999D01*
G01X239745Y175628D02*
X239746Y175630D01*
G01X239744Y175622D02*
X239745Y175628D01*
G01X239744Y175614D02*
Y175622D01*
G01X239745Y170628D02*
X239746Y170630D01*
G01X239744Y170622D02*
X239745Y170628D01*
G01X239744Y170614D02*
Y170622D01*
G01X239745Y165628D02*
X239746Y165630D01*
G01X239744Y165622D02*
X239745Y165628D01*
G01X239744Y165614D02*
Y165622D01*
G01X239745Y160628D02*
X239746Y160630D01*
G01X239744Y160622D02*
X239745Y160628D01*
G01X239744Y160614D02*
Y160622D01*
G01X239745Y155628D02*
X239746Y155630D01*
G01X239744Y155622D02*
X239745Y155628D01*
G01X239744Y155614D02*
Y155622D01*
G01X239745Y150628D02*
X239746Y150630D01*
G01X239744Y150622D02*
X239745Y150628D01*
G01X239744Y150614D02*
Y150622D01*
G01X239745Y145628D02*
X239746Y145630D01*
G01X239744Y145622D02*
X239745Y145628D01*
G01X239744Y145614D02*
Y145622D01*
G01X239745Y140628D02*
X239746Y140630D01*
G01X239744Y140622D02*
X239745Y140628D01*
G01X239744Y140614D02*
Y140622D01*
G01X239745Y135628D02*
X239746Y135630D01*
G01X239744Y135622D02*
X239745Y135628D01*
G01X239744Y135614D02*
Y135622D01*
G01X239745Y130628D02*
X239746Y130630D01*
G01X239744Y130622D02*
X239745Y130628D01*
G01X239744Y130614D02*
Y130622D01*
G01X239745Y125628D02*
X239746Y125630D01*
G01X239744Y125622D02*
X239745Y125628D01*
G01X239744Y125614D02*
Y125622D01*
G01X239745Y120628D02*
X239746Y120630D01*
G01X239744Y120622D02*
X239745Y120628D01*
G01X239744Y120614D02*
Y120622D01*
G01X239745Y115628D02*
X239746Y115630D01*
G01X239744Y115622D02*
X239745Y115628D01*
G01X239744Y115614D02*
Y115622D01*
G01X239745Y110628D02*
X239746Y110630D01*
G01X239744Y110622D02*
X239745Y110628D01*
G01X239744Y110614D02*
Y110622D01*
G01X239745Y105628D02*
X239746Y105630D01*
G01X239744Y105622D02*
X239745Y105628D01*
G01X239744Y105614D02*
Y105622D01*
G01X226319Y102711D02*
Y102703D01*
G01X226318Y102715D02*
X226319Y102711D01*
G01X226318Y102707D02*
Y102715D01*
G01X226356Y102506D02*
X226355Y102519D01*
G01X226359Y102493D02*
X226356Y102506D01*
G01X226358Y102480D02*
X226359Y102493D01*
G01X226356Y99356D02*
X226355Y99370D01*
G01X226359Y99343D02*
X226356Y99356D01*
G01X226358Y99331D02*
X226359Y99343D01*
G01X226356Y96206D02*
X226355Y96220D01*
G01X226359Y96194D02*
X226356Y96206D01*
G01X226358Y96181D02*
X226359Y96194D01*
G01X227266Y104030D02*
X227267Y104016D01*
G01X227263Y104043D02*
X227266Y104030D01*
G01X227264Y104055D02*
X227263Y104043D01*
G01X227266Y100880D02*
X227267Y100866D01*
G01X227263Y100893D02*
X227266Y100880D01*
G01X227264Y100906D02*
X227263Y100893D01*
G01X227266Y97730D02*
X227267Y97717D01*
G01X227263Y97743D02*
X227266Y97730D01*
G01X227264Y97756D02*
X227263Y97743D01*
G01X227266Y94581D02*
X227267Y94567D01*
G01X227263Y94594D02*
X227266Y94581D01*
G01X227264Y94606D02*
X227263Y94594D01*
G01X226319Y99561D02*
Y99554D01*
G01X226318Y99565D02*
X226319Y99561D01*
G01X226317Y99558D02*
X226318Y99565D01*
G01X227263Y102493D02*
X227264Y102480D01*
G01X227266Y102506D02*
X227263Y102493D01*
G01X227267Y102519D02*
X227266Y102506D01*
G01X227263Y99343D02*
X227264Y99331D01*
G01X227266Y99356D02*
X227263Y99343D01*
G01X227267Y99370D02*
X227266Y99356D01*
G01X227263Y96194D02*
X227264Y96181D01*
G01X227266Y96206D02*
X227263Y96194D01*
G01X227267Y96220D02*
X227266Y96206D01*
G01X225572Y96417D02*
X225138D01*
G01X225945D02*
X225572D01*
G01X227294Y94408D02*
X227298Y94402D01*
G01X227289Y94412D02*
X227294Y94408D01*
G01X227283Y94416D02*
X227289Y94412D01*
G01X227277Y94419D02*
X227283Y94416D01*
G01X227270Y94420D02*
X227277Y94419D01*
G01X227264Y94420D02*
X227270D01*
G01X227294Y97557D02*
X227298Y97552D01*
G01X227289Y97562D02*
X227294Y97557D01*
G01X227283Y97565D02*
X227289Y97562D01*
G01X227277Y97568D02*
X227283Y97565D01*
G01X227270Y97570D02*
X227277Y97568D01*
G01X227264Y97570D02*
X227270D01*
G01X227294Y100707D02*
X227298Y100702D01*
G01X227289Y100711D02*
X227294Y100707D01*
G01X227283Y100715D02*
X227289Y100711D01*
G01X227277Y100718D02*
X227283Y100715D01*
G01X227270Y100719D02*
X227277Y100718D01*
G01X227264Y100720D02*
X227270Y100719D01*
G01X227294Y103857D02*
X227298Y103851D01*
G01X227289Y103861D02*
X227294Y103857D01*
G01X227283Y103865D02*
X227289Y103861D01*
G01X227277Y103867D02*
X227283Y103865D01*
G01X227270Y103869D02*
X227277Y103867D01*
G01X227264Y103869D02*
X227270D01*
G01X226320Y102696D02*
X226319Y102703D01*
G01X226322Y102689D02*
X226320Y102696D01*
G01X226326Y102682D02*
X226322Y102689D01*
G01X226330Y102677D02*
X226326Y102682D01*
G01X226337Y102672D02*
X226330Y102677D01*
G01X226343Y102669D02*
X226337Y102672D01*
G01X226351Y102667D02*
X226343Y102669D01*
G01X226358Y102666D02*
X226351Y102667D01*
G01X227302Y99546D02*
X227303Y99553D01*
G01X227300Y99539D02*
X227302Y99546D01*
G01X227296Y99533D02*
X227300Y99539D01*
G01X227292Y99527D02*
X227296Y99533D01*
G01X227285Y99522D02*
X227292Y99527D01*
G01X227279Y99519D02*
X227285Y99522D01*
G01X227272Y99517D02*
X227279Y99519D01*
G01X227264Y99516D02*
X227272Y99517D01*
G01X226341Y94417D02*
X226338Y94415D01*
G01X226344Y94418D02*
X226341Y94417D01*
G01X226348Y94419D02*
X226344Y94418D01*
G01X226351Y94420D02*
X226348Y94419D01*
G01X226355Y94420D02*
X226351D01*
G01X226358D02*
X226355D01*
G01X227281Y96370D02*
X227284Y96372D01*
G01X227278Y96369D02*
X227281Y96370D01*
G01X227274Y96368D02*
X227278Y96369D01*
G01X227271Y96367D02*
X227274Y96368D01*
G01X227267Y96367D02*
X227271D01*
G01X227264D02*
X227267D01*
G01X226341Y97567D02*
X226338Y97565D01*
G01X226344Y97568D02*
X226341Y97567D01*
G01X226348Y97569D02*
X226344Y97568D01*
G01X226351Y97570D02*
X226348Y97569D01*
G01X226355Y97570D02*
X226351D01*
G01X226358D02*
X226355D01*
G01X226341Y100716D02*
X226338Y100715D01*
G01X226344Y100717D02*
X226341Y100716D01*
G01X226348Y100719D02*
X226344Y100717D01*
G01X226351Y100719D02*
X226348D01*
G01X226355Y100720D02*
X226351Y100719D01*
G01X226358Y100720D02*
X226355D01*
G01X227281Y102669D02*
X227284Y102671D01*
G01X227278Y102668D02*
X227281Y102669D01*
G01X227274Y102667D02*
X227278Y102668D01*
G01X227271Y102667D02*
X227274D01*
G01X227267Y102666D02*
X227271Y102667D01*
G01X227264Y102666D02*
X227267D01*
G01X226341Y103866D02*
X226338Y103864D01*
G01X226344Y103867D02*
X226341Y103866D01*
G01X226348Y103868D02*
X226344Y103867D01*
G01X226351Y103869D02*
X226348Y103868D01*
G01X226355Y103869D02*
X226351D01*
G01X226358D02*
X226355D01*
G01X226332Y103850D02*
X226356Y103858D01*
G01X226321Y103835D02*
X226332Y103850D01*
G01X226319Y103828D02*
X226321Y103835D01*
G01X226332Y100700D02*
X226356Y100709D01*
G01X226321Y100685D02*
X226332Y100700D01*
G01X226319Y100679D02*
X226321Y100685D01*
G01X226332Y97550D02*
X226356Y97559D01*
G01X226321Y97536D02*
X226332Y97550D01*
G01X226319Y97529D02*
X226321Y97536D01*
G01X226332Y94401D02*
X226356Y94409D01*
G01X226321Y94386D02*
X226332Y94401D01*
G01X226319Y94380D02*
X226321Y94386D01*
G01X227303Y103825D02*
Y103832D01*
G01Y103820D02*
Y103825D01*
G01X227302Y103819D02*
X227303Y103820D01*
G01Y100676D02*
Y100683D01*
G01Y100671D02*
Y100676D01*
G01X227302Y100669D02*
X227303Y100671D01*
G01Y97526D02*
Y97533D01*
G01Y97521D02*
Y97526D01*
G01X227302Y97520D02*
X227303Y97521D01*
G01Y94376D02*
Y94383D01*
G01Y94372D02*
Y94376D01*
G01X227302Y94370D02*
X227303Y94372D01*
G01X226322Y94390D02*
X226317Y94370D01*
G01X226336Y94404D02*
X226322Y94390D01*
G01X226356Y94409D02*
X226336Y94404D01*
G01X226322Y97539D02*
X226317Y97520D01*
G01X226336Y97554D02*
X226322Y97539D01*
G01X226356Y97559D02*
X226336Y97554D01*
G01X226322Y100689D02*
X226317Y100669D01*
G01X226336Y100703D02*
X226322Y100689D01*
G01X226356Y100709D02*
X226336Y100703D01*
G01X226322Y103839D02*
X226317Y103819D01*
G01X226336Y103853D02*
X226322Y103839D01*
G01X226356Y103858D02*
X226336Y103853D01*
G01X227296Y96398D02*
X227302Y96417D01*
G01X227282Y96383D02*
X227296Y96398D01*
G01X227262Y96378D02*
X227282Y96383D01*
G01X227296Y99547D02*
X227302Y99567D01*
G01X227282Y99533D02*
X227296Y99547D01*
G01X227262Y99528D02*
X227282Y99533D01*
G01X227296Y102697D02*
X227302Y102717D01*
G01X227282Y102682D02*
X227296Y102697D01*
G01X227262Y102677D02*
X227282Y102682D01*
G01X227264Y103863D02*
Y103869D01*
G01X227263Y103859D02*
X227264Y103863D01*
G01X227262Y103858D02*
X227263Y103859D01*
G01X227264Y100714D02*
Y100720D01*
G01X227263Y100710D02*
X227264Y100714D01*
G01X227262Y100709D02*
X227263Y100710D01*
G01X227264Y97564D02*
Y97570D01*
G01X227263Y97560D02*
X227264Y97564D01*
G01X227262Y97559D02*
X227263Y97560D01*
G01X227264Y94415D02*
Y94420D01*
G01X227263Y94411D02*
X227264Y94415D01*
G01X227262Y94409D02*
X227263Y94411D01*
G01X240729Y175622D02*
X240728Y175613D01*
G01X240730Y175628D02*
X240729Y175622D01*
G01X240731Y175630D02*
X240730Y175628D01*
G01X240729Y170622D02*
X240728Y170613D01*
G01X240730Y170628D02*
X240729Y170622D01*
G01X240731Y170630D02*
X240730Y170628D01*
G01X240729Y165622D02*
X240728Y165613D01*
G01X240730Y165628D02*
X240729Y165622D01*
G01X240731Y165630D02*
X240730Y165628D01*
G01X240729Y160622D02*
X240728Y160613D01*
G01X240730Y160628D02*
X240729Y160622D01*
G01X240731Y160630D02*
X240730Y160628D01*
G01X240729Y155622D02*
X240728Y155613D01*
G01X240730Y155628D02*
X240729Y155622D01*
G01X240731Y155630D02*
X240730Y155628D01*
G01X240729Y150622D02*
X240728Y150613D01*
G01X240730Y150628D02*
X240729Y150622D01*
G01X240731Y150630D02*
X240730Y150628D01*
G01X240729Y145622D02*
X240728Y145613D01*
G01X240730Y145628D02*
X240729Y145622D01*
G01X240731Y145630D02*
X240730Y145628D01*
G01X240729Y140622D02*
X240728Y140613D01*
G01X240730Y140628D02*
X240729Y140622D01*
G01X240731Y140630D02*
X240730Y140628D01*
G01X240729Y135622D02*
X240728Y135613D01*
G01X240730Y135628D02*
X240729Y135622D01*
G01X240731Y135630D02*
X240730Y135628D01*
G01X240729Y130622D02*
X240728Y130613D01*
G01X240730Y130628D02*
X240729Y130622D01*
G01X240731Y130630D02*
X240730Y130628D01*
G01X240729Y125622D02*
X240728Y125613D01*
G01X240730Y125628D02*
X240729Y125622D01*
G01X240731Y125630D02*
X240730Y125628D01*
G01X240729Y120622D02*
X240728Y120613D01*
G01X240730Y120628D02*
X240729Y120622D01*
G01X240731Y120630D02*
X240730Y120628D01*
G01X240729Y115622D02*
X240728Y115613D01*
G01X240730Y115628D02*
X240729Y115622D01*
G01X240731Y115630D02*
X240730Y115628D01*
G01X240729Y110622D02*
X240728Y110613D01*
G01X240730Y110628D02*
X240729Y110622D01*
G01X240731Y110630D02*
X240730Y110628D01*
G01X240729Y105622D02*
X240728Y105613D01*
G01X240730Y105628D02*
X240729Y105622D01*
G01X240731Y105630D02*
X240730Y105628D01*
G01X226319Y103825D02*
Y103832D01*
G01X226318Y103820D02*
X226319Y103825D01*
G01X226317Y103819D02*
X226318Y103820D01*
G01X226319Y100675D02*
Y100683D01*
G01X226318Y100671D02*
X226319Y100675D01*
G01X226317Y100669D02*
X226318Y100671D01*
G01X226319Y97526D02*
Y97533D01*
G01X226318Y97521D02*
X226319Y97526D01*
G01X226317Y97520D02*
X226318Y97521D01*
G01X226319Y94376D02*
Y94383D01*
G01X226318Y94372D02*
X226319Y94376D01*
G01X226317Y94370D02*
X226318Y94372D01*
G01X227301Y102691D02*
X227303Y102703D01*
G01X227294Y102679D02*
X227301Y102691D01*
G01X227284Y102671D02*
X227294Y102679D01*
G01X227301Y96391D02*
X227303Y96404D01*
G01X227294Y96380D02*
X227301Y96391D01*
G01X227284Y96372D02*
X227294Y96380D01*
G01X226357Y103863D02*
Y103869D01*
G01Y103859D02*
Y103863D01*
G01X226356Y103858D02*
X226357Y103859D01*
G01Y100713D02*
Y100720D01*
G01Y100710D02*
Y100713D01*
G01X226356Y100709D02*
X226357Y100710D01*
G01Y97564D02*
Y97570D01*
G01Y97560D02*
Y97564D01*
G01X226356Y97559D02*
X226357Y97560D01*
G01Y94414D02*
Y94420D01*
G01Y94411D02*
Y94414D01*
G01X226356Y94409D02*
X226357Y94411D01*
G01X226320Y103839D02*
X226319Y103832D01*
G01X226321Y103845D02*
X226320Y103839D01*
G01X226324Y103851D02*
X226321Y103845D01*
G01X226328Y103856D02*
X226324Y103851D01*
G01X226333Y103861D02*
X226328Y103856D01*
G01X226338Y103864D02*
X226333Y103861D01*
G01X226320Y100689D02*
X226319Y100683D01*
G01X226321Y100695D02*
X226320Y100689D01*
G01X226324Y100701D02*
X226321Y100695D01*
G01X226328Y100706D02*
X226324Y100701D01*
G01X226333Y100711D02*
X226328Y100706D01*
G01X226338Y100715D02*
X226333Y100711D01*
G01X226320Y97539D02*
X226319Y97533D01*
G01X226321Y97546D02*
X226320Y97539D01*
G01X226324Y97552D02*
X226321Y97546D01*
G01X226328Y97557D02*
X226324Y97552D01*
G01X226333Y97561D02*
X226328Y97557D01*
G01X226338Y97565D02*
X226333Y97561D01*
G01X226320Y94390D02*
X226319Y94383D01*
G01X226321Y94396D02*
X226320Y94390D01*
G01X226324Y94402D02*
X226321Y94396D01*
G01X226328Y94407D02*
X226324Y94402D01*
G01X226333Y94412D02*
X226328Y94407D01*
G01X226338Y94415D02*
X226333Y94412D01*
G01X227274Y102679D02*
X227262Y102677D01*
G01X227285Y102684D02*
X227274Y102679D01*
G01Y99530D02*
X227262Y99528D01*
G01X227285Y99534D02*
X227274Y99530D01*
G01Y96380D02*
X227262Y96378D01*
G01X227285Y96385D02*
X227274Y96380D01*
G01X237126Y188130D02*
G03I-1890J0D01*
G01X237598D02*
G03I-2362J0D01*
G01X240157Y103681D02*
X241339Y104862D01*
G01X236220Y103681D02*
X237402Y104862D01*
G01X246063Y186161D02*
X242717Y182815D01*
G01X236220Y180138D02*
X237402Y181319D01*
G01X232752Y185059D02*
X234055Y187028D01*
G01X238728Y192950D02*
X236417Y188720D01*
G01X234055Y187028D02*
X236417D01*
G01X227756Y185059D02*
X242126D01*
G01X227756Y183681D02*
X231496D01*
G01X242126D02*
X238976D01*
G01X227756Y182815D02*
X242717D01*
G01X229528Y181319D02*
X237402D01*
G01X230709Y180138D02*
X236220D01*
G01X240728Y177500D02*
X239744D01*
G01X239746Y177008D02*
X245079D01*
G01Y176969D02*
X240731D01*
G01X245079Y175630D02*
X239746D01*
G01X239744Y175138D02*
X240728D01*
G01Y172500D02*
X239744D01*
G01X239746Y172008D02*
X245079D01*
G01Y171969D02*
X240731D01*
G01X245079Y170630D02*
X239746D01*
G01X239744Y170138D02*
X240728D01*
G01Y167500D02*
X239744D01*
G01X239746Y167008D02*
X245079D01*
G01Y166969D02*
X240731D01*
G01X245079Y165630D02*
X239746D01*
G01X239744Y165138D02*
X240728D01*
G01Y162500D02*
X239744D01*
G01X239746Y162008D02*
X245079D01*
G01Y161969D02*
X240731D01*
G01X245079Y160630D02*
X239746D01*
G01X239744Y160138D02*
X240728D01*
G01Y157500D02*
X239744D01*
G01X239746Y157008D02*
X245079D01*
G01Y156969D02*
X240731D01*
G01X245079Y155630D02*
X239746D01*
G01X239744Y155138D02*
X240728D01*
G01Y152500D02*
X239744D01*
G01X239746Y152008D02*
X245079D01*
G01Y151969D02*
X240731D01*
G01X245079Y150630D02*
X239746D01*
G01X239744Y150138D02*
X240728D01*
G01Y147500D02*
X239744D01*
G01X239746Y147008D02*
X245079D01*
G01Y146969D02*
X240731D01*
G01X245079Y145630D02*
X239746D01*
G01X239744Y145138D02*
X240728D01*
G01Y142500D02*
X239744D01*
G01X239746Y142008D02*
X245079D01*
G01Y141969D02*
X240731D01*
G01X245079Y140630D02*
X239746D01*
G01X239744Y140138D02*
X240728D01*
G01Y137500D02*
X239744D01*
G01X239746Y137008D02*
X245079D01*
G01Y136969D02*
X240731D01*
G01X245079Y135630D02*
X239746D01*
G01X239744Y135138D02*
X240728D01*
G01Y132500D02*
X239744D01*
G01X239746Y132008D02*
X245079D01*
G01Y131969D02*
X240731D01*
G01X245079Y130630D02*
X239746D01*
G01X239744Y130138D02*
X240728D01*
G01Y127500D02*
X239744D01*
G01X239746Y127008D02*
X245079D01*
G01Y126969D02*
X240731D01*
G01X245079Y125630D02*
X239746D01*
G01X239744Y125138D02*
X240728D01*
G01Y122500D02*
X239744D01*
G01X239746Y122008D02*
X245079D01*
G01Y121969D02*
X240731D01*
G01X245079Y120630D02*
X239746D01*
G01X239744Y120138D02*
X240728D01*
G01Y117500D02*
X239744D01*
G01Y177204D02*
X240699Y177205D01*
G01X240728Y175434D02*
X239744Y175433D01*
G01Y172204D02*
X240699Y172205D01*
G01X240728Y170434D02*
X239744Y170433D01*
G01Y167204D02*
X240699Y167205D01*
G01X240728Y165434D02*
X239744Y165433D01*
G01Y162204D02*
X240699Y162205D01*
G01X240728Y160434D02*
X239744Y160433D01*
G01Y157204D02*
X240699Y157205D01*
G01X240728Y155434D02*
X239744Y155433D01*
G01Y152204D02*
X240699Y152205D01*
G01X240728Y150434D02*
X239744Y150433D01*
G01Y147204D02*
X240699Y147205D01*
G01X240728Y145434D02*
X239744Y145433D01*
G01Y142204D02*
X240699Y142205D01*
G01X240728Y140434D02*
X239744Y140433D01*
G01Y137204D02*
X240699Y137205D01*
G01X240728Y135434D02*
X239744Y135433D01*
G01Y132204D02*
X240699Y132205D01*
G01X240728Y130434D02*
X239744Y130433D01*
G01Y127204D02*
X240699Y127205D01*
G01X240728Y125434D02*
X239744Y125433D01*
G01Y122204D02*
X240699Y122205D01*
G01X240728Y120434D02*
X239744Y120433D01*
G01Y117204D02*
X240699Y117205D01*
G01X226206Y102717D02*
X226317Y102708D01*
G01Y96414D02*
X226206Y96417D01*
G01X239746Y117008D02*
X245079D01*
G01Y116969D02*
X240731D01*
G01X245079Y115630D02*
X239746D01*
G01X239744Y115138D02*
X240728D01*
G01Y112500D02*
X239744D01*
G01X239746Y112008D02*
X245079D01*
G01Y111969D02*
X240731D01*
G01X245079Y110630D02*
X239746D01*
G01X239744Y110138D02*
X240728D01*
G01Y107500D02*
X239744D01*
G01X239746Y107008D02*
X245079D01*
G01Y106969D02*
X240731D01*
G01X227756Y106024D02*
X224409D01*
G01X245079Y105630D02*
X239746D01*
G01X239744Y105138D02*
X240728D01*
G01X237402Y104862D02*
X241339D01*
G01X227264Y104055D02*
X226358D01*
G01X227303Y104016D02*
X226319D01*
G01X227262Y103858D02*
X221378D01*
G01Y103819D02*
X227302D01*
G01X236220Y103681D02*
X240157D01*
G01X227302Y102717D02*
X221378D01*
G01X227262Y102677D02*
X221378D01*
G01X226319Y102520D02*
X227303D01*
G01X226358Y102480D02*
X227264D01*
G01Y100906D02*
X226358D01*
G01X227303Y100866D02*
X226319D01*
G01X227262Y100709D02*
X221378D01*
G01Y100669D02*
X227302D01*
G01Y99567D02*
X221378D01*
G01X227262Y99528D02*
X221378D01*
G01X226319Y99370D02*
X227303D01*
G01X226358Y99331D02*
X227264D01*
G01Y97756D02*
X226358D01*
G01X227303Y97717D02*
X226319D01*
G01X227262Y97559D02*
X221378D01*
G01Y97520D02*
X227302D01*
G01Y96417D02*
X221378D01*
G01X227262Y96378D02*
X221378D01*
G01X226319Y96220D02*
X227303D01*
G01X226358Y96181D02*
X227264D01*
G01Y94606D02*
X226358D01*
G01X227303Y94567D02*
X226319D01*
G01X227262Y94409D02*
X221378D01*
G01Y94370D02*
X227302D01*
G01X240728Y115434D02*
X239744Y115433D01*
G01Y112204D02*
X240699Y112205D01*
G01X240728Y110434D02*
X239744Y110433D01*
G01Y107204D02*
X240699Y107205D01*
G01X240728Y105434D02*
X239744Y105433D01*
G01X227303Y94372D02*
Y94383D01*
G01Y97522D02*
Y97533D01*
G01Y100671D02*
Y100683D01*
G01Y103821D02*
Y103832D01*
G01X240728Y106982D02*
X240729Y106991D01*
G01X240728Y111982D02*
X240729Y111991D01*
G01X240728Y116982D02*
X240729Y116991D01*
G01X240728Y121982D02*
X240729Y121991D01*
G01X240728Y126982D02*
X240729Y126991D01*
G01X240728Y131982D02*
X240729Y131991D01*
G01X240728Y136982D02*
X240729Y136991D01*
G01X240728Y141982D02*
X240729Y141991D01*
G01X240728Y146982D02*
X240729Y146991D01*
G01X240728Y151982D02*
X240729Y151991D01*
G01X240728Y156982D02*
X240729Y156991D01*
G01X240728Y161982D02*
X240729Y161991D01*
G01X240728Y166982D02*
X240729Y166991D01*
G01X240728Y171982D02*
X240729Y171991D01*
G01X240728Y176982D02*
X240729Y176991D01*
G01X246063Y186161D02*
Y201909D01*
G01X245079Y175630D02*
Y177008D01*
G01Y170630D02*
Y172008D01*
G01Y165630D02*
Y167008D01*
G01Y160630D02*
Y162008D01*
G01Y155630D02*
Y157008D01*
G01Y150630D02*
Y152008D01*
G01Y145630D02*
Y147008D01*
G01Y140630D02*
Y142008D01*
G01Y135630D02*
Y137008D01*
G01Y130630D02*
Y132008D01*
G01Y125630D02*
Y127008D01*
G01Y120630D02*
Y122008D01*
G01Y115630D02*
Y117008D01*
G01Y110630D02*
Y112008D01*
G01Y105630D02*
Y107008D01*
G01X241909D02*
Y105630D01*
G01Y112008D02*
Y110630D01*
G01Y117008D02*
Y115630D01*
G01Y122008D02*
Y120630D01*
G01Y127008D02*
Y125630D01*
G01Y132008D02*
Y130630D01*
G01Y137008D02*
Y135630D01*
G01Y142008D02*
Y140630D01*
G01Y147008D02*
Y145630D01*
G01Y152008D02*
Y150630D01*
G01Y157008D02*
Y155630D01*
G01Y162008D02*
Y160630D01*
G01Y167008D02*
Y165630D01*
G01Y172008D02*
Y170630D01*
G01Y177008D02*
Y175630D01*
G01X240728Y111982D02*
Y112125D01*
G01Y106982D02*
Y107125D01*
G01Y121982D02*
Y122125D01*
G01Y116982D02*
Y117125D01*
G01Y131982D02*
Y132125D01*
G01Y126982D02*
Y127125D01*
G01Y141982D02*
Y142125D01*
G01Y136982D02*
Y137125D01*
G01Y151982D02*
Y152125D01*
G01Y146982D02*
Y147125D01*
G01Y161982D02*
Y162125D01*
G01Y156982D02*
Y157125D01*
G01Y171982D02*
Y172125D01*
G01Y166982D02*
Y167125D01*
G01Y176982D02*
Y177125D01*
G01Y175138D02*
Y177500D01*
G01Y170138D02*
Y172500D01*
G01Y165138D02*
Y167500D01*
G01Y160138D02*
Y162500D01*
G01Y155138D02*
Y157500D01*
G01Y150138D02*
Y152500D01*
G01Y145138D02*
Y147500D01*
G01Y140138D02*
Y142500D01*
G01Y135138D02*
Y137500D01*
G01Y130138D02*
Y132500D01*
G01Y125138D02*
Y127500D01*
G01Y120138D02*
Y122500D01*
G01Y115138D02*
Y117500D01*
G01Y110138D02*
Y112500D01*
G01Y105138D02*
Y107500D01*
G01X239744D02*
Y105138D01*
G01Y112500D02*
Y110138D01*
G01Y117500D02*
Y115138D01*
G01Y122500D02*
Y120138D01*
G01Y127500D02*
Y125138D01*
G01Y132500D02*
Y130138D01*
G01Y137500D02*
Y135138D01*
G01Y142500D02*
Y140138D01*
G01Y147500D02*
Y145138D01*
G01Y152500D02*
Y150138D01*
G01Y157500D02*
Y155138D01*
G01Y162500D02*
Y160138D01*
G01Y167500D02*
Y165138D01*
G01Y172500D02*
Y170138D01*
G01Y177500D02*
Y175138D01*
G01X238976Y192224D02*
Y183681D01*
G01X237402Y181319D02*
Y104862D01*
G01X236417Y188720D02*
Y187028D01*
G01X236220Y180138D02*
Y103681D01*
G01X234055Y187028D02*
Y188720D01*
G01X231496Y183681D02*
Y192224D01*
G01X227756Y185059D02*
Y106024D01*
G01X227303Y102519D02*
Y104016D01*
G01Y99370D02*
Y100866D01*
G01Y96220D02*
Y97717D01*
G01X227264Y96367D02*
Y96220D01*
G01Y94567D02*
Y94420D01*
G01Y99516D02*
Y99369D01*
G01Y100867D02*
Y100720D01*
G01Y97717D02*
Y97570D01*
G01Y102666D02*
Y102519D01*
G01Y104016D02*
Y103869D01*
G01X226358Y102519D02*
Y102666D01*
G01Y103869D02*
Y104016D01*
G01Y99369D02*
Y99516D01*
G01Y100720D02*
Y100867D01*
G01Y97570D02*
Y97717D01*
G01Y96220D02*
Y96367D01*
G01Y94420D02*
Y94567D01*
G01X226319Y100866D02*
Y99370D01*
G01Y97717D02*
Y96220D01*
G01Y104016D02*
Y102520D01*
G01X225138Y97559D02*
Y96378D01*
G01Y100709D02*
Y99528D01*
G01Y103858D02*
Y102677D01*
G01X224409Y201909D02*
Y186161D01*
G01X221378Y102677D02*
Y103858D01*
G01Y99528D02*
Y100709D01*
G01Y96378D02*
Y97559D01*
G01X227303Y102703D02*
Y102714D01*
G01Y99554D02*
Y99564D01*
G01Y96404D02*
Y96415D01*
G01X227262Y99528D02*
X227266Y99516D01*
G01X234055Y188720D02*
X231745Y192950D01*
G01X236417Y187028D02*
X237721Y185059D01*
G01X229528Y181319D02*
X230709Y180138D01*
G01X224409Y186161D02*
X227756Y182815D01*
G01X246063Y201909D02*
G03X244094Y203878I-1969J0D01*
G01X195276Y260630D02*
G03X196457I591J0D01*
G01Y254331D02*
G03X195276I-590J0D01*
G01Y260630D02*
G03X196457I591J0D01*
G01Y254331D02*
G03X195276I-590J0D01*
G01X239173Y202500D02*
G03X238583Y203091I-591J0D01*
G01X231890D02*
G03X231299Y202500I0J-591D01*
G01X234055Y201319D02*
G03Y199350I0J-985D01*
G01X236417D02*
G03Y201319I0J984D01*
G01X232677Y193406D02*
G03X231496Y192224I0J-1181D01*
G01X238976D02*
G03X237795Y193406I-1181J1D01*
G01X226378Y203878D02*
G03X224409Y201909I0J-1969D01*
G01X197244Y260630D02*
X196457D01*
G01X197244D02*
X196457D01*
G01Y254331D02*
X197244D01*
G01X196457D02*
X197244D01*
G01X244094Y203878D02*
X226378D01*
G01X238583Y203091D02*
X231890D01*
G01X236417Y201319D02*
X234055D01*
G01Y199350D02*
X236417D01*
G01X239173Y197972D02*
X231299D01*
G01Y196398D02*
X239173D01*
G01X246063Y193445D02*
X224409D01*
G01X232677Y193406D02*
X237795D01*
G01X234055Y188720D02*
X236417D01*
G01X239173Y196398D02*
Y202500D01*
G01X231299Y196398D02*
Y202500D01*
G01X197244Y254331D02*
Y260630D01*
G01Y254331D02*
Y260630D01*
G01X240695Y504862D02*
X240699Y504961D01*
G01X240690Y504790D02*
X240695Y504862D01*
G01X240692Y504764D02*
X240690Y504790D01*
G01X240695Y509862D02*
X240699Y509961D01*
G01X240690Y509790D02*
X240695Y509862D01*
G01X240692Y509764D02*
X240690Y509790D01*
G01X240695Y514862D02*
X240699Y514961D01*
G01X240690Y514790D02*
X240695Y514862D01*
G01X240692Y514764D02*
X240690Y514790D01*
G01X240695Y519862D02*
X240699Y519961D01*
G01X240690Y519790D02*
X240695Y519862D01*
G01X240692Y519764D02*
X240690Y519790D01*
G01X240695Y524862D02*
X240699Y524961D01*
G01X240690Y524790D02*
X240695Y524862D01*
G01X240692Y524764D02*
X240690Y524790D01*
G01X240695Y529862D02*
X240699Y529961D01*
G01X240690Y529790D02*
X240695Y529862D01*
G01X240692Y529764D02*
X240690Y529790D01*
G01X240695Y534862D02*
X240699Y534961D01*
G01X240690Y534790D02*
X240695Y534862D01*
G01X240692Y534764D02*
X240690Y534790D01*
G01X240695Y559862D02*
X240699Y559961D01*
G01X240690Y559790D02*
X240695Y559862D01*
G01X240692Y559764D02*
X240690Y559790D01*
G01X240695Y564862D02*
X240699Y564961D01*
G01X240690Y564790D02*
X240695Y564862D01*
G01X240692Y564764D02*
X240690Y564790D01*
G01X240695Y569862D02*
X240699Y569961D01*
G01X240690Y569790D02*
X240695Y569862D01*
G01X240692Y569764D02*
X240690Y569790D01*
G01X226319Y549167D02*
Y549160D01*
G01X226318Y549172D02*
X226319Y549167D01*
G01X226318Y549162D02*
Y549172D01*
G01X226359Y556798D02*
X226358Y556811D01*
G01X226356Y556785D02*
X226359Y556798D01*
G01X226356Y556772D02*
Y556785D01*
G01X226359Y553649D02*
X226358Y553661D01*
G01X226356Y553636D02*
X226359Y553649D01*
G01X226356Y553622D02*
Y553636D01*
G01X226359Y550499D02*
X226358Y550512D01*
G01X226356Y550486D02*
X226359Y550499D01*
G01X226356Y550472D02*
Y550486D01*
G01X226359Y547350D02*
X226358Y547362D01*
G01X226356Y547337D02*
X226359Y547350D01*
G01X226356Y547323D02*
Y547337D01*
G01X226359Y544200D02*
X226358Y544213D01*
G01X226356Y544187D02*
X226359Y544200D01*
G01X226356Y544173D02*
Y544187D01*
G01X226359Y541050D02*
X226358Y541063D01*
G01X226356Y541037D02*
X226359Y541050D01*
G01X226356Y541024D02*
Y541037D01*
G01X226359Y537901D02*
X226358Y537913D01*
G01X226356Y537888D02*
X226359Y537901D01*
G01X226356Y537874D02*
Y537888D01*
G01X226319Y555467D02*
Y555459D01*
G01X226318Y555471D02*
X226319Y555467D01*
G01X226318Y555463D02*
Y555471D01*
G01X240729Y504731D02*
X240728Y504738D01*
G01X240730Y504726D02*
X240729Y504731D01*
G01X240731Y504724D02*
X240730Y504726D01*
G01X240729Y509731D02*
X240728Y509738D01*
G01X240730Y509726D02*
X240729Y509731D01*
G01X240731Y509724D02*
X240730Y509726D01*
G01X226342Y539687D02*
X226356Y539685D01*
G01X226330Y539694D02*
X226342Y539687D01*
G01X226318Y539713D02*
X226330Y539694D01*
G01X226342Y549136D02*
X226356Y549134D01*
G01X226330Y549144D02*
X226342Y549136D01*
G01X226318Y549162D02*
X226330Y549144D01*
G01X226341Y542837D02*
X226356Y542835D01*
G01X226329Y542845D02*
X226341Y542837D01*
G01X226317Y542865D02*
X226329Y542845D01*
G01X226341Y552286D02*
X226356Y552283D01*
G01X226329Y552294D02*
X226341Y552286D01*
G01X226317Y552314D02*
X226329Y552294D01*
G01X227303Y536569D02*
Y536561D01*
G01X227302Y536573D02*
X227303Y536569D01*
G01X227302Y536575D02*
Y536573D01*
G01X227303Y539719D02*
Y539711D01*
G01X227302Y539723D02*
X227303Y539719D01*
G01X227302Y539724D02*
Y539723D01*
G01X227303Y542868D02*
Y542860D01*
G01X227302Y542872D02*
X227303Y542868D01*
G01X227302Y542874D02*
Y542872D01*
G01X227303Y546018D02*
Y546010D01*
G01X227302Y546022D02*
X227303Y546018D01*
G01X227302Y546024D02*
Y546022D01*
G01X227303Y549167D02*
Y549159D01*
G01X227302Y549172D02*
X227303Y549167D01*
G01X227302Y549173D02*
Y549172D01*
G01X227303Y552317D02*
Y552309D01*
G01X227302Y552321D02*
X227303Y552317D01*
G01X227302Y552323D02*
Y552321D01*
G01X227303Y555467D02*
Y555459D01*
G01X227302Y555471D02*
X227303Y555467D01*
G01X227302Y555472D02*
Y555471D01*
G01X226341Y555436D02*
X226356Y555433D01*
G01X226329Y555444D02*
X226341Y555436D01*
G01X226317Y555464D02*
X226329Y555444D01*
G01X226341Y536538D02*
X226356Y536535D01*
G01X226328Y536547D02*
X226341Y536538D01*
G01X226317Y536567D02*
X226328Y536547D01*
G01X227302Y537697D02*
X227303Y537691D01*
G01X227301Y537704D02*
X227302Y537697D01*
G01X227298Y537709D02*
X227301Y537704D01*
G01X227302Y540847D02*
X227303Y540840D01*
G01X227301Y540853D02*
X227302Y540847D01*
G01X227298Y540859D02*
X227301Y540853D01*
G01X227302Y543996D02*
X227303Y543990D01*
G01X227301Y544003D02*
X227302Y543996D01*
G01X227298Y544009D02*
X227301Y544003D01*
G01X227302Y547146D02*
X227303Y547139D01*
G01X227301Y547152D02*
X227302Y547146D01*
G01X227298Y547158D02*
X227301Y547152D01*
G01X227302Y550296D02*
X227303Y550289D01*
G01X227301Y550302D02*
X227302Y550296D01*
G01X227298Y550308D02*
X227301Y550302D01*
G01X227302Y553445D02*
X227303Y553439D01*
G01X227301Y553452D02*
X227302Y553445D01*
G01X227298Y553457D02*
X227301Y553452D01*
G01X227302Y556595D02*
X227303Y556588D01*
G01X227301Y556601D02*
X227302Y556595D01*
G01X227298Y556607D02*
X227301Y556601D01*
G01X227264Y536530D02*
X227265Y536524D01*
G01X227263Y536534D02*
X227264Y536530D01*
G01X227262Y536535D02*
X227263Y536534D01*
G01X227264Y539680D02*
X227265Y539674D01*
G01X227263Y539683D02*
X227264Y539680D01*
G01X227262Y539685D02*
X227263Y539683D01*
G01X227264Y542830D02*
X227265Y542823D01*
G01X227263Y542833D02*
X227264Y542830D01*
G01X227262Y542835D02*
X227263Y542833D01*
G01X227264Y545979D02*
X227265Y545973D01*
G01X227263Y545983D02*
X227264Y545979D01*
G01X227262Y545984D02*
X227263Y545983D01*
G01X227264Y549129D02*
X227265Y549122D01*
G01X227263Y549132D02*
X227264Y549129D01*
G01X227262Y549134D02*
X227263Y549132D01*
G01X227264Y555428D02*
X227265Y555422D01*
G01X227263Y555431D02*
X227264Y555428D01*
G01X227262Y555433D02*
X227263Y555431D01*
G01X239744Y504771D02*
Y504780D01*
G01X239745Y504765D02*
X239744Y504771D01*
G01X239746Y504764D02*
X239745Y504765D01*
G01X239744Y509771D02*
Y509780D01*
G01X239745Y509765D02*
X239744Y509771D01*
G01X239746Y509764D02*
X239745Y509765D01*
G01X239744Y514771D02*
Y514780D01*
G01X239745Y514765D02*
X239744Y514771D01*
G01X239746Y514764D02*
X239745Y514765D01*
G01X239744Y519771D02*
Y519780D01*
G01X239745Y519765D02*
X239744Y519771D01*
G01X239746Y519764D02*
X239745Y519765D01*
G01X239744Y524771D02*
Y524780D01*
G01X239745Y524765D02*
X239744Y524771D01*
G01X239746Y524764D02*
X239745Y524765D01*
G01X239744Y529771D02*
Y529780D01*
G01X239745Y529765D02*
X239744Y529771D01*
G01X239746Y529764D02*
X239745Y529765D01*
G01X239744Y534771D02*
Y534780D01*
G01X239745Y534765D02*
X239744Y534771D01*
G01X239746Y534764D02*
X239745Y534765D01*
G01X239744Y559771D02*
Y559780D01*
G01X239745Y559765D02*
X239744Y559771D01*
G01X239746Y559764D02*
X239745Y559765D01*
G01X239744Y564771D02*
Y564780D01*
G01X239745Y564765D02*
X239744Y564771D01*
G01X239746Y564764D02*
X239745Y564765D01*
G01X239744Y569771D02*
Y569780D01*
G01X239745Y569765D02*
X239744Y569771D01*
G01X239746Y569764D02*
X239745Y569765D01*
G01X240720Y504907D02*
X240728Y504881D01*
G01X240711Y504934D02*
X240720Y504907D01*
G01X240699Y504961D02*
X240711Y504934D01*
G01X240720Y509907D02*
X240728Y509881D01*
G01X240711Y509934D02*
X240720Y509907D01*
G01X240699Y509961D02*
X240711Y509934D01*
G01X240720Y514907D02*
X240728Y514881D01*
G01X240711Y514934D02*
X240720Y514907D01*
G01X240699Y514961D02*
X240711Y514934D01*
G01X240720Y519907D02*
X240728Y519881D01*
G01X240711Y519934D02*
X240720Y519907D01*
G01X240699Y519961D02*
X240711Y519934D01*
G01X240720Y524907D02*
X240728Y524881D01*
G01X240711Y524934D02*
X240720Y524907D01*
G01X240699Y524961D02*
X240711Y524934D01*
G01X240720Y529907D02*
X240728Y529881D01*
G01X240711Y529934D02*
X240720Y529907D01*
G01X240699Y529961D02*
X240711Y529934D01*
G01X240720Y534907D02*
X240728Y534881D01*
G01X240711Y534934D02*
X240720Y534907D01*
G01X240699Y534961D02*
X240711Y534934D01*
G01X240720Y559907D02*
X240728Y559881D01*
G01X240711Y559934D02*
X240720Y559907D01*
G01X240699Y559961D02*
X240711Y559934D01*
G01X240720Y564907D02*
X240728Y564881D01*
G01X240711Y564934D02*
X240720Y564907D01*
G01X240699Y564961D02*
X240711Y564934D01*
G01X240720Y569907D02*
X240728Y569881D01*
G01X240711Y569934D02*
X240720Y569907D01*
G01X240699Y569961D02*
X240711Y569934D01*
G01X226337Y545989D02*
X226356Y545984D01*
G01X226323Y546002D02*
X226337Y545989D01*
G01X226317Y546019D02*
X226323Y546002D01*
G01X240711Y504759D02*
X240692Y504764D01*
G01X240726Y504744D02*
X240711Y504759D01*
G01X240731Y504724D02*
X240726Y504744D01*
G01X240711Y509759D02*
X240692Y509764D01*
G01X240726Y509744D02*
X240711Y509759D01*
G01X240731Y509724D02*
X240726Y509744D01*
G01X240711Y514759D02*
X240692Y514764D01*
G01X240726Y514744D02*
X240711Y514759D01*
G01X240731Y514724D02*
X240726Y514744D01*
G01X240711Y519759D02*
X240692Y519764D01*
G01X240726Y519744D02*
X240711Y519759D01*
G01X240731Y519724D02*
X240726Y519744D01*
G01X240711Y524759D02*
X240692Y524764D01*
G01X240726Y524744D02*
X240711Y524759D01*
G01X240731Y524724D02*
X240726Y524744D01*
G01X240711Y529759D02*
X240692Y529764D01*
G01X240726Y529744D02*
X240711Y529759D01*
G01X240731Y529724D02*
X240726Y529744D01*
G01X240711Y534759D02*
X240692Y534764D01*
G01X240726Y534744D02*
X240711Y534759D01*
G01X240731Y534724D02*
X240726Y534744D01*
G01X240711Y559759D02*
X240692Y559764D01*
G01X240726Y559744D02*
X240711Y559759D01*
G01X240731Y559724D02*
X240726Y559744D01*
G01X240711Y564759D02*
X240692Y564764D01*
G01X240726Y564744D02*
X240711Y564759D01*
G01X240731Y564724D02*
X240726Y564744D01*
G01X240711Y569759D02*
X240692Y569764D01*
G01X240726Y569744D02*
X240711Y569759D01*
G01X240731Y569724D02*
X240726Y569744D01*
G01X227296Y543998D02*
X227288Y544006D01*
G01X227300Y543987D02*
X227296Y543998D01*
G01X227302Y543976D02*
X227300Y543987D01*
G01X227296Y537698D02*
X227288Y537707D01*
G01X227300Y537688D02*
X227296Y537698D01*
G01X227302Y537677D02*
X227300Y537688D01*
G01X227296Y540848D02*
X227288Y540856D01*
G01X227300Y540838D02*
X227296Y540848D01*
G01X227302Y540827D02*
X227300Y540838D01*
G01X227296Y547147D02*
X227288Y547156D01*
G01X227300Y547137D02*
X227296Y547147D01*
G01X227302Y547126D02*
X227300Y547137D01*
G01X227296Y550297D02*
X227288Y550305D01*
G01X227300Y550287D02*
X227296Y550297D01*
G01X227302Y550276D02*
X227300Y550287D01*
G01X227296Y553446D02*
X227288Y553455D01*
G01X227300Y553436D02*
X227296Y553446D01*
G01X227302Y553425D02*
X227300Y553436D01*
G01X227296Y556596D02*
X227288Y556604D01*
G01X227300Y556586D02*
X227296Y556596D01*
G01X227302Y556575D02*
X227300Y556586D01*
G01X239745Y568384D02*
X239746Y568386D01*
G01X239744Y568378D02*
X239745Y568384D01*
G01X239744Y568370D02*
Y568378D01*
G01X239745Y563384D02*
X239746Y563386D01*
G01X239744Y563378D02*
X239745Y563384D01*
G01X239744Y563370D02*
Y563378D01*
G01X239745Y558384D02*
X239746Y558386D01*
G01X239744Y558378D02*
X239745Y558384D01*
G01X239744Y558370D02*
Y558378D01*
G01X239745Y533384D02*
X239746Y533386D01*
G01X239744Y533378D02*
X239745Y533384D01*
G01X239744Y533370D02*
Y533378D01*
G01X239745Y528384D02*
X239746Y528386D01*
G01X239744Y528378D02*
X239745Y528384D01*
G01X239744Y528370D02*
Y528378D01*
G01X239745Y523384D02*
X239746Y523386D01*
G01X239744Y523378D02*
X239745Y523384D01*
G01X239744Y523370D02*
Y523378D01*
G01X239745Y518384D02*
X239746Y518386D01*
G01X239744Y518378D02*
X239745Y518384D01*
G01X239744Y518370D02*
Y518378D01*
G01X239745Y513384D02*
X239746Y513386D01*
G01X239744Y513378D02*
X239745Y513384D01*
G01X239744Y513370D02*
Y513378D01*
G01X239745Y508384D02*
X239746Y508386D01*
G01X239744Y508378D02*
X239745Y508384D01*
G01X239744Y508370D02*
Y508378D01*
G01X239745Y503384D02*
X239746Y503386D01*
G01X239744Y503378D02*
X239745Y503384D01*
G01X239744Y503370D02*
Y503378D01*
G01X226356Y555261D02*
X226355Y555275D01*
G01X226359Y555249D02*
X226356Y555261D01*
G01X226358Y555236D02*
X226359Y555249D01*
G01X226356Y552112D02*
X226355Y552126D01*
G01X226359Y552099D02*
X226356Y552112D01*
G01X226358Y552087D02*
X226359Y552099D01*
G01X226356Y548962D02*
X226355Y548976D01*
G01X226359Y548950D02*
X226356Y548962D01*
G01X226358Y548937D02*
X226359Y548950D01*
G01X226356Y545813D02*
X226355Y545826D01*
G01X226359Y545800D02*
X226356Y545813D01*
G01X226358Y545787D02*
X226359Y545800D01*
G01X226356Y542663D02*
X226355Y542677D01*
G01X226359Y542650D02*
X226356Y542663D01*
G01X226358Y542638D02*
X226359Y542650D01*
G01X226356Y539513D02*
X226355Y539527D01*
G01X226359Y539501D02*
X226356Y539513D01*
G01X226358Y539488D02*
X226359Y539501D01*
G01X226356Y536364D02*
X226355Y536378D01*
G01X226359Y536351D02*
X226356Y536364D01*
G01X226358Y536339D02*
X226359Y536351D01*
G01X227266Y556785D02*
X227267Y556772D01*
G01X227263Y556798D02*
X227266Y556785D01*
G01X227264Y556811D02*
X227263Y556798D01*
G01X227266Y553636D02*
X227267Y553622D01*
G01X227263Y553649D02*
X227266Y553636D01*
G01X227264Y553661D02*
X227263Y553649D01*
G01X227266Y550486D02*
X227267Y550472D01*
G01X227263Y550499D02*
X227266Y550486D01*
G01X227264Y550512D02*
X227263Y550499D01*
G01X227266Y547337D02*
X227267Y547323D01*
G01X227263Y547350D02*
X227266Y547337D01*
G01X227264Y547362D02*
X227263Y547350D01*
G01X227266Y544187D02*
X227267Y544173D01*
G01X227263Y544200D02*
X227266Y544187D01*
G01X227264Y544213D02*
X227263Y544200D01*
G01X227266Y541037D02*
X227267Y541024D01*
G01X227263Y541050D02*
X227266Y541037D01*
G01X227264Y541063D02*
X227263Y541050D01*
G01X227266Y537888D02*
X227267Y537874D01*
G01X227263Y537901D02*
X227266Y537888D01*
G01X227264Y537913D02*
X227263Y537901D01*
G01X226319Y542868D02*
Y542861D01*
G01X226318Y542872D02*
X226319Y542868D01*
G01X226317Y542865D02*
X226318Y542872D01*
G01X226319Y552317D02*
Y552309D01*
G01X226318Y552321D02*
X226319Y552317D01*
G01X226317Y552314D02*
X226318Y552321D01*
G01X227263Y555249D02*
X227264Y555236D01*
G01X227266Y555261D02*
X227263Y555249D01*
G01X227267Y555275D02*
X227266Y555261D01*
G01X227263Y552099D02*
X227264Y552087D01*
G01X227266Y552112D02*
X227263Y552099D01*
G01X227267Y552126D02*
X227266Y552112D01*
G01X227263Y548950D02*
X227264Y548937D01*
G01X227266Y548962D02*
X227263Y548950D01*
G01X227267Y548976D02*
X227266Y548962D01*
G01X227263Y545800D02*
X227264Y545787D01*
G01X227266Y545813D02*
X227263Y545800D01*
G01X227267Y545826D02*
X227266Y545813D01*
G01X227263Y542650D02*
X227264Y542638D01*
G01X227266Y542663D02*
X227263Y542650D01*
G01X227267Y542677D02*
X227266Y542663D01*
G01X227263Y539501D02*
X227264Y539488D01*
G01X227266Y539513D02*
X227263Y539501D01*
G01X227267Y539527D02*
X227266Y539513D01*
G01X227263Y536351D02*
X227264Y536339D01*
G01X227266Y536364D02*
X227263Y536351D01*
G01X227267Y536378D02*
X227266Y536364D01*
G01X226319Y536569D02*
Y536561D01*
G01X226318Y536573D02*
X226319Y536569D01*
G01X226317Y536567D02*
X226318Y536573D01*
G01X226332Y556606D02*
X226356Y556614D01*
G01X226321Y556591D02*
X226332Y556606D01*
G01X226319Y556584D02*
X226321Y556591D01*
G01X226332Y553456D02*
X226356Y553465D01*
G01X226321Y553441D02*
X226332Y553456D01*
G01X226319Y553435D02*
X226321Y553441D01*
G01X226332Y550306D02*
X226356Y550315D01*
G01X226321Y550292D02*
X226332Y550306D01*
G01X226319Y550285D02*
X226321Y550292D01*
G01X226332Y547157D02*
X226356Y547165D01*
G01X226321Y547142D02*
X226332Y547157D01*
G01X226319Y547135D02*
X226321Y547142D01*
G01X226332Y544007D02*
X226356Y544016D01*
G01X226321Y543993D02*
X226332Y544007D01*
G01X226319Y543986D02*
X226321Y543993D01*
G01X226332Y540857D02*
X226356Y540866D01*
G01X226321Y540843D02*
X226332Y540857D01*
G01X226319Y540836D02*
X226321Y540843D01*
G01X226332Y537708D02*
X226356Y537717D01*
G01X226321Y537693D02*
X226332Y537708D01*
G01X226319Y537687D02*
X226321Y537693D01*
G01X226358Y536530D02*
Y536524D01*
G01X226357Y536534D02*
X226358Y536530D01*
G01X226356Y536535D02*
X226357Y536534D01*
G01X226358Y539680D02*
Y539674D01*
G01X226357Y539684D02*
X226358Y539680D01*
G01X226356Y539685D02*
X226357Y539684D01*
G01X226358Y542830D02*
Y542823D01*
G01X226357Y542833D02*
X226358Y542830D01*
G01X226356Y542835D02*
X226357Y542833D01*
G01X226358Y545979D02*
Y545973D01*
G01X226357Y545983D02*
X226358Y545979D01*
G01X226356Y545984D02*
X226357Y545983D01*
G01X226358Y549129D02*
Y549122D01*
G01X226357Y549133D02*
X226358Y549129D01*
G01X226356Y549134D02*
X226357Y549133D01*
G01X226358Y552278D02*
Y552272D01*
G01X226357Y552282D02*
X226358Y552278D01*
G01X226356Y552283D02*
X226357Y552282D01*
G01X240729Y514731D02*
X240728Y514738D01*
G01X240730Y514726D02*
X240729Y514731D01*
G01X240731Y514724D02*
X240730Y514726D01*
G01X240729Y519731D02*
X240728Y519738D01*
G01X240730Y519726D02*
X240729Y519731D01*
G01X240731Y519724D02*
X240730Y519726D01*
G01X240729Y524731D02*
X240728Y524738D01*
G01X240730Y524726D02*
X240729Y524731D01*
G01X240731Y524724D02*
X240730Y524726D01*
G01X240729Y529731D02*
X240728Y529738D01*
G01X240730Y529726D02*
X240729Y529731D01*
G01X240731Y529724D02*
X240730Y529726D01*
G01X240729Y534731D02*
X240728Y534738D01*
G01X240730Y534726D02*
X240729Y534731D01*
G01X240731Y534724D02*
X240730Y534726D01*
G01X240729Y559731D02*
X240728Y559738D01*
G01X240730Y559726D02*
X240729Y559731D01*
G01X240731Y559724D02*
X240730Y559726D01*
G01X240729Y564731D02*
X240728Y564738D01*
G01X240730Y564726D02*
X240729Y564731D01*
G01X240731Y564724D02*
X240730Y564726D01*
G01X240729Y569731D02*
X240728Y569738D01*
G01X240730Y569726D02*
X240729Y569731D01*
G01X240731Y569724D02*
X240730Y569726D01*
G01X227303Y556581D02*
Y556588D01*
G01Y556576D02*
Y556581D01*
G01X227302Y556575D02*
X227303Y556576D01*
G01Y553431D02*
Y553439D01*
G01Y553427D02*
Y553431D01*
G01X227302Y553425D02*
X227303Y553427D01*
G01Y550282D02*
Y550289D01*
G01Y550277D02*
Y550282D01*
G01X227302Y550276D02*
X227303Y550277D01*
G01Y547132D02*
Y547139D01*
G01Y547128D02*
Y547132D01*
G01X227302Y547126D02*
X227303Y547128D01*
G01Y543983D02*
Y543990D01*
G01Y543978D02*
Y543983D01*
G01X227302Y543976D02*
X227303Y543978D01*
G01Y540833D02*
Y540840D01*
G01Y540828D02*
Y540833D01*
G01X227302Y540827D02*
X227303Y540828D01*
G01Y537683D02*
Y537691D01*
G01Y537679D02*
Y537683D01*
G01X227302Y537677D02*
X227303Y537679D01*
G01X226319Y546018D02*
Y546010D01*
G01X226318Y546022D02*
X226319Y546018D01*
G01X226317Y546019D02*
X226318Y546022D01*
G01X227272Y544015D02*
X227262Y544016D01*
G01X227280Y544011D02*
X227272Y544015D01*
G01X227288Y544006D02*
X227280Y544011D01*
G01X227272Y537715D02*
X227262Y537717D01*
G01X227281Y537712D02*
X227272Y537715D01*
G01X227288Y537707D02*
X227281Y537712D01*
G01X227272Y540865D02*
X227262Y540866D01*
G01X227281Y540862D02*
X227272Y540865D01*
G01X227288Y540856D02*
X227281Y540862D01*
G01X227272Y547164D02*
X227262Y547165D01*
G01X227281Y547161D02*
X227272Y547164D01*
G01X227288Y547156D02*
X227281Y547161D01*
G01X227272Y550314D02*
X227262Y550315D01*
G01X227281Y550311D02*
X227272Y550314D01*
G01X227288Y550305D02*
X227281Y550311D01*
G01X227272Y553463D02*
X227262Y553465D01*
G01X227281Y553460D02*
X227272Y553463D01*
G01X227288Y553455D02*
X227281Y553460D01*
G01X227272Y556613D02*
X227262Y556614D01*
G01X227281Y556610D02*
X227272Y556613D01*
G01X227288Y556604D02*
X227281Y556610D01*
G01X226358Y555428D02*
Y555422D01*
G01X226357Y555432D02*
X226358Y555428D01*
G01X226356Y555433D02*
X226357Y555432D01*
G01X226319Y539719D02*
Y539711D01*
G01X226318Y539723D02*
X226319Y539719D01*
G01X226317Y539721D02*
X226318Y539723D01*
G01X227264Y556619D02*
Y556625D01*
G01X227263Y556615D02*
X227264Y556619D01*
G01X227262Y556614D02*
X227263Y556615D01*
G01X227264Y553470D02*
Y553476D01*
G01X227263Y553466D02*
X227264Y553470D01*
G01X227262Y553465D02*
X227263Y553466D01*
G01X227264Y550320D02*
Y550326D01*
G01X227263Y550316D02*
X227264Y550320D01*
G01X227262Y550315D02*
X227263Y550316D01*
G01X227264Y547170D02*
Y547176D01*
G01X227263Y547167D02*
X227264Y547170D01*
G01X227262Y547165D02*
X227263Y547167D01*
G01X227264Y544021D02*
Y544027D01*
G01X227263Y544017D02*
X227264Y544021D01*
G01X227262Y544016D02*
X227263Y544017D01*
G01X227264Y540871D02*
Y540877D01*
G01X227263Y540867D02*
X227264Y540871D01*
G01X227262Y540866D02*
X227263Y540867D01*
G01X227264Y537722D02*
Y537728D01*
G01X227263Y537718D02*
X227264Y537722D01*
G01X227262Y537717D02*
X227263Y537718D01*
G01X240716Y504755D02*
X240727Y504740D01*
G01X240691Y504764D02*
X240716Y504755D01*
G01X226319Y546014D02*
Y546010D01*
G01X226320Y546008D02*
X226319Y546014D01*
G01X226331Y545994D02*
X226320Y546008D01*
G01X226354Y545984D02*
X226331Y545994D01*
G01X240729Y568378D02*
X240728Y568369D01*
G01X240730Y568384D02*
X240729Y568378D01*
G01X240731Y568386D02*
X240730Y568384D01*
G01X240729Y563378D02*
X240728Y563369D01*
G01X240730Y563384D02*
X240729Y563378D01*
G01X240731Y563386D02*
X240730Y563384D01*
G01X240729Y558378D02*
X240728Y558369D01*
G01X240730Y558384D02*
X240729Y558378D01*
G01X240731Y558386D02*
X240730Y558384D01*
G01X240729Y533378D02*
X240728Y533369D01*
G01X240730Y533384D02*
X240729Y533378D01*
G01X240731Y533386D02*
X240730Y533384D01*
G01X240729Y528378D02*
X240728Y528369D01*
G01X240730Y528384D02*
X240729Y528378D01*
G01X240731Y528386D02*
X240730Y528384D01*
G01X240729Y523378D02*
X240728Y523369D01*
G01X240730Y523384D02*
X240729Y523378D01*
G01X240731Y523386D02*
X240730Y523384D01*
G01X240729Y518378D02*
X240728Y518369D01*
G01X240730Y518384D02*
X240729Y518378D01*
G01X240731Y518386D02*
X240730Y518384D01*
G01X240729Y513378D02*
X240728Y513369D01*
G01X240730Y513384D02*
X240729Y513378D01*
G01X240731Y513386D02*
X240730Y513384D01*
G01X240729Y508378D02*
X240728Y508369D01*
G01X240730Y508384D02*
X240729Y508378D01*
G01X240731Y508386D02*
X240730Y508384D01*
G01X240729Y503378D02*
X240728Y503369D01*
G01X240730Y503384D02*
X240729Y503378D01*
G01X240731Y503386D02*
X240730Y503384D01*
G01X226319Y556581D02*
Y556588D01*
G01X226318Y556576D02*
X226319Y556581D01*
G01X226317Y556575D02*
X226318Y556576D01*
G01X226319Y553431D02*
Y553439D01*
G01X226318Y553427D02*
X226319Y553431D01*
G01X226317Y553425D02*
X226318Y553427D01*
G01X226319Y550281D02*
Y550289D01*
G01X226318Y550277D02*
X226319Y550281D01*
G01X226317Y550276D02*
X226318Y550277D01*
G01X226319Y547132D02*
Y547139D01*
G01X226318Y547128D02*
X226319Y547132D01*
G01X226317Y547126D02*
X226318Y547128D01*
G01X226319Y539715D02*
Y539711D01*
G01X226320Y539708D02*
X226319Y539715D01*
G01X226332Y539693D02*
X226320Y539708D01*
G01X226357Y539685D02*
X226332Y539693D01*
G01X226319Y542864D02*
Y542860D01*
G01X226320Y542858D02*
X226319Y542864D01*
G01X226332Y542843D02*
X226320Y542858D01*
G01X226356Y542835D02*
X226332Y542843D01*
G01X226319Y549163D02*
Y549159D01*
G01X226320Y549157D02*
X226319Y549163D01*
G01X226332Y549142D02*
X226320Y549157D01*
G01X226356Y549134D02*
X226332Y549142D01*
G01X226319Y552313D02*
Y552309D01*
G01X226320Y552307D02*
X226319Y552313D01*
G01X226332Y552292D02*
X226320Y552307D01*
G01X226356Y552283D02*
X226332Y552292D01*
G01X226319Y536565D02*
Y536561D01*
G01X226320Y536559D02*
X226319Y536565D01*
G01X226332Y536544D02*
X226320Y536559D01*
G01X226356Y536535D02*
X226332Y536544D01*
G01X226319Y555463D02*
Y555459D01*
G01X226320Y555457D02*
X226319Y555463D01*
G01X226332Y555441D02*
X226320Y555457D01*
G01X226356Y555433D02*
X226332Y555441D01*
G01X240716Y509755D02*
X240727Y509740D01*
G01X240691Y509764D02*
X240716Y509755D01*
G01Y514755D02*
X240727Y514740D01*
G01X240691Y514764D02*
X240716Y514755D01*
G01Y519755D02*
X240727Y519740D01*
G01X240691Y519764D02*
X240716Y519755D01*
G01Y524755D02*
X240727Y524740D01*
G01X240691Y524764D02*
X240716Y524755D01*
G01Y529755D02*
X240727Y529740D01*
G01X240691Y529764D02*
X240716Y529755D01*
G01Y534755D02*
X240727Y534740D01*
G01X240691Y534764D02*
X240716Y534755D01*
G01Y559755D02*
X240727Y559740D01*
G01X240691Y559764D02*
X240716Y559755D01*
G01Y564755D02*
X240727Y564740D01*
G01X240691Y564764D02*
X240716Y564755D01*
G01Y569755D02*
X240727Y569740D01*
G01X240691Y569764D02*
X240716Y569755D01*
G01X226319Y543982D02*
Y543990D01*
G01X226318Y543978D02*
X226319Y543982D01*
G01X226317Y543976D02*
X226318Y543978D01*
G01X226319Y540833D02*
Y540840D01*
G01X226318Y540828D02*
X226319Y540833D01*
G01X226317Y540827D02*
X226318Y540828D01*
G01X226319Y537683D02*
Y537691D01*
G01X226318Y537679D02*
X226319Y537683D01*
G01X226317Y537677D02*
X226318Y537679D01*
G01X227273Y537715D02*
X227282Y537711D01*
G01X227262Y537717D02*
X227273Y537715D01*
G01Y540865D02*
X227282Y540861D01*
G01X227262Y540866D02*
X227273Y540865D01*
G01Y544014D02*
X227282Y544010D01*
G01X227262Y544016D02*
X227273Y544014D01*
G01X227301Y555446D02*
X227303Y555459D01*
G01X227294Y555435D02*
X227301Y555446D01*
G01X227284Y555427D02*
X227294Y555435D01*
G01X227301Y549147D02*
X227303Y549159D01*
G01X227294Y549136D02*
X227301Y549147D01*
G01X227284Y549128D02*
X227294Y549136D01*
G01X227301Y545998D02*
X227303Y546010D01*
G01X227294Y545986D02*
X227301Y545998D01*
G01X227284Y545978D02*
X227294Y545986D01*
G01X227301Y542848D02*
X227303Y542860D01*
G01X227294Y542837D02*
X227301Y542848D01*
G01X227284Y542829D02*
X227294Y542837D01*
G01X227301Y539698D02*
X227303Y539711D01*
G01X227294Y539687D02*
X227301Y539698D01*
G01X227284Y539679D02*
X227294Y539687D01*
G01X227301Y536549D02*
X227303Y536561D01*
G01X227294Y536537D02*
X227301Y536549D01*
G01X227284Y536530D02*
X227294Y536537D01*
G01X226357Y556619D02*
Y556625D01*
G01Y556615D02*
Y556619D01*
G01X226356Y556614D02*
X226357Y556615D01*
G01Y553469D02*
Y553476D01*
G01Y553466D02*
Y553469D01*
G01X226356Y553465D02*
X226357Y553466D01*
G01Y550320D02*
Y550326D01*
G01Y550316D02*
Y550320D01*
G01X226356Y550315D02*
X226357Y550316D01*
G01Y547170D02*
Y547176D01*
G01Y547167D02*
Y547170D01*
G01X226356Y547165D02*
X226357Y547167D01*
G01Y544020D02*
Y544027D01*
G01Y544017D02*
Y544020D01*
G01X226356Y544016D02*
X226357Y544017D01*
G01Y540871D02*
Y540877D01*
G01Y540867D02*
Y540871D01*
G01X226356Y540866D02*
X226357Y540867D01*
G01Y537721D02*
Y537728D01*
G01Y537718D02*
Y537721D01*
G01X226356Y537717D02*
X226357Y537718D01*
G01X226320Y556594D02*
X226319Y556588D01*
G01X226321Y556601D02*
X226320Y556594D01*
G01X226324Y556607D02*
X226321Y556601D01*
G01X226328Y556612D02*
X226324Y556607D01*
G01X226333Y556617D02*
X226328Y556612D01*
G01X226338Y556620D02*
X226333Y556617D01*
G01X226320Y553445D02*
X226319Y553439D01*
G01X226321Y553451D02*
X226320Y553445D01*
G01X226324Y553457D02*
X226321Y553451D01*
G01X226328Y553462D02*
X226324Y553457D01*
G01X226333Y553467D02*
X226328Y553462D01*
G01X226338Y553470D02*
X226333Y553467D01*
G01X226320Y550295D02*
X226319Y550289D01*
G01X226321Y550302D02*
X226320Y550295D01*
G01X226324Y550307D02*
X226321Y550302D01*
G01X226328Y550313D02*
X226324Y550307D01*
G01X226333Y550317D02*
X226328Y550313D01*
G01X226338Y550321D02*
X226333Y550317D01*
G01X226320Y547146D02*
X226319Y547139D01*
G01X226321Y547152D02*
X226320Y547146D01*
G01X226324Y547158D02*
X226321Y547152D01*
G01X226328Y547163D02*
X226324Y547158D01*
G01X226333Y547168D02*
X226328Y547163D01*
G01X226338Y547171D02*
X226333Y547168D01*
G01X227294Y537715D02*
X227298Y537709D01*
G01X227289Y537719D02*
X227294Y537715D01*
G01X227283Y537723D02*
X227289Y537719D01*
G01X227277Y537726D02*
X227283Y537723D01*
G01X227270Y537727D02*
X227277Y537726D01*
G01X227264Y537728D02*
X227270Y537727D01*
G01X227294Y540865D02*
X227298Y540859D01*
G01X227289Y540869D02*
X227294Y540865D01*
G01X227283Y540872D02*
X227289Y540869D01*
G01X227277Y540875D02*
X227283Y540872D01*
G01X227270Y540877D02*
X227277Y540875D01*
G01X227264Y540877D02*
X227270D01*
G01X227294Y544014D02*
X227298Y544009D01*
G01X227289Y544019D02*
X227294Y544014D01*
G01X227283Y544022D02*
X227289Y544019D01*
G01X227277Y544025D02*
X227283Y544022D01*
G01X227270Y544026D02*
X227277Y544025D01*
G01X227264Y544027D02*
X227270Y544026D01*
G01X227294Y547164D02*
X227298Y547158D01*
G01X227289Y547168D02*
X227294Y547164D01*
G01X227283Y547172D02*
X227289Y547168D01*
G01X227277Y547174D02*
X227283Y547172D01*
G01X227270Y547176D02*
X227277Y547174D01*
G01X227264Y547176D02*
X227270D01*
G01X227294Y550313D02*
X227298Y550308D01*
G01X227289Y550318D02*
X227294Y550313D01*
G01X227283Y550321D02*
X227289Y550318D01*
G01X227277Y550324D02*
X227283Y550321D01*
G01X227270Y550326D02*
X227277Y550324D01*
G01X227264Y550326D02*
X227270D01*
G01X227294Y553463D02*
X227298Y553457D01*
G01X227289Y553467D02*
X227294Y553463D01*
G01X227283Y553471D02*
X227289Y553467D01*
G01X227277Y553474D02*
X227283Y553471D01*
G01X227270Y553475D02*
X227277Y553474D01*
G01X227264Y553476D02*
X227270Y553475D01*
G01X227294Y556613D02*
X227298Y556607D01*
G01X227289Y556617D02*
X227294Y556613D01*
G01X227283Y556620D02*
X227289Y556617D01*
G01X227277Y556623D02*
X227283Y556620D01*
G01X227270Y556625D02*
X227277Y556623D01*
G01X227264Y556625D02*
X227270D01*
G01X226320Y536554D02*
X226319Y536561D01*
G01X226322Y536547D02*
X226320Y536554D01*
G01X226326Y536541D02*
X226322Y536547D01*
G01X226330Y536535D02*
X226326Y536541D01*
G01X226337Y536530D02*
X226330Y536535D01*
G01X226343Y536527D02*
X226337Y536530D01*
G01X226351Y536525D02*
X226343Y536527D01*
G01X226358Y536524D02*
X226351Y536525D01*
G01X226320Y539704D02*
X226319Y539711D01*
G01X226322Y539696D02*
X226320Y539704D01*
G01X226326Y539690D02*
X226322Y539696D01*
G01X226330Y539685D02*
X226326Y539690D01*
G01X226337Y539680D02*
X226330Y539685D01*
G01X226343Y539676D02*
X226337Y539680D01*
G01X226351Y539674D02*
X226343Y539676D01*
G01X226358Y539674D02*
X226351D01*
G01X226320Y542853D02*
X226319Y542860D01*
G01X226322Y542846D02*
X226320Y542853D01*
G01X226326Y542840D02*
X226322Y542846D01*
G01X226330Y542834D02*
X226326Y542840D01*
G01X226337Y542830D02*
X226330Y542834D01*
G01X226343Y542826D02*
X226337Y542830D01*
G01X226351Y542824D02*
X226343Y542826D01*
G01X226358Y542823D02*
X226351Y542824D01*
G01X226320Y546003D02*
X226319Y546010D01*
G01X226322Y545996D02*
X226320Y546003D01*
G01X226326Y545989D02*
X226322Y545996D01*
G01X226330Y545984D02*
X226326Y545989D01*
G01X226337Y545979D02*
X226330Y545984D01*
G01X226343Y545976D02*
X226337Y545979D01*
G01X226351Y545974D02*
X226343Y545976D01*
G01X226358Y545973D02*
X226351Y545974D01*
G01X226320Y549152D02*
X226319Y549159D01*
G01X226322Y549145D02*
X226320Y549152D01*
G01X226326Y549139D02*
X226322Y549145D01*
G01X226330Y549133D02*
X226326Y549139D01*
G01X226337Y549129D02*
X226330Y549133D01*
G01X226343Y549125D02*
X226337Y549129D01*
G01X226351Y549123D02*
X226343Y549125D01*
G01X226358Y549122D02*
X226351Y549123D01*
G01X226320Y552302D02*
X226319Y552309D01*
G01X226322Y552295D02*
X226320Y552302D01*
G01X226326Y552289D02*
X226322Y552295D01*
G01X226330Y552283D02*
X226326Y552289D01*
G01X226337Y552278D02*
X226330Y552283D01*
G01X226343Y552275D02*
X226337Y552278D01*
G01X226351Y552273D02*
X226343Y552275D01*
G01X226358Y552272D02*
X226351Y552273D01*
G01X226320Y555452D02*
X226319Y555459D01*
G01X226322Y555444D02*
X226320Y555452D01*
G01X226326Y555438D02*
X226322Y555444D01*
G01X226330Y555433D02*
X226326Y555438D01*
G01X226337Y555428D02*
X226330Y555433D01*
G01X226343Y555424D02*
X226337Y555428D01*
G01X226351Y555422D02*
X226343Y555424D01*
G01X226358Y555422D02*
X226351D01*
G01X227273Y547164D02*
X227282Y547160D01*
G01X227262Y547165D02*
X227273Y547164D01*
G01Y550313D02*
X227282Y550309D01*
G01X227262Y550315D02*
X227273Y550313D01*
G01Y553463D02*
X227282Y553459D01*
G01X227262Y553465D02*
X227273Y553463D01*
G01Y556613D02*
X227282Y556609D01*
G01X227262Y556614D02*
X227273Y556613D01*
G01X226320Y543996D02*
X226319Y543990D01*
G01X226321Y544002D02*
X226320Y543996D01*
G01X226324Y544008D02*
X226321Y544002D01*
G01X226328Y544013D02*
X226324Y544008D01*
G01X226333Y544018D02*
X226328Y544013D01*
G01X226338Y544022D02*
X226333Y544018D01*
G01X226320Y540846D02*
X226319Y540840D01*
G01X226321Y540853D02*
X226320Y540846D01*
G01X226324Y540859D02*
X226321Y540853D01*
G01X226328Y540864D02*
X226324Y540859D01*
G01X226333Y540869D02*
X226328Y540864D01*
G01X226338Y540872D02*
X226333Y540869D01*
G01X226320Y537697D02*
X226319Y537691D01*
G01X226321Y537703D02*
X226320Y537697D01*
G01X226324Y537709D02*
X226321Y537703D01*
G01X226328Y537714D02*
X226324Y537709D01*
G01X226333Y537719D02*
X226328Y537714D01*
G01X226338Y537722D02*
X226333Y537719D01*
G01X227281Y536528D02*
X227284Y536530D01*
G01X227278Y536526D02*
X227281Y536528D01*
G01X227274Y536526D02*
X227278D01*
G01X227271Y536525D02*
X227274Y536526D01*
G01X227267Y536524D02*
X227271Y536525D01*
G01X227264Y536524D02*
X227267D01*
G01X226341Y537724D02*
X226338Y537722D01*
G01X226344Y537725D02*
X226341Y537724D01*
G01X226348Y537726D02*
X226344Y537725D01*
G01X226351Y537727D02*
X226348Y537726D01*
G01X226355Y537728D02*
X226351Y537727D01*
G01X226358Y537728D02*
X226355D01*
G01X227281Y539677D02*
X227284Y539679D01*
G01X227278Y539676D02*
X227281Y539677D01*
G01X227274Y539675D02*
X227278Y539676D01*
G01X227271Y539674D02*
X227274Y539675D01*
G01X227267Y539674D02*
X227271D01*
G01X227264D02*
X227267D01*
G01X226341Y540874D02*
X226338Y540872D01*
G01X226344Y540875D02*
X226341Y540874D01*
G01X226348Y540876D02*
X226344Y540875D01*
G01X226351Y540877D02*
X226348Y540876D01*
G01X226355Y540877D02*
X226351D01*
G01X226358D02*
X226355D01*
G01X227281Y542827D02*
X227284Y542829D01*
G01X227278Y542826D02*
X227281Y542827D01*
G01X227274Y542825D02*
X227278Y542826D01*
G01X227271Y542824D02*
X227274Y542825D01*
G01X227267Y542824D02*
X227271D01*
G01X227264Y542823D02*
X227267Y542824D01*
G01X226341Y544023D02*
X226338Y544022D01*
G01X226344Y544024D02*
X226341Y544023D01*
G01X226348Y544026D02*
X226344Y544024D01*
G01X226351Y544026D02*
X226348D01*
G01X226355Y544027D02*
X226351Y544026D01*
G01X226358Y544027D02*
X226355D01*
G01X227281Y545976D02*
X227284Y545978D01*
G01X227278Y545975D02*
X227281Y545976D01*
G01X227274Y545974D02*
X227278Y545975D01*
G01X227271Y545974D02*
X227274D01*
G01X227267Y545973D02*
X227271Y545974D01*
G01X227264Y545973D02*
X227267D01*
G01X226341Y547173D02*
X226338Y547171D01*
G01X226344Y547174D02*
X226341Y547173D01*
G01X226348Y547175D02*
X226344Y547174D01*
G01X226351Y547176D02*
X226348Y547175D01*
G01X226355Y547176D02*
X226351D01*
G01X226358D02*
X226355D01*
G01X227281Y549126D02*
X227284Y549128D01*
G01X227278Y549125D02*
X227281Y549126D01*
G01X227274Y549124D02*
X227278Y549125D01*
G01X227271Y549123D02*
X227274Y549124D01*
G01X227267Y549123D02*
X227271D01*
G01X227264Y549122D02*
X227267Y549123D01*
G01X226341Y550322D02*
X226338Y550321D01*
G01X226344Y550324D02*
X226341Y550322D01*
G01X226348Y550325D02*
X226344Y550324D01*
G01X226351Y550326D02*
X226348Y550325D01*
G01X226355Y550326D02*
X226351D01*
G01X226358D02*
X226355D01*
G01X226341Y553472D02*
X226338Y553470D01*
G01X226344Y553473D02*
X226341Y553472D01*
G01X226348Y553474D02*
X226344Y553473D01*
G01X226351Y553475D02*
X226348Y553474D01*
G01X226355Y553476D02*
X226351Y553475D01*
G01X226358Y553476D02*
X226355D01*
G01X227281Y555425D02*
X227284Y555427D01*
G01X227278Y555424D02*
X227281Y555425D01*
G01X227274Y555423D02*
X227278Y555424D01*
G01X227271Y555422D02*
X227274Y555423D01*
G01X227267Y555422D02*
X227271D01*
G01X227264D02*
X227267D01*
G01X226341Y556622D02*
X226338Y556620D01*
G01X226344Y556623D02*
X226341Y556622D01*
G01X226348Y556624D02*
X226344Y556623D01*
G01X226351Y556625D02*
X226348Y556624D01*
G01X226355Y556625D02*
X226351D01*
G01X226358D02*
X226355D01*
G01X225572Y539724D02*
X225138D01*
G01X225945D02*
X225572D01*
G01Y546024D02*
X225138D01*
G01X225945D02*
X225572D01*
G01Y549173D02*
X225138D01*
G01X225945D02*
X225572D01*
G01X227274Y555435D02*
X227262Y555433D01*
G01X227285Y555440D02*
X227274Y555435D01*
G01Y552285D02*
X227262Y552283D01*
G01X227285Y552290D02*
X227274Y552285D01*
G01Y549136D02*
X227262Y549134D01*
G01X227285Y549141D02*
X227274Y549136D01*
G01Y545986D02*
X227262Y545984D01*
G01X227285Y545991D02*
X227274Y545986D01*
G01Y542837D02*
X227262Y542835D01*
G01X227285Y542841D02*
X227274Y542837D01*
G01Y539687D02*
X227262Y539685D01*
G01X227285Y539692D02*
X227274Y539687D01*
G01Y536537D02*
X227262Y536535D01*
G01X227285Y536542D02*
X227274Y536537D01*
G01X227302Y552302D02*
X227303Y552309D01*
G01X227300Y552295D02*
X227302Y552302D01*
G01X227296Y552289D02*
X227300Y552295D01*
G01X227292Y552283D02*
X227296Y552289D01*
G01X227285Y552278D02*
X227292Y552283D01*
G01X227279Y552275D02*
X227285Y552278D01*
G01X227272Y552273D02*
X227279Y552275D01*
G01X227264Y552272D02*
X227272Y552273D01*
G01X226322Y537697D02*
X226317Y537677D01*
G01X226336Y537711D02*
X226322Y537697D01*
G01X226356Y537717D02*
X226336Y537711D01*
G01X226322Y540846D02*
X226317Y540827D01*
G01X226336Y540861D02*
X226322Y540846D01*
G01X226356Y540866D02*
X226336Y540861D01*
G01X226322Y543996D02*
X226317Y543976D01*
G01X226336Y544010D02*
X226322Y543996D01*
G01X226356Y544016D02*
X226336Y544010D01*
G01X226322Y547146D02*
X226317Y547126D01*
G01X226336Y547160D02*
X226322Y547146D01*
G01X226356Y547165D02*
X226336Y547160D01*
G01X226322Y550295D02*
X226317Y550276D01*
G01X226336Y550309D02*
X226322Y550295D01*
G01X226356Y550315D02*
X226336Y550309D01*
G01X226322Y553445D02*
X226317Y553425D01*
G01X226336Y553459D02*
X226322Y553445D01*
G01X226356Y553465D02*
X226336Y553459D01*
G01X226322Y556594D02*
X226317Y556575D01*
G01X226336Y556609D02*
X226322Y556594D01*
G01X226356Y556614D02*
X226336Y556609D01*
G01X227296Y536555D02*
X227302Y536575D01*
G01X227282Y536541D02*
X227296Y536555D01*
G01X227262Y536535D02*
X227282Y536541D01*
G01X227296Y539705D02*
X227302Y539724D01*
G01X227282Y539690D02*
X227296Y539705D01*
G01X227262Y539685D02*
X227282Y539690D01*
G01X227296Y542854D02*
X227302Y542874D01*
G01X227282Y542840D02*
X227296Y542854D01*
G01X227262Y542835D02*
X227282Y542840D01*
G01X227296Y546004D02*
X227302Y546024D01*
G01X227282Y545989D02*
X227296Y546004D01*
G01X227262Y545984D02*
X227282Y545989D01*
G01X227296Y549154D02*
X227302Y549173D01*
G01X227282Y549139D02*
X227296Y549154D01*
G01X227262Y549134D02*
X227282Y549139D01*
G01X227296Y552303D02*
X227302Y552323D01*
G01X227282Y552289D02*
X227296Y552303D01*
G01X227262Y552283D02*
X227282Y552289D01*
G01X227296Y555453D02*
X227302Y555472D01*
G01X227282Y555438D02*
X227296Y555453D01*
G01X227262Y555433D02*
X227282Y555438D01*
G01X236339Y492264D02*
G03I-1103J0D01*
G01X237795Y486988D02*
G03X238976Y488169I0J1181D01*
G01X231496D02*
G03X232677Y486988I1181J0D01*
G01X236811Y492264D02*
G03I-1575J0D01*
G01X231299Y477894D02*
G03X231890Y477303I591J0D01*
G01X238583D02*
G03X239173Y477894I0J590D01*
G01X236417Y479075D02*
G03Y481043I0J984D01*
G01X234055D02*
G03Y479075I0J-984D01*
G01X224409Y478484D02*
G03X226378Y476516I1969J1D01*
G01X244094D02*
G03X246063Y478484I1J1968D01*
G01X240728Y570256D02*
X239744D01*
G01X239746Y569764D02*
X245079D01*
G01Y569724D02*
X240731D01*
G01X245079Y568386D02*
X239746D01*
G01X239744Y567894D02*
X240728D01*
G01Y565256D02*
X239744D01*
G01X239746Y564764D02*
X245079D01*
G01Y564724D02*
X240731D01*
G01X245079Y563386D02*
X239746D01*
G01X239744Y562894D02*
X240728D01*
G01Y560256D02*
X239744D01*
G01X239746Y559764D02*
X245079D01*
G01Y559724D02*
X240731D01*
G01X227756Y558780D02*
X224409D01*
G01X245079Y558386D02*
X239746D01*
G01X239744Y557894D02*
X240728D01*
G01X237402Y557618D02*
X241339D01*
G01X227264Y556811D02*
X226358D01*
G01X227303Y556772D02*
X226319D01*
G01X227262Y556614D02*
X221378D01*
G01Y556575D02*
X227302D01*
G01X236220Y556437D02*
X240157D01*
G01X227302Y555472D02*
X221378D01*
G01X227262Y555433D02*
X221378D01*
G01X226319Y555276D02*
X227303D01*
G01X226358Y555236D02*
X227264D01*
G01Y553661D02*
X226358D01*
G01X227303Y553622D02*
X226319D01*
G01X227262Y553465D02*
X221378D01*
G01Y553425D02*
X227302D01*
G01Y552323D02*
X221378D01*
G01X227262Y552283D02*
X221378D01*
G01X226319Y552126D02*
X227303D01*
G01X226358Y552087D02*
X227264D01*
G01Y550512D02*
X226358D01*
G01X227303Y550472D02*
X226319D01*
G01X227262Y550315D02*
X221378D01*
G01Y550276D02*
X227302D01*
G01Y549173D02*
X221378D01*
G01X227262Y549134D02*
X221378D01*
G01X226319Y548976D02*
X227303D01*
G01X226358Y548937D02*
X227264D01*
G01Y547362D02*
X226358D01*
G01X227303Y547323D02*
X226319D01*
G01X227262Y547165D02*
X221378D01*
G01Y547126D02*
X227302D01*
G01Y546024D02*
X221378D01*
G01X227262Y545984D02*
X221378D01*
G01X226319Y545827D02*
X227303D01*
G01X226358Y545787D02*
X227264D01*
G01Y544213D02*
X226358D01*
G01X227303Y544173D02*
X226319D01*
G01X227262Y544016D02*
X221378D01*
G01Y543976D02*
X227302D01*
G01Y542874D02*
X221378D01*
G01X227262Y542835D02*
X221378D01*
G01X226319Y542677D02*
X227303D01*
G01X226358Y542638D02*
X227264D01*
G01Y541063D02*
X226358D01*
G01X227303Y541024D02*
X226319D01*
G01X227262Y540866D02*
X221378D01*
G01Y540827D02*
X227302D01*
G01Y539724D02*
X221378D01*
G01X227262Y539685D02*
X221378D01*
G01X226319Y539528D02*
X227303D01*
G01X226358Y539488D02*
X227264D01*
G01Y537913D02*
X226358D01*
G01X227303Y537874D02*
X226319D01*
G01X227262Y537717D02*
X221378D01*
G01Y537677D02*
X227302D01*
G01X240157Y536713D02*
X236220D01*
G01X227302Y536575D02*
X221378D01*
G01X227262Y536535D02*
X221378D01*
G01X226319Y536378D02*
X227303D01*
G01X226358Y536339D02*
X227264D01*
G01X241339Y535531D02*
X237402D01*
G01X240728Y535256D02*
X239744D01*
G01X239746Y534764D02*
X245079D01*
G01Y534724D02*
X240731D01*
G01X227756Y534370D02*
X224409D01*
G01X245079Y533386D02*
X239746D01*
G01X239744Y532894D02*
X240728D01*
G01Y530256D02*
X239744D01*
G01X239746Y529764D02*
X245079D01*
G01Y529724D02*
X240731D01*
G01X245079Y528386D02*
X239746D01*
G01X239744Y569959D02*
X240699Y569961D01*
G01X240728Y568190D02*
X239744Y568189D01*
G01Y564959D02*
X240699Y564961D01*
G01X240728Y563190D02*
X239744Y563189D01*
G01Y559959D02*
X240699Y559961D01*
G01X240728Y558190D02*
X239744Y558189D01*
G01Y534959D02*
X240699Y534961D01*
G01X240728Y533190D02*
X239744Y533189D01*
G01Y529959D02*
X240699Y529961D01*
G01X240728Y528190D02*
X239744Y528189D01*
G01X226206Y555472D02*
X226317Y555464D01*
G01Y546019D02*
X226206Y546024D01*
G01X226317Y539721D02*
X226206Y539724D01*
G01X226317Y549170D02*
X226206Y549173D01*
G01X239744Y527894D02*
X240728D01*
G01Y525256D02*
X239744D01*
G01X239746Y524764D02*
X245079D01*
G01Y524724D02*
X240731D01*
G01X245079Y523386D02*
X239746D01*
G01X239744Y522894D02*
X240728D01*
G01Y520256D02*
X239744D01*
G01X239746Y519764D02*
X245079D01*
G01Y519724D02*
X240731D01*
G01X245079Y518386D02*
X239746D01*
G01X239744Y517894D02*
X240728D01*
G01Y515256D02*
X239744D01*
G01X239746Y514764D02*
X245079D01*
G01Y514724D02*
X240731D01*
G01X245079Y513386D02*
X239746D01*
G01X239744Y512894D02*
X240728D01*
G01Y510256D02*
X239744D01*
G01X239746Y509764D02*
X245079D01*
G01Y509724D02*
X240731D01*
G01X245079Y508386D02*
X239746D01*
G01X239744Y507894D02*
X240728D01*
G01Y505256D02*
X239744D01*
G01X239746Y504764D02*
X245079D01*
G01Y504724D02*
X240731D01*
G01X245079Y503386D02*
X239746D01*
G01X239744Y502894D02*
X240728D01*
G01X236220Y500256D02*
X230709D01*
G01X237402Y499075D02*
X229528D01*
G01X242717Y497579D02*
X227756D01*
G01X238976Y496713D02*
X242126D01*
G01X231496D02*
X227756D01*
G01Y495335D02*
X242126D01*
G01X236417Y493366D02*
X234055D01*
G01X236417Y491673D02*
X234055D01*
G01X237795Y486988D02*
X232677D01*
G01X246063Y486949D02*
X224409D01*
G01X239173Y483996D02*
X231299D01*
G01Y482421D02*
X239173D01*
G01X236417Y481043D02*
X234055D01*
G01Y479075D02*
X236417D01*
G01X238583Y477303D02*
X231890D01*
G01X244094Y476516D02*
X226378D01*
G01X239744Y524959D02*
X240699Y524961D01*
G01X240728Y523190D02*
X239744Y523189D01*
G01Y519959D02*
X240699Y519961D01*
G01X240728Y518190D02*
X239744Y518189D01*
G01Y514959D02*
X240699Y514961D01*
G01X240728Y513190D02*
X239744Y513189D01*
G01Y509959D02*
X240699Y509961D01*
G01X240728Y508190D02*
X239744Y508189D01*
G01Y504959D02*
X240699Y504961D01*
G01X240728Y503190D02*
X239744Y503189D01*
G01X230709Y500256D02*
X229528Y499075D01*
G01X227756Y497579D02*
X224409Y494232D01*
G01X240157Y556437D02*
X241339Y557618D01*
G01X236220Y556437D02*
X237402Y557618D01*
G01X237721Y495335D02*
X236417Y493366D01*
G01X231745Y487444D02*
X234055Y491673D01*
G01X240157Y536713D02*
X241339Y535531D01*
G01X236220Y536713D02*
X237402Y535531D01*
G01X242717Y497579D02*
X246063Y494232D01*
G01X236220Y500256D02*
X237402Y499075D01*
G01X240728Y504738D02*
X240729Y504746D01*
G01X240728Y509738D02*
X240729Y509746D01*
G01X240728Y514738D02*
X240729Y514746D01*
G01X240728Y519738D02*
X240729Y519746D01*
G01X240728Y524738D02*
X240729Y524746D01*
G01X240728Y529738D02*
X240729Y529746D01*
G01X240728Y534738D02*
X240729Y534746D01*
G01X240728Y559738D02*
X240729Y559746D01*
G01X240728Y564738D02*
X240729Y564746D01*
G01X240728Y569738D02*
X240729Y569746D01*
G01X246063Y478484D02*
Y494232D01*
G01X245079Y568386D02*
Y569764D01*
G01Y563386D02*
Y564764D01*
G01Y558386D02*
Y559764D01*
G01Y533386D02*
Y534764D01*
G01Y528386D02*
Y529764D01*
G01Y523386D02*
Y524764D01*
G01Y518386D02*
Y519764D01*
G01Y513386D02*
Y514764D01*
G01Y508386D02*
Y509764D01*
G01Y503386D02*
Y504764D01*
G01X242717Y635571D02*
Y497579D01*
G01X242126Y637815D02*
Y495335D01*
G01X241909Y504764D02*
Y503386D01*
G01Y509764D02*
Y508386D01*
G01Y514764D02*
Y513386D01*
G01Y519764D02*
Y518386D01*
G01Y524764D02*
Y523386D01*
G01Y529764D02*
Y528386D01*
G01Y534764D02*
Y533386D01*
G01Y559764D02*
Y558386D01*
G01Y564764D02*
Y563386D01*
G01Y569764D02*
Y568386D01*
G01X241339Y557618D02*
Y535531D01*
G01X240728Y509738D02*
Y509881D01*
G01Y504738D02*
Y504881D01*
G01Y519738D02*
Y519881D01*
G01Y514738D02*
Y514881D01*
G01Y529738D02*
Y529881D01*
G01Y524738D02*
Y524881D01*
G01Y534738D02*
Y534881D01*
G01Y559738D02*
Y559881D01*
G01Y569738D02*
Y569881D01*
G01Y564738D02*
Y564881D01*
G01Y567894D02*
Y570256D01*
G01Y562894D02*
Y565256D01*
G01Y557894D02*
Y560256D01*
G01Y532894D02*
Y535256D01*
G01Y527894D02*
Y530256D01*
G01Y522894D02*
Y525256D01*
G01Y517894D02*
Y520256D01*
G01Y512894D02*
Y515256D01*
G01Y507894D02*
Y510256D01*
G01Y502894D02*
Y505256D01*
G01X240157Y556437D02*
Y536713D01*
G01X239744Y505256D02*
Y502894D01*
G01Y510256D02*
Y507894D01*
G01Y515256D02*
Y512894D01*
G01Y520256D02*
Y517894D01*
G01Y525256D02*
Y522894D01*
G01Y530256D02*
Y527894D01*
G01Y535256D02*
Y532894D01*
G01Y560256D02*
Y557894D01*
G01Y565256D02*
Y562894D01*
G01Y570256D02*
Y567894D01*
G01X239173Y483996D02*
Y477894D01*
G01X227262Y552283D02*
X227266Y552272D01*
G01X236417Y491673D02*
X238728Y487444D01*
G01X234055Y493366D02*
X232752Y495335D01*
G01X227303Y537679D02*
Y537691D01*
G01Y540829D02*
Y540840D01*
G01Y543978D02*
Y543990D01*
G01Y547128D02*
Y547139D01*
G01Y550278D02*
Y550289D01*
G01Y553427D02*
Y553439D01*
G01Y556577D02*
Y556588D01*
G01X238976Y496713D02*
Y488169D01*
G01X237402Y535531D02*
Y499075D01*
G01Y634075D02*
Y557618D01*
G01X236417Y493366D02*
Y491673D01*
G01X236220Y536713D02*
Y500256D01*
G01Y632894D02*
Y556437D01*
G01X234055Y491673D02*
Y493366D01*
G01X231496Y488169D02*
Y496713D01*
G01X231299Y483996D02*
Y477894D01*
G01X230709Y500256D02*
Y632894D01*
G01X229528Y499075D02*
Y634075D01*
G01X227756Y534370D02*
Y495335D01*
G01Y637815D02*
Y558780D01*
G01X227303Y555275D02*
Y556772D01*
G01Y552126D02*
Y553622D01*
G01Y548976D02*
Y550472D01*
G01Y545826D02*
Y547323D01*
G01Y542677D02*
Y544173D01*
G01Y539527D02*
Y541024D01*
G01Y536378D02*
Y537874D01*
G01X227264Y536524D02*
Y536377D01*
G01Y539674D02*
Y539527D01*
G01Y541024D02*
Y540877D01*
G01Y537874D02*
Y537728D01*
G01Y545973D02*
Y545826D01*
G01Y542823D02*
Y542676D01*
G01Y544174D02*
Y544027D01*
G01Y549122D02*
Y548976D01*
G01Y550473D02*
Y550326D01*
G01Y547323D02*
Y547176D01*
G01Y555422D02*
Y555275D01*
G01Y552272D02*
Y552125D01*
G01Y553622D02*
Y553476D01*
G01Y556772D02*
Y556625D01*
G01X226358D02*
Y556772D01*
G01Y555275D02*
Y555422D01*
G01Y552125D02*
Y552272D01*
G01Y553476D02*
Y553622D01*
G01Y548976D02*
Y549122D01*
G01Y550326D02*
Y550473D01*
G01Y547176D02*
Y547323D01*
G01Y545826D02*
Y545973D01*
G01Y542676D02*
Y542823D01*
G01Y544027D02*
Y544174D01*
G01Y539527D02*
Y539674D01*
G01Y540877D02*
Y541024D01*
G01Y537728D02*
Y537874D01*
G01Y536377D02*
Y536524D01*
G01X226319Y541024D02*
Y539528D01*
G01Y537874D02*
Y536378D01*
G01Y544173D02*
Y542677D01*
G01Y550472D02*
Y548976D01*
G01Y547323D02*
Y545827D01*
G01Y553622D02*
Y552126D01*
G01Y556772D02*
Y555276D01*
G01X225138Y537717D02*
Y536535D01*
G01Y540866D02*
Y539685D01*
G01Y547165D02*
Y545984D01*
G01Y544016D02*
Y542835D01*
G01Y550315D02*
Y549134D01*
G01Y556614D02*
Y555433D01*
G01Y553465D02*
Y552283D01*
G01X224803Y558780D02*
Y534370D01*
G01X224409D02*
Y558780D01*
G01Y494232D02*
Y478484D01*
G01X221378Y555433D02*
Y556614D01*
G01Y552283D02*
Y553465D01*
G01Y549134D02*
Y550315D01*
G01Y545984D02*
Y547165D01*
G01Y542835D02*
Y544016D01*
G01Y539685D02*
Y540866D01*
G01Y536535D02*
Y537717D01*
G01X227303Y555459D02*
Y555470D01*
G01Y552309D02*
Y552320D01*
G01Y549160D02*
Y549170D01*
G01Y546010D02*
Y546021D01*
G01Y542861D02*
Y542871D01*
G01Y539711D02*
Y539722D01*
G01Y536561D02*
Y536572D01*
G01X240695Y574862D02*
X240699Y574961D01*
G01X240690Y574790D02*
X240695Y574862D01*
G01X240692Y574764D02*
X240690Y574790D01*
G01X240695Y579862D02*
X240699Y579961D01*
G01X240690Y579790D02*
X240695Y579862D01*
G01X240692Y579764D02*
X240690Y579790D01*
G01X240695Y584862D02*
X240699Y584961D01*
G01X240690Y584790D02*
X240695Y584862D01*
G01X240692Y584764D02*
X240690Y584790D01*
G01X240695Y589862D02*
X240699Y589961D01*
G01X240690Y589790D02*
X240695Y589862D01*
G01X240692Y589764D02*
X240690Y589790D01*
G01X240695Y594862D02*
X240699Y594961D01*
G01X240690Y594790D02*
X240695Y594862D01*
G01X240692Y594764D02*
X240690Y594790D01*
G01X240695Y599862D02*
X240699Y599961D01*
G01X240690Y599790D02*
X240695Y599862D01*
G01X240692Y599764D02*
X240690Y599790D01*
G01X240695Y604862D02*
X240699Y604961D01*
G01X240690Y604790D02*
X240695Y604862D01*
G01X240692Y604764D02*
X240690Y604790D01*
G01X240695Y609862D02*
X240699Y609961D01*
G01X240690Y609790D02*
X240695Y609862D01*
G01X240692Y609764D02*
X240690Y609790D01*
G01X240695Y614862D02*
X240699Y614961D01*
G01X240690Y614790D02*
X240695Y614862D01*
G01X240692Y614764D02*
X240690Y614790D01*
G01X240695Y619862D02*
X240699Y619961D01*
G01X240690Y619790D02*
X240695Y619862D01*
G01X240692Y619764D02*
X240690Y619790D01*
G01X240695Y624862D02*
X240699Y624961D01*
G01X240690Y624790D02*
X240695Y624862D01*
G01X240692Y624764D02*
X240690Y624790D01*
G01X240695Y629862D02*
X240699Y629961D01*
G01X240690Y629790D02*
X240695Y629862D01*
G01X240692Y629764D02*
X240690Y629790D01*
G01X239744Y574771D02*
Y574780D01*
G01X239745Y574765D02*
X239744Y574771D01*
G01X239746Y574764D02*
X239745Y574765D01*
G01X239744Y579771D02*
Y579780D01*
G01X239745Y579765D02*
X239744Y579771D01*
G01X239746Y579764D02*
X239745Y579765D01*
G01X239744Y584771D02*
Y584780D01*
G01X239745Y584765D02*
X239744Y584771D01*
G01X239746Y584764D02*
X239745Y584765D01*
G01X239744Y589771D02*
Y589780D01*
G01X239745Y589765D02*
X239744Y589771D01*
G01X239746Y589764D02*
X239745Y589765D01*
G01X239744Y594771D02*
Y594780D01*
G01X239745Y594765D02*
X239744Y594771D01*
G01X239746Y594764D02*
X239745Y594765D01*
G01X239744Y599771D02*
Y599780D01*
G01X239745Y599765D02*
X239744Y599771D01*
G01X239746Y599764D02*
X239745Y599765D01*
G01X239744Y604771D02*
Y604780D01*
G01X239745Y604765D02*
X239744Y604771D01*
G01X239746Y604764D02*
X239745Y604765D01*
G01X240720Y574907D02*
X240728Y574881D01*
G01X240711Y574934D02*
X240720Y574907D01*
G01X240699Y574961D02*
X240711Y574934D01*
G01X240720Y579907D02*
X240728Y579881D01*
G01X240711Y579934D02*
X240720Y579907D01*
G01X240699Y579961D02*
X240711Y579934D01*
G01X240720Y584907D02*
X240728Y584881D01*
G01X240711Y584934D02*
X240720Y584907D01*
G01X240699Y584961D02*
X240711Y584934D01*
G01X240720Y589907D02*
X240728Y589881D01*
G01X240711Y589934D02*
X240720Y589907D01*
G01X240699Y589961D02*
X240711Y589934D01*
G01X240720Y594907D02*
X240728Y594881D01*
G01X240711Y594934D02*
X240720Y594907D01*
G01X240699Y594961D02*
X240711Y594934D01*
G01X240720Y599907D02*
X240728Y599881D01*
G01X240711Y599934D02*
X240720Y599907D01*
G01X240699Y599961D02*
X240711Y599934D01*
G01X240720Y604907D02*
X240728Y604881D01*
G01X240711Y604934D02*
X240720Y604907D01*
G01X240699Y604961D02*
X240711Y604934D01*
G01Y574759D02*
X240692Y574764D01*
G01X240726Y574744D02*
X240711Y574759D01*
G01X240731Y574724D02*
X240726Y574744D01*
G01X240711Y579759D02*
X240692Y579764D01*
G01X240726Y579744D02*
X240711Y579759D01*
G01X240731Y579724D02*
X240726Y579744D01*
G01X240711Y584759D02*
X240692Y584764D01*
G01X240726Y584744D02*
X240711Y584759D01*
G01X240731Y584724D02*
X240726Y584744D01*
G01X240711Y589759D02*
X240692Y589764D01*
G01X240726Y589744D02*
X240711Y589759D01*
G01X240731Y589724D02*
X240726Y589744D01*
G01X240711Y594759D02*
X240692Y594764D01*
G01X240726Y594744D02*
X240711Y594759D01*
G01X240731Y594724D02*
X240726Y594744D01*
G01X240711Y599759D02*
X240692Y599764D01*
G01X240726Y599744D02*
X240711Y599759D01*
G01X240731Y599724D02*
X240726Y599744D01*
G01X240711Y604759D02*
X240692Y604764D01*
G01X240726Y604744D02*
X240711Y604759D01*
G01X240731Y604724D02*
X240726Y604744D01*
G01X240711Y609759D02*
X240692Y609764D01*
G01X240726Y609744D02*
X240711Y609759D01*
G01X240731Y609724D02*
X240726Y609744D01*
G01X240711Y614759D02*
X240692Y614764D01*
G01X240726Y614744D02*
X240711Y614759D01*
G01X240731Y614724D02*
X240726Y614744D01*
G01X240711Y619759D02*
X240692Y619764D01*
G01X240726Y619744D02*
X240711Y619759D01*
G01X240731Y619724D02*
X240726Y619744D01*
G01X240711Y624759D02*
X240692Y624764D01*
G01X240726Y624744D02*
X240711Y624759D01*
G01X240731Y624724D02*
X240726Y624744D01*
G01X240711Y629759D02*
X240692Y629764D01*
G01X240726Y629744D02*
X240711Y629759D01*
G01X240731Y629724D02*
X240726Y629744D01*
G01X239745Y628384D02*
X239746Y628386D01*
G01X239744Y628378D02*
X239745Y628384D01*
G01X239744Y628370D02*
Y628378D01*
G01X239745Y623384D02*
X239746Y623386D01*
G01X239744Y623378D02*
X239745Y623384D01*
G01X239744Y623370D02*
Y623378D01*
G01X239745Y618384D02*
X239746Y618386D01*
G01X239744Y618378D02*
X239745Y618384D01*
G01X239744Y618370D02*
Y618378D01*
G01X239745Y613384D02*
X239746Y613386D01*
G01X239744Y613378D02*
X239745Y613384D01*
G01X239744Y613370D02*
Y613378D01*
G01X239745Y608384D02*
X239746Y608386D01*
G01X239744Y608378D02*
X239745Y608384D01*
G01X239744Y608370D02*
Y608378D01*
G01X239745Y603384D02*
X239746Y603386D01*
G01X239744Y603378D02*
X239745Y603384D01*
G01X239744Y603370D02*
Y603378D01*
G01X239745Y598384D02*
X239746Y598386D01*
G01X239744Y598378D02*
X239745Y598384D01*
G01X239744Y598370D02*
Y598378D01*
G01X239745Y593384D02*
X239746Y593386D01*
G01X239744Y593378D02*
X239745Y593384D01*
G01X239744Y593370D02*
Y593378D01*
G01X239745Y588384D02*
X239746Y588386D01*
G01X239744Y588378D02*
X239745Y588384D01*
G01X239744Y588370D02*
Y588378D01*
G01X239745Y583384D02*
X239746Y583386D01*
G01X239744Y583378D02*
X239745Y583384D01*
G01X239744Y583370D02*
Y583378D01*
G01X239745Y578384D02*
X239746Y578386D01*
G01X239744Y578378D02*
X239745Y578384D01*
G01X239744Y578370D02*
Y578378D01*
G01X239745Y573384D02*
X239746Y573386D01*
G01X239744Y573378D02*
X239745Y573384D01*
G01X239744Y573370D02*
Y573378D01*
G01X240729Y574731D02*
X240728Y574738D01*
G01X240730Y574726D02*
X240729Y574731D01*
G01X240731Y574724D02*
X240730Y574726D01*
G01X240729Y579731D02*
X240728Y579738D01*
G01X240730Y579726D02*
X240729Y579731D01*
G01X240731Y579724D02*
X240730Y579726D01*
G01X240729Y584731D02*
X240728Y584738D01*
G01X240730Y584726D02*
X240729Y584731D01*
G01X240731Y584724D02*
X240730Y584726D01*
G01X240729Y589731D02*
X240728Y589738D01*
G01X240730Y589726D02*
X240729Y589731D01*
G01X240731Y589724D02*
X240730Y589726D01*
G01X240729Y594731D02*
X240728Y594738D01*
G01X240730Y594726D02*
X240729Y594731D01*
G01X240731Y594724D02*
X240730Y594726D01*
G01X240729Y599731D02*
X240728Y599738D01*
G01X240730Y599726D02*
X240729Y599731D01*
G01X240731Y599724D02*
X240730Y599726D01*
G01X240729Y604731D02*
X240728Y604738D01*
G01X240730Y604726D02*
X240729Y604731D01*
G01X240731Y604724D02*
X240730Y604726D01*
G01X240729Y609731D02*
X240728Y609738D01*
G01X240730Y609726D02*
X240729Y609731D01*
G01X240731Y609724D02*
X240730Y609726D01*
G01X240729Y614731D02*
X240728Y614738D01*
G01X240730Y614726D02*
X240729Y614731D01*
G01X240731Y614724D02*
X240730Y614726D01*
G01X240729Y619731D02*
X240728Y619738D01*
G01X240730Y619726D02*
X240729Y619731D01*
G01X240731Y619724D02*
X240730Y619726D01*
G01X240729Y624731D02*
X240728Y624738D01*
G01X240730Y624726D02*
X240729Y624731D01*
G01X240731Y624724D02*
X240730Y624726D01*
G01X240729Y629731D02*
X240728Y629738D01*
G01X240730Y629726D02*
X240729Y629731D01*
G01X240731Y629724D02*
X240730Y629726D01*
G01X239744Y609771D02*
Y609780D01*
G01X239745Y609765D02*
X239744Y609771D01*
G01X239746Y609764D02*
X239745Y609765D01*
G01X239744Y614771D02*
Y614780D01*
G01X239745Y614765D02*
X239744Y614771D01*
G01X239746Y614764D02*
X239745Y614765D01*
G01X239744Y619771D02*
Y619780D01*
G01X239745Y619765D02*
X239744Y619771D01*
G01X239746Y619764D02*
X239745Y619765D01*
G01X239744Y624771D02*
Y624780D01*
G01X239745Y624765D02*
X239744Y624771D01*
G01X239746Y624764D02*
X239745Y624765D01*
G01X239744Y629771D02*
Y629780D01*
G01X239745Y629765D02*
X239744Y629771D01*
G01X239746Y629764D02*
X239745Y629765D01*
G01X240720Y609907D02*
X240728Y609881D01*
G01X240711Y609934D02*
X240720Y609907D01*
G01X240699Y609961D02*
X240711Y609934D01*
G01X240720Y614907D02*
X240728Y614881D01*
G01X240711Y614934D02*
X240720Y614907D01*
G01X240699Y614961D02*
X240711Y614934D01*
G01X240720Y619907D02*
X240728Y619881D01*
G01X240711Y619934D02*
X240720Y619907D01*
G01X240699Y619961D02*
X240711Y619934D01*
G01X240720Y624907D02*
X240728Y624881D01*
G01X240711Y624934D02*
X240720Y624907D01*
G01X240699Y624961D02*
X240711Y624934D01*
G01X240720Y629907D02*
X240728Y629881D01*
G01X240711Y629934D02*
X240720Y629907D01*
G01X240699Y629961D02*
X240711Y629934D01*
G01X240729Y628378D02*
X240728Y628369D01*
G01X240730Y628384D02*
X240729Y628378D01*
G01X240731Y628386D02*
X240730Y628384D01*
G01X240729Y623378D02*
X240728Y623369D01*
G01X240730Y623384D02*
X240729Y623378D01*
G01X240731Y623386D02*
X240730Y623384D01*
G01X240729Y618378D02*
X240728Y618369D01*
G01X240730Y618384D02*
X240729Y618378D01*
G01X240731Y618386D02*
X240730Y618384D01*
G01X240729Y613378D02*
X240728Y613369D01*
G01X240730Y613384D02*
X240729Y613378D01*
G01X240731Y613386D02*
X240730Y613384D01*
G01X240729Y608378D02*
X240728Y608369D01*
G01X240730Y608384D02*
X240729Y608378D01*
G01X240731Y608386D02*
X240730Y608384D01*
G01X240729Y603378D02*
X240728Y603369D01*
G01X240730Y603384D02*
X240729Y603378D01*
G01X240731Y603386D02*
X240730Y603384D01*
G01X240729Y598378D02*
X240728Y598369D01*
G01X240730Y598384D02*
X240729Y598378D01*
G01X240731Y598386D02*
X240730Y598384D01*
G01X240729Y593378D02*
X240728Y593369D01*
G01X240730Y593384D02*
X240729Y593378D01*
G01X240731Y593386D02*
X240730Y593384D01*
G01X240729Y588378D02*
X240728Y588369D01*
G01X240730Y588384D02*
X240729Y588378D01*
G01X240731Y588386D02*
X240730Y588384D01*
G01X240729Y583378D02*
X240728Y583369D01*
G01X240730Y583384D02*
X240729Y583378D01*
G01X240731Y583386D02*
X240730Y583384D01*
G01X240729Y578378D02*
X240728Y578369D01*
G01X240730Y578384D02*
X240729Y578378D01*
G01X240731Y578386D02*
X240730Y578384D01*
G01X240729Y573378D02*
X240728Y573369D01*
G01X240730Y573384D02*
X240729Y573378D01*
G01X240731Y573386D02*
X240730Y573384D01*
G01X240716Y574755D02*
X240727Y574740D01*
G01X240691Y574764D02*
X240716Y574755D01*
G01Y579755D02*
X240727Y579740D01*
G01X240691Y579764D02*
X240716Y579755D01*
G01Y584755D02*
X240727Y584740D01*
G01X240691Y584764D02*
X240716Y584755D01*
G01Y589755D02*
X240727Y589740D01*
G01X240691Y589764D02*
X240716Y589755D01*
G01Y594755D02*
X240727Y594740D01*
G01X240691Y594764D02*
X240716Y594755D01*
G01Y599755D02*
X240727Y599740D01*
G01X240691Y599764D02*
X240716Y599755D01*
G01Y604755D02*
X240727Y604740D01*
G01X240691Y604764D02*
X240716Y604755D01*
G01Y609755D02*
X240727Y609740D01*
G01X240691Y609764D02*
X240716Y609755D01*
G01Y614755D02*
X240727Y614740D01*
G01X240691Y614764D02*
X240716Y614755D01*
G01Y619755D02*
X240727Y619740D01*
G01X240691Y619764D02*
X240716Y619755D01*
G01Y624755D02*
X240727Y624740D01*
G01X240691Y624764D02*
X240716Y624755D01*
G01Y629755D02*
X240727Y629740D01*
G01X240691Y629764D02*
X240716Y629755D01*
G01X239173Y655256D02*
G03X238583Y655846I-590J0D01*
G01X231890D02*
G03X231299Y655256I0J-591D01*
G01X234055Y654075D02*
G03Y652106I0J-985D01*
G01X236417D02*
G03Y654075I0J984D01*
G01X232677Y646161D02*
G03X231496Y644980I0J-1181D01*
G01X238976D02*
G03X237795Y646161I-1181J0D01*
G01X237126Y640886D02*
G03I-1890J0D01*
G01X246063Y654665D02*
G03X244094Y656634I-1969J0D01*
G01X226378D02*
G03X224409Y654665I0J-1969D01*
G01X237598Y640886D02*
G03I-2362J0D01*
G01X244094Y656634D02*
X226378D01*
G01X238583Y655846D02*
X231890D01*
G01X236417Y654075D02*
X234055D01*
G01Y652106D02*
X236417D01*
G01X239173Y650728D02*
X231299D01*
G01Y649154D02*
X239173D01*
G01X246063Y646201D02*
X224409D01*
G01X232677Y646161D02*
X237795D01*
G01X234055Y641476D02*
X236417D01*
G01X234055Y639783D02*
X236417D01*
G01X227756Y637815D02*
X242126D01*
G01X227756Y636437D02*
X231496D01*
G01X242126D02*
X238976D01*
G01X227756Y635571D02*
X242717D01*
G01X229528Y634075D02*
X237402D01*
G01X230709Y632894D02*
X236220D01*
G01X240728Y630256D02*
X239744D01*
G01X239746Y629764D02*
X245079D01*
G01Y629724D02*
X240731D01*
G01X245079Y628386D02*
X239746D01*
G01X239744Y627894D02*
X240728D01*
G01Y625256D02*
X239744D01*
G01X239746Y624764D02*
X245079D01*
G01Y624724D02*
X240731D01*
G01X245079Y623386D02*
X239746D01*
G01X239744Y622894D02*
X240728D01*
G01Y620256D02*
X239744D01*
G01X239746Y619764D02*
X245079D01*
G01Y619724D02*
X240731D01*
G01X245079Y618386D02*
X239746D01*
G01X239744Y617894D02*
X240728D01*
G01Y615256D02*
X239744D01*
G01X239746Y614764D02*
X245079D01*
G01Y614724D02*
X240731D01*
G01X245079Y613386D02*
X239746D01*
G01X239744Y612894D02*
X240728D01*
G01Y610256D02*
X239744D01*
G01Y629959D02*
X240699Y629961D01*
G01X240728Y628190D02*
X239744Y628189D01*
G01Y624959D02*
X240699Y624961D01*
G01X240728Y623190D02*
X239744Y623189D01*
G01Y619959D02*
X240699Y619961D01*
G01X240728Y618190D02*
X239744Y618189D01*
G01Y614959D02*
X240699Y614961D01*
G01X240728Y613190D02*
X239744Y613189D01*
G01Y609959D02*
X240699Y609961D01*
G01X239746Y609764D02*
X245079D01*
G01Y609724D02*
X240731D01*
G01X245079Y608386D02*
X239746D01*
G01X239744Y607894D02*
X240728D01*
G01Y605256D02*
X239744D01*
G01X239746Y604764D02*
X245079D01*
G01Y604724D02*
X240731D01*
G01X245079Y603386D02*
X239746D01*
G01X239744Y602894D02*
X240728D01*
G01Y600256D02*
X239744D01*
G01X239746Y599764D02*
X245079D01*
G01Y599724D02*
X240731D01*
G01X245079Y598386D02*
X239746D01*
G01X239744Y597894D02*
X240728D01*
G01Y595256D02*
X239744D01*
G01X239746Y594764D02*
X245079D01*
G01Y594724D02*
X240731D01*
G01X245079Y593386D02*
X239746D01*
G01X239744Y592894D02*
X240728D01*
G01Y590256D02*
X239744D01*
G01X239746Y589764D02*
X245079D01*
G01Y589724D02*
X240731D01*
G01X245079Y588386D02*
X239746D01*
G01X239744Y587894D02*
X240728D01*
G01Y585256D02*
X239744D01*
G01X239746Y584764D02*
X245079D01*
G01Y584724D02*
X240731D01*
G01X245079Y583386D02*
X239746D01*
G01X239744Y582894D02*
X240728D01*
G01Y580256D02*
X239744D01*
G01X239746Y579764D02*
X245079D01*
G01Y579724D02*
X240731D01*
G01X245079Y578386D02*
X239746D01*
G01X239744Y577894D02*
X240728D01*
G01Y575256D02*
X239744D01*
G01X239746Y574764D02*
X245079D01*
G01Y574724D02*
X240731D01*
G01X245079Y573386D02*
X239746D01*
G01X239744Y572894D02*
X240728D01*
G01Y608190D02*
X239744Y608189D01*
G01Y604959D02*
X240699Y604961D01*
G01X240728Y603190D02*
X239744Y603189D01*
G01Y599959D02*
X240699Y599961D01*
G01X240728Y598190D02*
X239744Y598189D01*
G01Y594959D02*
X240699Y594961D01*
G01X240728Y593190D02*
X239744Y593189D01*
G01Y589959D02*
X240699Y589961D01*
G01X240728Y588190D02*
X239744Y588189D01*
G01Y584959D02*
X240699Y584961D01*
G01X240728Y583190D02*
X239744Y583189D01*
G01Y579959D02*
X240699Y579961D01*
G01X240728Y578190D02*
X239744Y578189D01*
G01Y574959D02*
X240699Y574961D01*
G01X240728Y573190D02*
X239744Y573189D01*
G01X246063Y638917D02*
X242717Y635571D01*
G01X236220Y632894D02*
X237402Y634075D01*
G01X232752Y637815D02*
X234055Y639783D01*
G01X229528Y634075D02*
X230709Y632894D01*
G01X224409Y638917D02*
X227756Y635571D01*
G01X238728Y645706D02*
X236417Y641476D01*
G01X234055D02*
X231745Y645706D01*
G01X236417Y639783D02*
X237721Y637815D01*
G01X240728Y574738D02*
X240729Y574746D01*
G01X240728Y579738D02*
X240729Y579746D01*
G01X240728Y584738D02*
X240729Y584746D01*
G01X240728Y589738D02*
X240729Y589746D01*
G01X240728Y594738D02*
X240729Y594746D01*
G01X240728Y599738D02*
X240729Y599746D01*
G01X240728Y604738D02*
X240729Y604746D01*
G01X240728Y609738D02*
X240729Y609746D01*
G01X240728Y614738D02*
X240729Y614746D01*
G01X240728Y619738D02*
X240729Y619746D01*
G01X240728Y624738D02*
X240729Y624746D01*
G01X240728Y629738D02*
X240729Y629746D01*
G01X246063Y638917D02*
Y654665D01*
G01X245079Y628386D02*
Y629764D01*
G01Y623386D02*
Y624764D01*
G01Y618386D02*
Y619764D01*
G01Y613386D02*
Y614764D01*
G01Y608386D02*
Y609764D01*
G01Y603386D02*
Y604764D01*
G01Y598386D02*
Y599764D01*
G01Y593386D02*
Y594764D01*
G01Y588386D02*
Y589764D01*
G01Y583386D02*
Y584764D01*
G01Y578386D02*
Y579764D01*
G01Y573386D02*
Y574764D01*
G01X241909D02*
Y573386D01*
G01Y579764D02*
Y578386D01*
G01Y584764D02*
Y583386D01*
G01Y589764D02*
Y588386D01*
G01Y594764D02*
Y593386D01*
G01Y599764D02*
Y598386D01*
G01Y604764D02*
Y603386D01*
G01Y609764D02*
Y608386D01*
G01Y614764D02*
Y613386D01*
G01Y619764D02*
Y618386D01*
G01Y624764D02*
Y623386D01*
G01Y629764D02*
Y628386D01*
G01X240728Y627894D02*
Y630256D01*
G01Y622894D02*
Y625256D01*
G01Y617894D02*
Y620256D01*
G01Y612894D02*
Y615256D01*
G01Y607894D02*
Y610256D01*
G01Y602894D02*
Y605256D01*
G01Y597894D02*
Y600256D01*
G01Y592894D02*
Y595256D01*
G01Y587894D02*
Y590256D01*
G01Y582894D02*
Y585256D01*
G01Y577894D02*
Y580256D01*
G01Y572894D02*
Y575256D01*
G01X239744D02*
Y572894D01*
G01Y580256D02*
Y577894D01*
G01Y585256D02*
Y582894D01*
G01Y590256D02*
Y587894D01*
G01Y595256D02*
Y592894D01*
G01Y600256D02*
Y597894D01*
G01Y605256D02*
Y602894D01*
G01Y610256D02*
Y607894D01*
G01Y615256D02*
Y612894D01*
G01Y620256D02*
Y617894D01*
G01Y625256D02*
Y622894D01*
G01Y630256D02*
Y627894D01*
G01X239173Y649154D02*
Y655256D01*
G01X238976Y644980D02*
Y636437D01*
G01X236417Y641476D02*
Y639783D01*
G01X234055D02*
Y641476D01*
G01X231496Y636437D02*
Y644980D01*
G01X231299Y649154D02*
Y655256D01*
G01X224409Y654665D02*
Y638917D01*
G01X195276Y713386D02*
G03X196457I591J0D01*
G01Y707087D02*
G03X195276I-590J0D01*
G01Y713386D02*
G03X196457I591J0D01*
G01Y707087D02*
G03X195276I-590J0D01*
G01X197244Y713386D02*
X196457D01*
G01X197244D02*
X196457D01*
G01Y707087D02*
X197244D01*
G01X196457D02*
X197244D01*
G01D02*
Y713386D01*
G01Y707087D02*
Y713386D01*
G01X236339Y945020D02*
G03I-1103J0D01*
G01X237795Y939744D02*
G03X238976Y940925I0J1181D01*
G01X231496D02*
G03X232677Y939744I1181J0D01*
G01X236811Y945020D02*
G03I-1575J0D01*
G01X231299Y930650D02*
G03X231890Y930059I591J0D01*
G01X238583D02*
G03X239173Y930650I0J590D01*
G01X236417Y931831D02*
G03Y933799I0J984D01*
G01X234055D02*
G03Y931831I0J-984D01*
G01X224409Y931240D02*
G03X226378Y929272I1969J1D01*
G01X244094D02*
G03X246063Y931240I1J1968D01*
G01X237402Y951831D02*
X229528D01*
G01X242717Y950335D02*
X227756D01*
G01X238976Y949469D02*
X242126D01*
G01X231496D02*
X227756D01*
G01Y948091D02*
X242126D01*
G01X236417Y946122D02*
X234055D01*
G01X236417Y944429D02*
X234055D01*
G01X237795Y939744D02*
X232677D01*
G01X246063Y939705D02*
X224409D01*
G01X239173Y936752D02*
X231299D01*
G01Y935177D02*
X239173D01*
G01X236417Y933799D02*
X234055D01*
G01Y931831D02*
X236417D01*
G01X238583Y930059D02*
X231890D01*
G01X244094Y929272D02*
X226378D01*
G01X242717Y950335D02*
X246063Y946988D01*
G01X236220Y953012D02*
X237402Y951831D01*
G01X236417Y944429D02*
X238728Y940200D01*
G01X234055Y946122D02*
X232752Y948091D01*
G01X230709Y953012D02*
X229528Y951831D01*
G01X227756Y950335D02*
X224409Y946988D01*
G01X237721Y948091D02*
X236417Y946122D01*
G01X246063Y931240D02*
Y946988D01*
G01X242717Y1088327D02*
Y950335D01*
G01X242126Y1090571D02*
Y948091D01*
G01X239173Y936752D02*
Y930650D01*
G01X231745Y940200D02*
X234055Y944429D01*
G01X238976Y949469D02*
Y940925D01*
G01X237402Y988287D02*
Y951831D01*
G01X236417Y946122D02*
Y944429D01*
G01X234055D02*
Y946122D01*
G01X231496Y940925D02*
Y949469D01*
G01X231299Y936752D02*
Y930650D01*
G01X229528Y951831D02*
Y1086831D01*
G01X227756Y987126D02*
Y948091D01*
G01X224409Y946988D02*
Y931240D01*
G01X226319Y1001923D02*
Y1001916D01*
G01X226318Y1001928D02*
X226319Y1001923D01*
G01X226318Y1001918D02*
Y1001928D01*
G01X226359Y1009554D02*
X226358Y1009567D01*
G01X226356Y1009541D02*
X226359Y1009554D01*
G01X226356Y1009528D02*
Y1009541D01*
G01X226359Y1006405D02*
X226358Y1006417D01*
G01X226356Y1006392D02*
X226359Y1006405D01*
G01X226356Y1006378D02*
Y1006392D01*
G01X226359Y1003255D02*
X226358Y1003268D01*
G01X226356Y1003242D02*
X226359Y1003255D01*
G01X226356Y1003228D02*
Y1003242D01*
G01X226359Y1000106D02*
X226358Y1000118D01*
G01X226356Y1000093D02*
X226359Y1000106D01*
G01X226356Y1000079D02*
Y1000093D01*
G01X226359Y996956D02*
X226358Y996969D01*
G01X226356Y996943D02*
X226359Y996956D01*
G01X226356Y996929D02*
Y996943D01*
G01X226359Y993806D02*
X226358Y993819D01*
G01X226356Y993793D02*
X226359Y993806D01*
G01X226356Y993780D02*
Y993793D01*
G01X226359Y990657D02*
X226358Y990669D01*
G01X226356Y990644D02*
X226359Y990657D01*
G01X226356Y990630D02*
Y990644D01*
G01X239745Y1046140D02*
X239746Y1046142D01*
G01X239744Y1046134D02*
X239745Y1046140D01*
G01X239744Y1046126D02*
Y1046134D01*
G01X239745Y1041140D02*
X239746Y1041142D01*
G01X239744Y1041134D02*
X239745Y1041140D01*
G01X239744Y1041126D02*
Y1041134D01*
G01X239745Y1036140D02*
X239746Y1036142D01*
G01X239744Y1036134D02*
X239745Y1036140D01*
G01X239744Y1036126D02*
Y1036134D01*
G01X239745Y1031140D02*
X239746Y1031142D01*
G01X239744Y1031134D02*
X239745Y1031140D01*
G01X239744Y1031126D02*
Y1031134D01*
G01X239745Y1026140D02*
X239746Y1026142D01*
G01X239744Y1026134D02*
X239745Y1026140D01*
G01X239744Y1026126D02*
Y1026134D01*
G01X239745Y1021140D02*
X239746Y1021142D01*
G01X239744Y1021134D02*
X239745Y1021140D01*
G01X239744Y1021126D02*
Y1021134D01*
G01X239745Y1016140D02*
X239746Y1016142D01*
G01X239744Y1016134D02*
X239745Y1016140D01*
G01X239744Y1016126D02*
Y1016134D01*
G01X239745Y1011140D02*
X239746Y1011142D01*
G01X239744Y1011134D02*
X239745Y1011140D01*
G01X239744Y1011126D02*
Y1011134D01*
G01X239745Y986140D02*
X239746Y986142D01*
G01X239744Y986134D02*
X239745Y986140D01*
G01X239744Y986126D02*
Y986134D01*
G01X239745Y981140D02*
X239746Y981142D01*
G01X239744Y981134D02*
X239745Y981140D01*
G01X239744Y981126D02*
Y981134D01*
G01X239745Y976140D02*
X239746Y976142D01*
G01X239744Y976134D02*
X239745Y976140D01*
G01X239744Y976126D02*
Y976134D01*
G01X239745Y971140D02*
X239746Y971142D01*
G01X239744Y971134D02*
X239745Y971140D01*
G01X239744Y971126D02*
Y971134D01*
G01X239745Y966140D02*
X239746Y966142D01*
G01X239744Y966134D02*
X239745Y966140D01*
G01X239744Y966126D02*
Y966134D01*
G01X239745Y961140D02*
X239746Y961142D01*
G01X239744Y961134D02*
X239745Y961140D01*
G01X239744Y961126D02*
Y961134D01*
G01X239745Y956140D02*
X239746Y956142D01*
G01X239744Y956134D02*
X239745Y956140D01*
G01X239744Y956126D02*
Y956134D01*
G01X226319Y1008222D02*
Y1008215D01*
G01X226318Y1008227D02*
X226319Y1008222D01*
G01X226318Y1008219D02*
Y1008227D01*
G01X226356Y1008017D02*
X226355Y1008031D01*
G01X226359Y1008005D02*
X226356Y1008017D01*
G01X226358Y1007992D02*
X226359Y1008005D01*
G01X226356Y1004868D02*
X226355Y1004881D01*
G01X226359Y1004855D02*
X226356Y1004868D01*
G01X226358Y1004843D02*
X226359Y1004855D01*
G01X226356Y1001718D02*
X226355Y1001732D01*
G01X226359Y1001706D02*
X226356Y1001718D01*
G01X226358Y1001693D02*
X226359Y1001706D01*
G01X226356Y998569D02*
X226355Y998582D01*
G01X226359Y998556D02*
X226356Y998569D01*
G01X226358Y998543D02*
X226359Y998556D01*
G01X226356Y995419D02*
X226355Y995433D01*
G01X226359Y995406D02*
X226356Y995419D01*
G01X226358Y995394D02*
X226359Y995406D01*
G01X226356Y992269D02*
X226355Y992283D01*
G01X226359Y992257D02*
X226356Y992269D01*
G01X226358Y992244D02*
X226359Y992257D01*
G01X226356Y989120D02*
X226355Y989133D01*
G01X226359Y989107D02*
X226356Y989120D01*
G01X226358Y989094D02*
X226359Y989107D01*
G01X227266Y1009541D02*
X227267Y1009528D01*
G01X227263Y1009554D02*
X227266Y1009541D01*
G01X227264Y1009567D02*
X227263Y1009554D01*
G01X227266Y1006392D02*
X227267Y1006378D01*
G01X227263Y1006405D02*
X227266Y1006392D01*
G01X227264Y1006417D02*
X227263Y1006405D01*
G01X227266Y1003242D02*
X227267Y1003228D01*
G01X227263Y1003255D02*
X227266Y1003242D01*
G01X227264Y1003268D02*
X227263Y1003255D01*
G01X227266Y1000093D02*
X227267Y1000079D01*
G01X227263Y1000106D02*
X227266Y1000093D01*
G01X227264Y1000118D02*
X227263Y1000106D01*
G01X227266Y996943D02*
X227267Y996929D01*
G01X227263Y996956D02*
X227266Y996943D01*
G01X227264Y996969D02*
X227263Y996956D01*
G01X227266Y993793D02*
X227267Y993780D01*
G01X227263Y993806D02*
X227266Y993793D01*
G01X227264Y993819D02*
X227263Y993806D01*
G01X227266Y990644D02*
X227267Y990630D01*
G01X227263Y990657D02*
X227266Y990644D01*
G01X227264Y990669D02*
X227263Y990657D01*
G01X226319Y995624D02*
Y995617D01*
G01X226318Y995628D02*
X226319Y995624D01*
G01X226317Y995621D02*
X226318Y995628D01*
G01X226319Y1005073D02*
Y1005065D01*
G01X226318Y1005077D02*
X226319Y1005073D01*
G01X226317Y1005070D02*
X226318Y1005077D01*
G01X227263Y1008005D02*
X227264Y1007992D01*
G01X227266Y1008017D02*
X227263Y1008005D01*
G01X227267Y1008031D02*
X227266Y1008017D01*
G01X227263Y1004855D02*
X227264Y1004843D01*
G01X227266Y1004868D02*
X227263Y1004855D01*
G01X227267Y1004881D02*
X227266Y1004868D01*
G01X227263Y1001706D02*
X227264Y1001693D01*
G01X227266Y1001718D02*
X227263Y1001706D01*
G01X227267Y1001732D02*
X227266Y1001718D01*
G01X227263Y998556D02*
X227264Y998543D01*
G01X227266Y998569D02*
X227263Y998556D01*
G01X227267Y998582D02*
X227266Y998569D01*
G01X227263Y995406D02*
X227264Y995394D01*
G01X227266Y995419D02*
X227263Y995406D01*
G01X227267Y995433D02*
X227266Y995419D01*
G01X227263Y992257D02*
X227264Y992244D01*
G01X227266Y992269D02*
X227263Y992257D01*
G01X227267Y992283D02*
X227266Y992269D01*
G01X227263Y989107D02*
X227264Y989094D01*
G01X227266Y989120D02*
X227263Y989107D01*
G01X227267Y989133D02*
X227266Y989120D01*
G01X226319Y989325D02*
Y989317D01*
G01X226318Y989329D02*
X226319Y989325D01*
G01X226317Y989323D02*
X226318Y989329D01*
G01X226332Y1009361D02*
X226356Y1009370D01*
G01X226321Y1009347D02*
X226332Y1009361D01*
G01X226319Y1009340D02*
X226321Y1009347D01*
G01X226332Y1006212D02*
X226356Y1006220D01*
G01X226321Y1006197D02*
X226332Y1006212D01*
G01X226319Y1006191D02*
X226321Y1006197D01*
G01X226332Y1003062D02*
X226356Y1003071D01*
G01X226321Y1003048D02*
X226332Y1003062D01*
G01X226319Y1003041D02*
X226321Y1003048D01*
G01X226332Y999913D02*
X226356Y999921D01*
G01X226321Y999898D02*
X226332Y999913D01*
G01X226319Y999891D02*
X226321Y999898D01*
G01X226332Y996763D02*
X226356Y996772D01*
G01X226321Y996748D02*
X226332Y996763D01*
G01X226319Y996742D02*
X226321Y996748D01*
G01X226332Y993613D02*
X226356Y993622D01*
G01X226321Y993599D02*
X226332Y993613D01*
G01X226319Y993592D02*
X226321Y993599D01*
G01X226332Y990464D02*
X226356Y990472D01*
G01X226321Y990449D02*
X226332Y990464D01*
G01X226319Y990443D02*
X226321Y990449D01*
G01X227303Y1009337D02*
Y1009344D01*
G01Y1009332D02*
Y1009337D01*
G01X227302Y1009331D02*
X227303Y1009332D01*
G01Y1006187D02*
Y1006194D01*
G01Y1006183D02*
Y1006187D01*
G01X227302Y1006181D02*
X227303Y1006183D01*
G01Y1003038D02*
Y1003045D01*
G01Y1003033D02*
Y1003038D01*
G01X227302Y1003031D02*
X227303Y1003033D01*
G01Y999888D02*
Y999895D01*
G01Y999883D02*
Y999888D01*
G01X227302Y999882D02*
X227303Y999883D01*
G01Y996739D02*
Y996746D01*
G01Y996734D02*
Y996739D01*
G01X227302Y996732D02*
X227303Y996734D01*
G01Y993589D02*
Y993596D01*
G01Y993584D02*
Y993589D01*
G01X227302Y993583D02*
X227303Y993584D01*
G01Y990439D02*
Y990446D01*
G01Y990435D02*
Y990439D01*
G01X227302Y990433D02*
X227303Y990435D01*
G01X226319Y998774D02*
Y998766D01*
G01X226318Y998778D02*
X226319Y998774D01*
G01X226317Y998775D02*
X226318Y998778D01*
G01X226319Y992474D02*
Y992467D01*
G01X226318Y992479D02*
X226319Y992474D01*
G01X226317Y992477D02*
X226318Y992479D01*
G01X227264Y1009375D02*
Y1009381D01*
G01X227263Y1009371D02*
X227264Y1009375D01*
G01X227262Y1009370D02*
X227263Y1009371D01*
G01X227264Y1006226D02*
Y1006231D01*
G01X227263Y1006222D02*
X227264Y1006226D01*
G01X227262Y1006220D02*
X227263Y1006222D01*
G01X227264Y1003076D02*
Y1003082D01*
G01X227263Y1003072D02*
X227264Y1003076D01*
G01X227262Y1003071D02*
X227263Y1003072D01*
G01X227264Y999926D02*
Y999932D01*
G01X227263Y999922D02*
X227264Y999926D01*
G01X227262Y999921D02*
X227263Y999922D01*
G01X227264Y996777D02*
Y996783D01*
G01X227263Y996773D02*
X227264Y996777D01*
G01X227262Y996772D02*
X227263Y996773D01*
G01X227264Y993627D02*
Y993633D01*
G01X227263Y993623D02*
X227264Y993627D01*
G01X227262Y993622D02*
X227263Y993623D01*
G01X227264Y990478D02*
Y990483D01*
G01X227263Y990474D02*
X227264Y990478D01*
G01X227262Y990472D02*
X227263Y990474D01*
G01X240729Y1046134D02*
X240728Y1046125D01*
G01X240730Y1046140D02*
X240729Y1046134D01*
G01X240731Y1046142D02*
X240730Y1046140D01*
G01X240729Y1041134D02*
X240728Y1041125D01*
G01X240730Y1041140D02*
X240729Y1041134D01*
G01X240731Y1041142D02*
X240730Y1041140D01*
G01X240729Y1036134D02*
X240728Y1036125D01*
G01X240730Y1036140D02*
X240729Y1036134D01*
G01X240731Y1036142D02*
X240730Y1036140D01*
G01X240729Y1031134D02*
X240728Y1031125D01*
G01X240730Y1031140D02*
X240729Y1031134D01*
G01X240731Y1031142D02*
X240730Y1031140D01*
G01X240729Y1026134D02*
X240728Y1026125D01*
G01X240730Y1026140D02*
X240729Y1026134D01*
G01X240731Y1026142D02*
X240730Y1026140D01*
G01X240695Y957618D02*
X240699Y957717D01*
G01X240690Y957546D02*
X240695Y957618D01*
G01X240692Y957520D02*
X240690Y957546D01*
G01X240695Y962618D02*
X240699Y962717D01*
G01X240690Y962546D02*
X240695Y962618D01*
G01X240692Y962520D02*
X240690Y962546D01*
G01X240695Y967618D02*
X240699Y967717D01*
G01X240690Y967546D02*
X240695Y967618D01*
G01X240692Y967520D02*
X240690Y967546D01*
G01X240695Y972618D02*
X240699Y972717D01*
G01X240690Y972546D02*
X240695Y972618D01*
G01X240692Y972520D02*
X240690Y972546D01*
G01X240695Y977618D02*
X240699Y977717D01*
G01X240690Y977546D02*
X240695Y977618D01*
G01X240692Y977520D02*
X240690Y977546D01*
G01X240695Y982618D02*
X240699Y982717D01*
G01X240690Y982546D02*
X240695Y982618D01*
G01X240692Y982520D02*
X240690Y982546D01*
G01X240695Y987618D02*
X240699Y987717D01*
G01X240690Y987546D02*
X240695Y987618D01*
G01X240692Y987520D02*
X240690Y987546D01*
G01X240695Y1012618D02*
X240699Y1012717D01*
G01X240690Y1012546D02*
X240695Y1012618D01*
G01X240692Y1012520D02*
X240690Y1012546D01*
G01X240695Y1017618D02*
X240699Y1017717D01*
G01X240690Y1017546D02*
X240695Y1017618D01*
G01X240692Y1017520D02*
X240690Y1017546D01*
G01X240695Y1022618D02*
X240699Y1022717D01*
G01X240690Y1022546D02*
X240695Y1022618D01*
G01X240692Y1022520D02*
X240690Y1022546D01*
G01X240695Y1027618D02*
X240699Y1027717D01*
G01X240690Y1027546D02*
X240695Y1027618D01*
G01X240692Y1027520D02*
X240690Y1027546D01*
G01X240695Y1032618D02*
X240699Y1032717D01*
G01X240690Y1032546D02*
X240695Y1032618D01*
G01X240692Y1032520D02*
X240690Y1032546D01*
G01X240695Y1037618D02*
X240699Y1037717D01*
G01X240690Y1037546D02*
X240695Y1037618D01*
G01X240692Y1037520D02*
X240690Y1037546D01*
G01X240695Y1042618D02*
X240699Y1042717D01*
G01X240690Y1042546D02*
X240695Y1042618D01*
G01X240692Y1042520D02*
X240690Y1042546D01*
G01X240729Y1021134D02*
X240728Y1021125D01*
G01X240730Y1021140D02*
X240729Y1021134D01*
G01X240731Y1021142D02*
X240730Y1021140D01*
G01X240729Y1016134D02*
X240728Y1016125D01*
G01X240730Y1016140D02*
X240729Y1016134D01*
G01X240731Y1016142D02*
X240730Y1016140D01*
G01X240729Y1011134D02*
X240728Y1011125D01*
G01X240730Y1011140D02*
X240729Y1011134D01*
G01X240731Y1011142D02*
X240730Y1011140D01*
G01X240729Y986134D02*
X240728Y986125D01*
G01X240730Y986140D02*
X240729Y986134D01*
G01X240731Y986142D02*
X240730Y986140D01*
G01X240729Y981134D02*
X240728Y981125D01*
G01X240730Y981140D02*
X240729Y981134D01*
G01X240731Y981142D02*
X240730Y981140D01*
G01X240729Y976134D02*
X240728Y976125D01*
G01X240730Y976140D02*
X240729Y976134D01*
G01X240731Y976142D02*
X240730Y976140D01*
G01X240729Y971134D02*
X240728Y971125D01*
G01X240730Y971140D02*
X240729Y971134D01*
G01X240731Y971142D02*
X240730Y971140D01*
G01X240729Y966134D02*
X240728Y966125D01*
G01X240730Y966140D02*
X240729Y966134D01*
G01X240731Y966142D02*
X240730Y966140D01*
G01X240729Y961134D02*
X240728Y961125D01*
G01X240730Y961140D02*
X240729Y961134D01*
G01X240731Y961142D02*
X240730Y961140D01*
G01X240729Y956134D02*
X240728Y956125D01*
G01X240730Y956140D02*
X240729Y956134D01*
G01X240731Y956142D02*
X240730Y956140D01*
G01X226319Y1009337D02*
Y1009344D01*
G01X226318Y1009332D02*
X226319Y1009337D01*
G01X226317Y1009331D02*
X226318Y1009332D01*
G01X226319Y1006187D02*
Y1006194D01*
G01X226318Y1006183D02*
X226319Y1006187D01*
G01X226317Y1006181D02*
X226318Y1006183D01*
G01X226319Y1003037D02*
Y1003045D01*
G01X226318Y1003033D02*
X226319Y1003037D01*
G01X226317Y1003031D02*
X226318Y1003033D01*
G01X226319Y999888D02*
Y999895D01*
G01X226318Y999883D02*
X226319Y999888D01*
G01X226317Y999882D02*
X226318Y999883D01*
G01X226319Y996738D02*
Y996746D01*
G01X226318Y996734D02*
X226319Y996738D01*
G01X226317Y996732D02*
X226318Y996734D01*
G01X226319Y993589D02*
Y993596D01*
G01X226318Y993584D02*
X226319Y993589D01*
G01X226317Y993583D02*
X226318Y993584D01*
G01X226319Y990439D02*
Y990446D01*
G01X226318Y990435D02*
X226319Y990439D01*
G01X226317Y990433D02*
X226318Y990435D01*
G01X227301Y1008202D02*
X227303Y1008215D01*
G01X227294Y1008191D02*
X227301Y1008202D01*
G01X227284Y1008183D02*
X227294Y1008191D01*
G01X227301Y1001903D02*
X227303Y1001915D01*
G01X227294Y1001892D02*
X227301Y1001903D01*
G01X227284Y1001884D02*
X227294Y1001892D01*
G01X227301Y998754D02*
X227303Y998766D01*
G01X227294Y998742D02*
X227301Y998754D01*
G01X227284Y998734D02*
X227294Y998742D01*
G01X240711Y957515D02*
X240692Y957520D01*
G01X240726Y957500D02*
X240711Y957515D01*
G01X240731Y957480D02*
X240726Y957500D01*
G01X240711Y962515D02*
X240692Y962520D01*
G01X240726Y962500D02*
X240711Y962515D01*
G01X240731Y962480D02*
X240726Y962500D01*
G01X240711Y967515D02*
X240692Y967520D01*
G01X240726Y967500D02*
X240711Y967515D01*
G01X240731Y967480D02*
X240726Y967500D01*
G01X240711Y972515D02*
X240692Y972520D01*
G01X240726Y972500D02*
X240711Y972515D01*
G01X240731Y972480D02*
X240726Y972500D01*
G01X240711Y977515D02*
X240692Y977520D01*
G01X240726Y977500D02*
X240711Y977515D01*
G01X240731Y977480D02*
X240726Y977500D01*
G01X227296Y996754D02*
X227288Y996762D01*
G01X227300Y996743D02*
X227296Y996754D01*
G01X227302Y996732D02*
X227300Y996743D01*
G01X227296Y990454D02*
X227288Y990463D01*
G01X227300Y990444D02*
X227296Y990454D01*
G01X227302Y990433D02*
X227300Y990444D01*
G01X227296Y993604D02*
X227288Y993612D01*
G01X227300Y993594D02*
X227296Y993604D01*
G01X227302Y993583D02*
X227300Y993594D01*
G01X227296Y999903D02*
X227288Y999911D01*
G01X227300Y999893D02*
X227296Y999903D01*
G01X227302Y999882D02*
X227300Y999893D01*
G01X227296Y1003053D02*
X227288Y1003061D01*
G01X227300Y1003043D02*
X227296Y1003053D01*
G01X227302Y1003031D02*
X227300Y1003043D01*
G01X227296Y1006202D02*
X227288Y1006211D01*
G01X227300Y1006192D02*
X227296Y1006202D01*
G01X227302Y1006181D02*
X227300Y1006192D01*
G01X227296Y1009352D02*
X227288Y1009360D01*
G01X227300Y1009342D02*
X227296Y1009352D01*
G01X227302Y1009331D02*
X227300Y1009342D01*
G01X227301Y995604D02*
X227303Y995616D01*
G01X227294Y995593D02*
X227301Y995604D01*
G01X227284Y995585D02*
X227294Y995593D01*
G01X227301Y992454D02*
X227303Y992467D01*
G01X227294Y992443D02*
X227301Y992454D01*
G01X227284Y992435D02*
X227294Y992443D01*
G01X227301Y989305D02*
X227303Y989317D01*
G01X227294Y989293D02*
X227301Y989305D01*
G01X227284Y989285D02*
X227294Y989293D01*
G01X226357Y1009375D02*
Y1009381D01*
G01Y1009371D02*
Y1009375D01*
G01X226356Y1009370D02*
X226357Y1009371D01*
G01Y1006225D02*
Y1006231D01*
G01Y1006222D02*
Y1006225D01*
G01X226356Y1006220D02*
X226357Y1006222D01*
G01Y1003076D02*
Y1003082D01*
G01Y1003072D02*
Y1003076D01*
G01X226356Y1003071D02*
X226357Y1003072D01*
G01Y999926D02*
Y999932D01*
G01Y999922D02*
Y999926D01*
G01X226356Y999921D02*
X226357Y999922D01*
G01Y996776D02*
Y996783D01*
G01Y996773D02*
Y996776D01*
G01X226356Y996772D02*
X226357Y996773D01*
G01Y993627D02*
Y993633D01*
G01Y993623D02*
Y993627D01*
G01X226356Y993622D02*
X226357Y993623D01*
G01Y990477D02*
Y990483D01*
G01Y990474D02*
Y990477D01*
G01X226356Y990472D02*
X226357Y990474D01*
G01X226320Y1009350D02*
X226319Y1009344D01*
G01X226321Y1009357D02*
X226320Y1009350D01*
G01X226324Y1009363D02*
X226321Y1009357D01*
G01X226328Y1009368D02*
X226324Y1009363D01*
G01X226333Y1009372D02*
X226328Y1009368D01*
G01X226338Y1009376D02*
X226333Y1009372D01*
G01X226320Y1006201D02*
X226319Y1006194D01*
G01X226321Y1006207D02*
X226320Y1006201D01*
G01X226324Y1006213D02*
X226321Y1006207D01*
G01X226328Y1006218D02*
X226324Y1006213D01*
G01X226333Y1006223D02*
X226328Y1006218D01*
G01X226338Y1006226D02*
X226333Y1006223D01*
G01X226320Y1003051D02*
X226319Y1003045D01*
G01X226321Y1003057D02*
X226320Y1003051D01*
G01X226324Y1003063D02*
X226321Y1003057D01*
G01X226328Y1003069D02*
X226324Y1003063D01*
G01X226333Y1003073D02*
X226328Y1003069D01*
G01X226338Y1003077D02*
X226333Y1003073D01*
G01X226320Y999902D02*
X226319Y999895D01*
G01X226321Y999908D02*
X226320Y999902D01*
G01X226324Y999914D02*
X226321Y999908D01*
G01X226328Y999919D02*
X226324Y999914D01*
G01X226333Y999924D02*
X226328Y999919D01*
G01X226338Y999927D02*
X226333Y999924D01*
G01X226320Y996752D02*
X226319Y996746D01*
G01X226321Y996758D02*
X226320Y996752D01*
G01X226324Y996764D02*
X226321Y996758D01*
G01X226328Y996769D02*
X226324Y996764D01*
G01X226333Y996774D02*
X226328Y996769D01*
G01X226338Y996778D02*
X226333Y996774D01*
G01X226320Y993602D02*
X226319Y993596D01*
G01X226321Y993609D02*
X226320Y993602D01*
G01X226324Y993615D02*
X226321Y993609D01*
G01X226328Y993620D02*
X226324Y993615D01*
G01X226333Y993624D02*
X226328Y993620D01*
G01X226338Y993628D02*
X226333Y993624D01*
G01X226320Y990453D02*
X226319Y990446D01*
G01X226321Y990459D02*
X226320Y990453D01*
G01X226324Y990465D02*
X226321Y990459D01*
G01X226328Y990470D02*
X226324Y990465D01*
G01X226333Y990475D02*
X226328Y990470D01*
G01X226338Y990478D02*
X226333Y990475D01*
G01X227264Y989286D02*
X227265Y989280D01*
G01X227263Y989290D02*
X227264Y989286D01*
G01X227262Y989291D02*
X227263Y989290D01*
G01X227264Y992436D02*
X227265Y992430D01*
G01X227263Y992439D02*
X227264Y992436D01*
G01X227262Y992441D02*
X227263Y992439D01*
G01X227264Y995585D02*
X227265Y995579D01*
G01X227263Y995589D02*
X227264Y995585D01*
G01X227262Y995591D02*
X227263Y995589D01*
G01X227264Y998735D02*
X227265Y998729D01*
G01X227263Y998739D02*
X227264Y998735D01*
G01X227262Y998740D02*
X227263Y998739D01*
G01X227264Y1001885D02*
X227265Y1001878D01*
G01X227263Y1001888D02*
X227264Y1001885D01*
G01X227262Y1001890D02*
X227263Y1001888D01*
G01X227264Y1008184D02*
X227265Y1008178D01*
G01X227263Y1008187D02*
X227264Y1008184D01*
G01X227262Y1008189D02*
X227263Y1008187D01*
G01X239744Y957527D02*
Y957536D01*
G01X239745Y957521D02*
X239744Y957527D01*
G01X239746Y957520D02*
X239745Y957521D01*
G01X239744Y962527D02*
Y962536D01*
G01X239745Y962521D02*
X239744Y962527D01*
G01X239746Y962520D02*
X239745Y962521D01*
G01X239744Y967527D02*
Y967536D01*
G01X239745Y967521D02*
X239744Y967527D01*
G01X239746Y967520D02*
X239745Y967521D01*
G01X239744Y972527D02*
Y972536D01*
G01X239745Y972521D02*
X239744Y972527D01*
G01X239746Y972520D02*
X239745Y972521D01*
G01X239744Y977527D02*
Y977536D01*
G01X239745Y977521D02*
X239744Y977527D01*
G01X239746Y977520D02*
X239745Y977521D01*
G01X239744Y982527D02*
Y982536D01*
G01X239745Y982521D02*
X239744Y982527D01*
G01X239746Y982520D02*
X239745Y982521D01*
G01X239744Y987527D02*
Y987536D01*
G01X239745Y987521D02*
X239744Y987527D01*
G01X239746Y987520D02*
X239745Y987521D01*
G01X239744Y1012527D02*
Y1012536D01*
G01X239745Y1012521D02*
X239744Y1012527D01*
G01X239746Y1012520D02*
X239745Y1012521D01*
G01X240720Y957663D02*
X240728Y957637D01*
G01X240711Y957690D02*
X240720Y957663D01*
G01X240699Y957717D02*
X240711Y957690D01*
G01X240720Y962663D02*
X240728Y962637D01*
G01X240711Y962690D02*
X240720Y962663D01*
G01X240699Y962717D02*
X240711Y962690D01*
G01X240720Y967663D02*
X240728Y967637D01*
G01X240711Y967690D02*
X240720Y967663D01*
G01X240699Y967717D02*
X240711Y967690D01*
G01X240720Y972663D02*
X240728Y972637D01*
G01X240711Y972690D02*
X240720Y972663D01*
G01X240699Y972717D02*
X240711Y972690D01*
G01X240720Y977663D02*
X240728Y977637D01*
G01X240711Y977690D02*
X240720Y977663D01*
G01X240699Y977717D02*
X240711Y977690D01*
G01X240720Y982663D02*
X240728Y982637D01*
G01X240711Y982690D02*
X240720Y982663D01*
G01X240699Y982717D02*
X240711Y982690D01*
G01X240720Y987663D02*
X240728Y987637D01*
G01X240711Y987690D02*
X240720Y987663D01*
G01X240699Y987717D02*
X240711Y987690D01*
G01X240720Y1012663D02*
X240728Y1012637D01*
G01X240711Y1012690D02*
X240720Y1012663D01*
G01X240699Y1012717D02*
X240711Y1012690D01*
G01X240720Y1017663D02*
X240728Y1017637D01*
G01X240711Y1017690D02*
X240720Y1017663D01*
G01X240699Y1017717D02*
X240711Y1017690D01*
G01X240720Y1022663D02*
X240728Y1022637D01*
G01X240711Y1022690D02*
X240720Y1022663D01*
G01X240699Y1022717D02*
X240711Y1022690D01*
G01X226337Y998745D02*
X226356Y998740D01*
G01X226323Y998757D02*
X226337Y998745D01*
G01X226317Y998775D02*
X226323Y998757D01*
G01X240711Y982515D02*
X240692Y982520D01*
G01X240726Y982500D02*
X240711Y982515D01*
G01X240731Y982480D02*
X240726Y982500D01*
G01X240711Y987515D02*
X240692Y987520D01*
G01X240726Y987500D02*
X240711Y987515D01*
G01X240731Y987480D02*
X240726Y987500D01*
G01X240711Y1012515D02*
X240692Y1012520D01*
G01X240726Y1012500D02*
X240711Y1012515D01*
G01X240731Y1012480D02*
X240726Y1012500D01*
G01X240711Y1017515D02*
X240692Y1017520D01*
G01X240726Y1017500D02*
X240711Y1017515D01*
G01X240731Y1017480D02*
X240726Y1017500D01*
G01X240711Y1022515D02*
X240692Y1022520D01*
G01X240726Y1022500D02*
X240711Y1022515D01*
G01X240731Y1022480D02*
X240726Y1022500D01*
G01X240711Y1027515D02*
X240692Y1027520D01*
G01X240726Y1027500D02*
X240711Y1027515D01*
G01X240731Y1027480D02*
X240726Y1027500D01*
G01X240711Y1032515D02*
X240692Y1032520D01*
G01X240726Y1032500D02*
X240711Y1032515D01*
G01X240731Y1032480D02*
X240726Y1032500D01*
G01X240711Y1037515D02*
X240692Y1037520D01*
G01X240726Y1037500D02*
X240711Y1037515D01*
G01X240731Y1037480D02*
X240726Y1037500D01*
G01X240711Y1042515D02*
X240692Y1042520D01*
G01X240726Y1042500D02*
X240711Y1042515D01*
G01X240731Y1042480D02*
X240726Y1042500D01*
G01X240711Y1047515D02*
X240692Y1047520D01*
G01X240726Y1047500D02*
X240711Y1047515D01*
G01X240731Y1047480D02*
X240726Y1047500D01*
G01X227274Y1008191D02*
X227262Y1008189D01*
G01X227285Y1008196D02*
X227274Y1008191D01*
G01Y1005041D02*
X227262Y1005039D01*
G01X227285Y1005046D02*
X227274Y1005041D01*
G01Y1001892D02*
X227262Y1001890D01*
G01X227285Y1001896D02*
X227274Y1001892D01*
G01Y998742D02*
X227262Y998740D01*
G01X227285Y998747D02*
X227274Y998742D01*
G01Y995593D02*
X227262Y995591D01*
G01X227285Y995597D02*
X227274Y995593D01*
G01Y992443D02*
X227262Y992441D01*
G01X227285Y992448D02*
X227274Y992443D01*
G01Y989293D02*
X227262Y989291D01*
G01X227285Y989298D02*
X227274Y989293D01*
G01X226342Y992443D02*
X226356Y992441D01*
G01X226330Y992450D02*
X226342Y992443D01*
G01X226318Y992469D02*
X226330Y992450D01*
G01X226342Y1001892D02*
X226356Y1001890D01*
G01X226330Y1001900D02*
X226342Y1001892D01*
G01X226318Y1001918D02*
X226330Y1001900D01*
G01X226341Y995593D02*
X226356Y995591D01*
G01X226329Y995601D02*
X226341Y995593D01*
G01X226317Y995621D02*
X226329Y995601D01*
G01X226341Y1005042D02*
X226356Y1005039D01*
G01X226329Y1005050D02*
X226341Y1005042D01*
G01X226317Y1005070D02*
X226329Y1005050D01*
G01X227303Y989325D02*
Y989317D01*
G01X227302Y989329D02*
X227303Y989325D01*
G01X227302Y989331D02*
Y989329D01*
G01X227303Y992474D02*
Y992467D01*
G01X227302Y992479D02*
X227303Y992474D01*
G01X227302Y992480D02*
Y992479D01*
G01X227303Y995624D02*
Y995616D01*
G01X227302Y995628D02*
X227303Y995624D01*
G01X227302Y995630D02*
Y995628D01*
G01X227303Y998774D02*
Y998766D01*
G01X227302Y998778D02*
X227303Y998774D01*
G01X227302Y998780D02*
Y998778D01*
G01X227303Y1001923D02*
Y1001915D01*
G01X227302Y1001928D02*
X227303Y1001923D01*
G01X227302Y1001929D02*
Y1001928D01*
G01X227303Y1005073D02*
Y1005065D01*
G01X227302Y1005077D02*
X227303Y1005073D01*
G01X227302Y1005079D02*
Y1005077D01*
G01X227303Y1008222D02*
Y1008215D01*
G01X227302Y1008227D02*
X227303Y1008222D01*
G01X227302Y1008228D02*
Y1008227D01*
G01X226341Y1008192D02*
X226356Y1008189D01*
G01X226329Y1008200D02*
X226341Y1008192D01*
G01X226317Y1008220D02*
X226329Y1008200D01*
G01X226341Y989294D02*
X226356Y989291D01*
G01X226328Y989303D02*
X226341Y989294D01*
G01X226317Y989323D02*
X226328Y989303D01*
G01X227302Y990453D02*
X227303Y990446D01*
G01X227301Y990459D02*
X227302Y990453D01*
G01X227298Y990465D02*
X227301Y990459D01*
G01X227302Y993603D02*
X227303Y993596D01*
G01X227301Y993609D02*
X227302Y993603D01*
G01X227298Y993615D02*
X227301Y993609D01*
G01X227302Y996752D02*
X227303Y996746D01*
G01X227301Y996759D02*
X227302Y996752D01*
G01X227298Y996765D02*
X227301Y996759D01*
G01X227302Y999902D02*
X227303Y999895D01*
G01X227301Y999908D02*
X227302Y999902D01*
G01X227298Y999914D02*
X227301Y999908D01*
G01X227302Y1003052D02*
X227303Y1003045D01*
G01X227301Y1003058D02*
X227302Y1003052D01*
G01X227298Y1003064D02*
X227301Y1003058D01*
G01X227302Y1006201D02*
X227303Y1006194D01*
G01X227301Y1006207D02*
X227302Y1006201D01*
G01X227298Y1006213D02*
X227301Y1006207D01*
G01X227302Y1009351D02*
X227303Y1009344D01*
G01X227301Y1009357D02*
X227302Y1009351D01*
G01X227298Y1009363D02*
X227301Y1009357D01*
G01X239744Y1017527D02*
Y1017536D01*
G01X239745Y1017521D02*
X239744Y1017527D01*
G01X239746Y1017520D02*
X239745Y1017521D01*
G01X239744Y1022527D02*
Y1022536D01*
G01X239745Y1022521D02*
X239744Y1022527D01*
G01X239746Y1022520D02*
X239745Y1022521D01*
G01X239744Y1027527D02*
Y1027536D01*
G01X239745Y1027521D02*
X239744Y1027527D01*
G01X239746Y1027520D02*
X239745Y1027521D01*
G01X239744Y1032527D02*
Y1032536D01*
G01X239745Y1032521D02*
X239744Y1032527D01*
G01X239746Y1032520D02*
X239745Y1032521D01*
G01X239744Y1037527D02*
Y1037536D01*
G01X239745Y1037521D02*
X239744Y1037527D01*
G01X239746Y1037520D02*
X239745Y1037521D01*
G01X239744Y1042527D02*
Y1042536D01*
G01X239745Y1042521D02*
X239744Y1042527D01*
G01X239746Y1042520D02*
X239745Y1042521D01*
G01X239746Y1047520D02*
X239745Y1047521D01*
G01X240720Y1027663D02*
X240728Y1027637D01*
G01X240711Y1027690D02*
X240720Y1027663D01*
G01X240699Y1027717D02*
X240711Y1027690D01*
G01X240720Y1032663D02*
X240728Y1032637D01*
G01X240711Y1032690D02*
X240720Y1032663D01*
G01X240699Y1032717D02*
X240711Y1032690D01*
G01X240720Y1037663D02*
X240728Y1037637D01*
G01X240711Y1037690D02*
X240720Y1037663D01*
G01X240699Y1037717D02*
X240711Y1037690D01*
G01X240720Y1042663D02*
X240728Y1042637D01*
G01X240711Y1042690D02*
X240720Y1042663D01*
G01X240699Y1042717D02*
X240711Y1042690D01*
G01X240729Y957487D02*
X240728Y957494D01*
G01X240730Y957482D02*
X240729Y957487D01*
G01X240731Y957480D02*
X240730Y957482D01*
G01X240729Y962487D02*
X240728Y962494D01*
G01X240730Y962482D02*
X240729Y962487D01*
G01X240731Y962480D02*
X240730Y962482D01*
G01X240729Y967487D02*
X240728Y967494D01*
G01X240730Y967482D02*
X240729Y967487D01*
G01X240731Y967480D02*
X240730Y967482D01*
G01X240729Y972487D02*
X240728Y972494D01*
G01X240730Y972482D02*
X240729Y972487D01*
G01X240731Y972480D02*
X240730Y972482D01*
G01X240729Y977487D02*
X240728Y977494D01*
G01X240730Y977482D02*
X240729Y977487D01*
G01X240731Y977480D02*
X240730Y977482D01*
G01X240729Y982487D02*
X240728Y982494D01*
G01X240730Y982482D02*
X240729Y982487D01*
G01X240731Y982480D02*
X240730Y982482D01*
G01X240729Y987487D02*
X240728Y987494D01*
G01X240730Y987482D02*
X240729Y987487D01*
G01X240731Y987480D02*
X240730Y987482D01*
G01X240729Y1012487D02*
X240728Y1012494D01*
G01X240730Y1012482D02*
X240729Y1012487D01*
G01X240731Y1012480D02*
X240730Y1012482D01*
G01X240729Y1017487D02*
X240728Y1017494D01*
G01X240730Y1017482D02*
X240729Y1017487D01*
G01X240731Y1017480D02*
X240730Y1017482D01*
G01X240729Y1022487D02*
X240728Y1022494D01*
G01X240730Y1022482D02*
X240729Y1022487D01*
G01X240731Y1022480D02*
X240730Y1022482D01*
G01X240729Y1027487D02*
X240728Y1027494D01*
G01X240730Y1027482D02*
X240729Y1027487D01*
G01X240731Y1027480D02*
X240730Y1027482D01*
G01X240729Y1032487D02*
X240728Y1032494D01*
G01X240730Y1032482D02*
X240729Y1032487D01*
G01X240731Y1032480D02*
X240730Y1032482D01*
G01X240729Y1037487D02*
X240728Y1037494D01*
G01X240730Y1037482D02*
X240729Y1037487D01*
G01X240731Y1037480D02*
X240730Y1037482D01*
G01X240729Y1042487D02*
X240728Y1042494D01*
G01X240730Y1042482D02*
X240729Y1042487D01*
G01X240731Y1042480D02*
X240730Y1042482D01*
G01X240729Y1047487D02*
X240728Y1047494D01*
G01X240730Y1047482D02*
X240729Y1047487D01*
G01X240731Y1047480D02*
X240730Y1047482D01*
G01X226358Y989286D02*
Y989280D01*
G01X226357Y989290D02*
X226358Y989286D01*
G01X226356Y989291D02*
X226357Y989290D01*
G01X226358Y992436D02*
Y992430D01*
G01X226357Y992440D02*
X226358Y992436D01*
G01X226356Y992441D02*
X226357Y992440D01*
G01X226358Y995585D02*
Y995579D01*
G01X226357Y995589D02*
X226358Y995585D01*
G01X226356Y995591D02*
X226357Y995589D01*
G01X226358Y998735D02*
Y998729D01*
G01X226357Y998739D02*
X226358Y998735D01*
G01X226356Y998740D02*
X226357Y998739D01*
G01X226358Y1001885D02*
Y1001878D01*
G01X226357Y1001889D02*
X226358Y1001885D01*
G01X226356Y1001890D02*
X226357Y1001889D01*
G01X226358Y1005034D02*
Y1005028D01*
G01X226357Y1005038D02*
X226358Y1005034D01*
G01X226356Y1005039D02*
X226357Y1005038D01*
G01X226358Y1008184D02*
Y1008178D01*
G01X226357Y1008188D02*
X226358Y1008184D01*
G01X226356Y1008189D02*
X226357Y1008188D01*
G01X227272Y996770D02*
X227262Y996772D01*
G01X227280Y996767D02*
X227272Y996770D01*
G01X227288Y996762D02*
X227280Y996767D01*
G01X227272Y990471D02*
X227262Y990472D01*
G01X227281Y990468D02*
X227272Y990471D01*
G01X227288Y990463D02*
X227281Y990468D01*
G01X227272Y993621D02*
X227262Y993622D01*
G01X227281Y993618D02*
X227272Y993621D01*
G01X227288Y993612D02*
X227281Y993618D01*
G01X227272Y999920D02*
X227262Y999921D01*
G01X227281Y999917D02*
X227272Y999920D01*
G01X227288Y999911D02*
X227281Y999917D01*
G01X227272Y1003070D02*
X227262Y1003071D01*
G01X227281Y1003067D02*
X227272Y1003070D01*
G01X227288Y1003061D02*
X227281Y1003067D01*
G01X227272Y1006219D02*
X227262Y1006220D01*
G01X227281Y1006216D02*
X227272Y1006219D01*
G01X227288Y1006211D02*
X227281Y1006216D01*
G01X227272Y1009369D02*
X227262Y1009370D01*
G01X227281Y1009366D02*
X227272Y1009369D01*
G01X227288Y1009360D02*
X227281Y1009366D01*
G01X226319Y992470D02*
Y992467D01*
G01X226320Y992464D02*
X226319Y992470D01*
G01X226332Y992449D02*
X226320Y992464D01*
G01X226357Y992441D02*
X226332Y992449D01*
G01X226319Y995620D02*
Y995616D01*
G01X226320Y995614D02*
X226319Y995620D01*
G01X226332Y995599D02*
X226320Y995614D01*
G01X226356Y995591D02*
X226332Y995599D01*
G01X226319Y1001919D02*
Y1001915D01*
G01X226320Y1001913D02*
X226319Y1001919D01*
G01X226332Y1001898D02*
X226320Y1001913D01*
G01X226356Y1001890D02*
X226332Y1001898D01*
G01X226319Y1005069D02*
Y1005065D01*
G01X226320Y1005063D02*
X226319Y1005069D01*
G01X226332Y1005048D02*
X226320Y1005063D01*
G01X226356Y1005039D02*
X226332Y1005048D01*
G01X226319Y989321D02*
Y989317D01*
G01X226320Y989315D02*
X226319Y989321D01*
G01X226332Y989300D02*
X226320Y989315D01*
G01X226356Y989291D02*
X226332Y989300D01*
G01X226319Y1008219D02*
Y1008215D01*
G01X226320Y1008213D02*
X226319Y1008219D01*
G01X226332Y1008197D02*
X226320Y1008213D01*
G01X226356Y1008189D02*
X226332Y1008197D01*
G01X240716Y957511D02*
X240727Y957496D01*
G01X240691Y957520D02*
X240716Y957511D01*
G01Y962511D02*
X240727Y962496D01*
G01X240691Y962520D02*
X240716Y962511D01*
G01Y967511D02*
X240727Y967496D01*
G01X240691Y967520D02*
X240716Y967511D01*
G01Y972511D02*
X240727Y972496D01*
G01X240691Y972520D02*
X240716Y972511D01*
G01Y977511D02*
X240727Y977496D01*
G01X240691Y977520D02*
X240716Y977511D01*
G01Y982511D02*
X240727Y982496D01*
G01X240691Y982520D02*
X240716Y982511D01*
G01Y987511D02*
X240727Y987496D01*
G01X240691Y987520D02*
X240716Y987511D01*
G01Y1012511D02*
X240727Y1012496D01*
G01X240691Y1012520D02*
X240716Y1012511D01*
G01Y1017511D02*
X240727Y1017496D01*
G01X240691Y1017520D02*
X240716Y1017511D01*
G01Y1022511D02*
X240727Y1022496D01*
G01X240691Y1022520D02*
X240716Y1022511D01*
G01Y1027511D02*
X240727Y1027496D01*
G01X240691Y1027520D02*
X240716Y1027511D01*
G01X226319Y998770D02*
Y998766D01*
G01X226320Y998764D02*
X226319Y998770D01*
G01X226331Y998750D02*
X226320Y998764D01*
G01X226354Y998740D02*
X226331Y998750D01*
G01X240716Y1032511D02*
X240727Y1032496D01*
G01X240691Y1032520D02*
X240716Y1032511D01*
G01Y1037511D02*
X240727Y1037496D01*
G01X240691Y1037520D02*
X240716Y1037511D01*
G01Y1042511D02*
X240727Y1042496D01*
G01X240691Y1042520D02*
X240716Y1042511D01*
G01Y1047511D02*
X240727Y1047496D01*
G01X240691Y1047520D02*
X240716Y1047511D01*
G01X227294Y990471D02*
X227298Y990465D01*
G01X227289Y990475D02*
X227294Y990471D01*
G01X227283Y990479D02*
X227289Y990475D01*
G01X227277Y990481D02*
X227283Y990479D01*
G01X227270Y990483D02*
X227277Y990481D01*
G01X227264Y990483D02*
X227270D01*
G01X227294Y993620D02*
X227298Y993615D01*
G01X227289Y993625D02*
X227294Y993620D01*
G01X227283Y993628D02*
X227289Y993625D01*
G01X227277Y993631D02*
X227283Y993628D01*
G01X227270Y993633D02*
X227277Y993631D01*
G01X227264Y993633D02*
X227270D01*
G01X227294Y996770D02*
X227298Y996765D01*
G01X227289Y996774D02*
X227294Y996770D01*
G01X227283Y996778D02*
X227289Y996774D01*
G01X227277Y996781D02*
X227283Y996778D01*
G01X227270Y996782D02*
X227277Y996781D01*
G01X227264Y996783D02*
X227270Y996782D01*
G01X226320Y989310D02*
X226319Y989317D01*
G01X226322Y989303D02*
X226320Y989310D01*
G01X226326Y989296D02*
X226322Y989303D01*
G01X226330Y989291D02*
X226326Y989296D01*
G01X226337Y989286D02*
X226330Y989291D01*
G01X226343Y989283D02*
X226337Y989286D01*
G01X226351Y989281D02*
X226343Y989283D01*
G01X226358Y989280D02*
X226351Y989281D01*
G01X226320Y992459D02*
X226319Y992467D01*
G01X226322Y992452D02*
X226320Y992459D01*
G01X226326Y992446D02*
X226322Y992452D01*
G01X226330Y992441D02*
X226326Y992446D01*
G01X226337Y992436D02*
X226330Y992441D01*
G01X226343Y992432D02*
X226337Y992436D01*
G01X226351Y992430D02*
X226343Y992432D01*
G01X226358Y992430D02*
X226351D01*
G01X226320Y995609D02*
X226319Y995616D01*
G01X226322Y995602D02*
X226320Y995609D01*
G01X226326Y995596D02*
X226322Y995602D01*
G01X226330Y995590D02*
X226326Y995596D01*
G01X226337Y995585D02*
X226330Y995590D01*
G01X226343Y995582D02*
X226337Y995585D01*
G01X226351Y995580D02*
X226343Y995582D01*
G01X226358Y995579D02*
X226351Y995580D01*
G01X226320Y998759D02*
X226319Y998766D01*
G01X226322Y998752D02*
X226320Y998759D01*
G01X226326Y998745D02*
X226322Y998752D01*
G01X226330Y998740D02*
X226326Y998745D01*
G01X226337Y998735D02*
X226330Y998740D01*
G01X226343Y998731D02*
X226337Y998735D01*
G01X226351Y998730D02*
X226343Y998731D01*
G01X226358Y998729D02*
X226351Y998730D01*
G01X226320Y1001908D02*
X226319Y1001915D01*
G01X226322Y1001901D02*
X226320Y1001908D01*
G01X226326Y1001895D02*
X226322Y1001901D01*
G01X226330Y1001889D02*
X226326Y1001895D01*
G01X226337Y1001885D02*
X226330Y1001889D01*
G01X226343Y1001881D02*
X226337Y1001885D01*
G01X226351Y1001879D02*
X226343Y1001881D01*
G01X226358Y1001878D02*
X226351Y1001879D01*
G01X226320Y1005058D02*
X226319Y1005065D01*
G01X226322Y1005051D02*
X226320Y1005058D01*
G01X226326Y1005044D02*
X226322Y1005051D01*
G01X226330Y1005039D02*
X226326Y1005044D01*
G01X226337Y1005034D02*
X226330Y1005039D01*
G01X226343Y1005031D02*
X226337Y1005034D01*
G01X226351Y1005029D02*
X226343Y1005031D01*
G01X226358Y1005028D02*
X226351Y1005029D01*
G01X227273Y990471D02*
X227282Y990467D01*
G01X227262Y990472D02*
X227273Y990471D01*
G01Y993620D02*
X227282Y993617D01*
G01X227262Y993622D02*
X227273Y993620D01*
G01Y996770D02*
X227282Y996766D01*
G01X227262Y996772D02*
X227273Y996770D01*
G01Y999920D02*
X227282Y999916D01*
G01X227262Y999921D02*
X227273Y999920D01*
G01Y1003069D02*
X227282Y1003065D01*
G01X227262Y1003071D02*
X227273Y1003069D01*
G01Y1006219D02*
X227282Y1006215D01*
G01X227262Y1006220D02*
X227273Y1006219D01*
G01Y1009369D02*
X227282Y1009365D01*
G01X227262Y1009370D02*
X227273Y1009369D01*
G01X227281Y989283D02*
X227284Y989285D01*
G01X227278Y989282D02*
X227281Y989283D01*
G01X227274Y989281D02*
X227278Y989282D01*
G01X227271Y989281D02*
X227274D01*
G01X227267Y989280D02*
X227271Y989281D01*
G01X227264Y989280D02*
X227267D01*
G01X226341Y990480D02*
X226338Y990478D01*
G01X226344Y990481D02*
X226341Y990480D01*
G01X226348Y990482D02*
X226344Y990481D01*
G01X226351Y990483D02*
X226348Y990482D01*
G01X226355Y990483D02*
X226351D01*
G01X226358D02*
X226355D01*
G01X225572Y992480D02*
X225138D01*
G01X225945D02*
X225572D01*
G01Y998780D02*
X225138D01*
G01X225945D02*
X225572D01*
G01Y1001929D02*
X225138D01*
G01X225945D02*
X225572D01*
G01X227294Y999920D02*
X227298Y999914D01*
G01X227289Y999924D02*
X227294Y999920D01*
G01X227283Y999928D02*
X227289Y999924D01*
G01X227277Y999930D02*
X227283Y999928D01*
G01X227270Y999932D02*
X227277Y999930D01*
G01X227264Y999932D02*
X227270D01*
G01X227294Y1003069D02*
X227298Y1003064D01*
G01X227289Y1003074D02*
X227294Y1003069D01*
G01X227283Y1003077D02*
X227289Y1003074D01*
G01X227277Y1003080D02*
X227283Y1003077D01*
G01X227270Y1003081D02*
X227277Y1003080D01*
G01X227264Y1003082D02*
X227270Y1003081D01*
G01X227294Y1006219D02*
X227298Y1006213D01*
G01X227289Y1006223D02*
X227294Y1006219D01*
G01X227283Y1006227D02*
X227289Y1006223D01*
G01X227277Y1006230D02*
X227283Y1006227D01*
G01X227270Y1006231D02*
X227277Y1006230D01*
G01X227264Y1006231D02*
X227270D01*
G01X227294Y1009369D02*
X227298Y1009363D01*
G01X227289Y1009373D02*
X227294Y1009369D01*
G01X227283Y1009376D02*
X227289Y1009373D01*
G01X227277Y1009379D02*
X227283Y1009376D01*
G01X227270Y1009381D02*
X227277Y1009379D01*
G01X227264Y1009381D02*
X227270D01*
G01X226320Y1008207D02*
X226319Y1008215D01*
G01X226322Y1008200D02*
X226320Y1008207D01*
G01X226326Y1008194D02*
X226322Y1008200D01*
G01X226330Y1008189D02*
X226326Y1008194D01*
G01X226337Y1008184D02*
X226330Y1008189D01*
G01X226343Y1008180D02*
X226337Y1008184D01*
G01X226351Y1008178D02*
X226343Y1008180D01*
G01X226358Y1008178D02*
X226351D01*
G01X227302Y1005058D02*
X227303Y1005065D01*
G01X227300Y1005051D02*
X227302Y1005058D01*
G01X227296Y1005044D02*
X227300Y1005051D01*
G01X227292Y1005039D02*
X227296Y1005044D01*
G01X227285Y1005034D02*
X227292Y1005039D01*
G01X227279Y1005031D02*
X227285Y1005034D01*
G01X227272Y1005029D02*
X227279Y1005031D01*
G01X227264Y1005028D02*
X227272Y1005029D01*
G01X227281Y992433D02*
X227284Y992435D01*
G01X227278Y992432D02*
X227281Y992433D01*
G01X227274Y992431D02*
X227278Y992432D01*
G01X227271Y992430D02*
X227274Y992431D01*
G01X227267Y992430D02*
X227271D01*
G01X227264D02*
X227267D01*
G01X226341Y993630D02*
X226338Y993628D01*
G01X226344Y993631D02*
X226341Y993630D01*
G01X226348Y993632D02*
X226344Y993631D01*
G01X226351Y993633D02*
X226348Y993632D01*
G01X226355Y993633D02*
X226351D01*
G01X226358D02*
X226355D01*
G01X227281Y995583D02*
X227284Y995585D01*
G01X227278Y995581D02*
X227281Y995583D01*
G01X227274Y995581D02*
X227278D01*
G01X227271Y995580D02*
X227274Y995581D01*
G01X227267Y995580D02*
X227271D01*
G01X227264Y995579D02*
X227267Y995580D01*
G01X226341Y996779D02*
X226338Y996778D01*
G01X226344Y996780D02*
X226341Y996779D01*
G01X226348Y996781D02*
X226344Y996780D01*
G01X226351Y996782D02*
X226348Y996781D01*
G01X226355Y996783D02*
X226351Y996782D01*
G01X226358Y996783D02*
X226355D01*
G01X227281Y998732D02*
X227284Y998734D01*
G01X227278Y998731D02*
X227281Y998732D01*
G01X227274Y998730D02*
X227278Y998731D01*
G01X227271Y998730D02*
X227274D01*
G01X227267Y998729D02*
X227271Y998730D01*
G01X227264Y998729D02*
X227267D01*
G01X226341Y999929D02*
X226338Y999927D01*
G01X226344Y999930D02*
X226341Y999929D01*
G01X226348Y999931D02*
X226344Y999930D01*
G01X226351Y999932D02*
X226348Y999931D01*
G01X226355Y999932D02*
X226351D01*
G01X226358D02*
X226355D01*
G01X227281Y1001882D02*
X227284Y1001884D01*
G01X227278Y1001881D02*
X227281Y1001882D01*
G01X227274Y1001880D02*
X227278Y1001881D01*
G01X227271Y1001879D02*
X227274Y1001880D01*
G01X227267Y1001879D02*
X227271D01*
G01X227264Y1001878D02*
X227267Y1001879D01*
G01X226341Y1003078D02*
X226338Y1003077D01*
G01X226344Y1003080D02*
X226341Y1003078D01*
G01X226348Y1003081D02*
X226344Y1003080D01*
G01X226351Y1003081D02*
X226348D01*
G01X226355Y1003082D02*
X226351Y1003081D01*
G01X226358Y1003082D02*
X226355D01*
G01X226341Y1006228D02*
X226338Y1006226D01*
G01X226344Y1006229D02*
X226341Y1006228D01*
G01X226348Y1006230D02*
X226344Y1006229D01*
G01X226351Y1006231D02*
X226348Y1006230D01*
G01X226355Y1006231D02*
X226351D01*
G01X226358D02*
X226355D01*
G01X227281Y1008181D02*
X227284Y1008183D01*
G01X227278Y1008180D02*
X227281Y1008181D01*
G01X227274Y1008179D02*
X227278Y1008180D01*
G01X227271Y1008178D02*
X227274Y1008179D01*
G01X227267Y1008178D02*
X227271D01*
G01X227264D02*
X227267D01*
G01X226341Y1009378D02*
X226338Y1009376D01*
G01X226344Y1009379D02*
X226341Y1009378D01*
G01X226348Y1009380D02*
X226344Y1009379D01*
G01X226351Y1009381D02*
X226348Y1009380D01*
G01X226355Y1009381D02*
X226351D01*
G01X226358D02*
X226355D01*
G01X226322Y990453D02*
X226317Y990433D01*
G01X226336Y990467D02*
X226322Y990453D01*
G01X226356Y990472D02*
X226336Y990467D01*
G01X226322Y993602D02*
X226317Y993583D01*
G01X226336Y993617D02*
X226322Y993602D01*
G01X226356Y993622D02*
X226336Y993617D01*
G01X226322Y996752D02*
X226317Y996732D01*
G01X226336Y996766D02*
X226322Y996752D01*
G01X226356Y996772D02*
X226336Y996766D01*
G01X226322Y999902D02*
X226317Y999882D01*
G01X226336Y999916D02*
X226322Y999902D01*
G01X226356Y999921D02*
X226336Y999916D01*
G01X227296Y989311D02*
X227302Y989331D01*
G01X227282Y989296D02*
X227296Y989311D01*
G01X227262Y989291D02*
X227282Y989296D01*
G01X227296Y992461D02*
X227302Y992480D01*
G01X227282Y992446D02*
X227296Y992461D01*
G01X227262Y992441D02*
X227282Y992446D01*
G01X227296Y995610D02*
X227302Y995630D01*
G01X227282Y995596D02*
X227296Y995610D01*
G01X227262Y995591D02*
X227282Y995596D01*
G01X227296Y998760D02*
X227302Y998780D01*
G01X227282Y998745D02*
X227296Y998760D01*
G01X227262Y998740D02*
X227282Y998745D01*
G01X226322Y1003051D02*
X226317Y1003031D01*
G01X226336Y1003065D02*
X226322Y1003051D01*
G01X226356Y1003071D02*
X226336Y1003065D01*
G01X226322Y1006201D02*
X226317Y1006181D01*
G01X226336Y1006215D02*
X226322Y1006201D01*
G01X226356Y1006220D02*
X226336Y1006215D01*
G01X226322Y1009350D02*
X226317Y1009331D01*
G01X226336Y1009365D02*
X226322Y1009350D01*
G01X226356Y1009370D02*
X226336Y1009365D01*
G01X227296Y1001909D02*
X227302Y1001929D01*
G01X227282Y1001895D02*
X227296Y1001909D01*
G01X227262Y1001890D02*
X227282Y1001895D01*
G01X227296Y1005059D02*
X227302Y1005079D01*
G01X227282Y1005044D02*
X227296Y1005059D01*
G01X227262Y1005039D02*
X227282Y1005044D01*
G01X227296Y1008209D02*
X227302Y1008228D01*
G01X227282Y1008194D02*
X227296Y1008209D01*
G01X227262Y1008189D02*
X227282Y1008194D01*
G01X245079Y1046142D02*
X239746D01*
G01X239744Y1045650D02*
X240728D01*
G01Y1043012D02*
X239744D01*
G01X239746Y1042520D02*
X245079D01*
G01Y1042480D02*
X240731D01*
G01X245079Y1041142D02*
X239746D01*
G01X239744Y1040650D02*
X240728D01*
G01Y1038012D02*
X239744D01*
G01X239746Y1037520D02*
X245079D01*
G01Y1037480D02*
X240731D01*
G01X245079Y1036142D02*
X239746D01*
G01X239744Y1035650D02*
X240728D01*
G01Y1033012D02*
X239744D01*
G01X239746Y1032520D02*
X245079D01*
G01Y1032480D02*
X240731D01*
G01X245079Y1031142D02*
X239746D01*
G01X239744Y1030650D02*
X240728D01*
G01Y1028012D02*
X239744D01*
G01X239746Y1027520D02*
X245079D01*
G01Y1027480D02*
X240731D01*
G01X245079Y1026142D02*
X239746D01*
G01X239744Y1025650D02*
X240728D01*
G01Y1023012D02*
X239744D01*
G01X239746Y1022520D02*
X245079D01*
G01Y1022480D02*
X240731D01*
G01X245079Y1021142D02*
X239746D01*
G01X240728Y1045946D02*
X239744Y1045945D01*
G01Y1042715D02*
X240699Y1042717D01*
G01X240728Y1040946D02*
X239744Y1040945D01*
G01Y1037715D02*
X240699Y1037717D01*
G01X240728Y1035946D02*
X239744Y1035945D01*
G01Y1032715D02*
X240699Y1032717D01*
G01X240728Y1030946D02*
X239744Y1030945D01*
G01Y1027715D02*
X240699Y1027717D01*
G01X240728Y1025946D02*
X239744Y1025945D01*
G01Y1022715D02*
X240699Y1022717D01*
G01X240728Y1020946D02*
X239744Y1020945D01*
G01X226206Y1008228D02*
X226317Y1008220D01*
G01Y998775D02*
X226206Y998780D01*
G01X226317Y992477D02*
X226206Y992480D01*
G01X226317Y1001926D02*
X226206Y1001929D01*
G01X239744Y1020650D02*
X240728D01*
G01Y1018012D02*
X239744D01*
G01X239746Y1017520D02*
X245079D01*
G01Y1017480D02*
X240731D01*
G01X245079Y1016142D02*
X239746D01*
G01X239744Y1015650D02*
X240728D01*
G01Y1013012D02*
X239744D01*
G01X239746Y1012520D02*
X245079D01*
G01Y1012480D02*
X240731D01*
G01X227756Y1011535D02*
X224409D01*
G01X245079Y1011142D02*
X239746D01*
G01X239744Y1010650D02*
X240728D01*
G01X237402Y1010374D02*
X241339D01*
G01X227264Y1009567D02*
X226358D01*
G01X227303Y1009528D02*
X226319D01*
G01X227262Y1009370D02*
X221378D01*
G01Y1009331D02*
X227302D01*
G01X236220Y1009193D02*
X240157D01*
G01X227302Y1008228D02*
X221378D01*
G01X227262Y1008189D02*
X221378D01*
G01X226319Y1008031D02*
X227303D01*
G01X226358Y1007992D02*
X227264D01*
G01Y1006417D02*
X226358D01*
G01X227303Y1006378D02*
X226319D01*
G01X227262Y1006220D02*
X221378D01*
G01Y1006181D02*
X227302D01*
G01Y1005079D02*
X221378D01*
G01X227262Y1005039D02*
X221378D01*
G01X226319Y1004882D02*
X227303D01*
G01X226358Y1004843D02*
X227264D01*
G01Y1003268D02*
X226358D01*
G01X227303Y1003228D02*
X226319D01*
G01X227262Y1003071D02*
X221378D01*
G01Y1003031D02*
X227302D01*
G01Y1001929D02*
X221378D01*
G01X227262Y1001890D02*
X221378D01*
G01X226319Y1001732D02*
X227303D01*
G01X226358Y1001693D02*
X227264D01*
G01Y1000118D02*
X226358D01*
G01X227303Y1000079D02*
X226319D01*
G01X227262Y999921D02*
X221378D01*
G01Y999882D02*
X227302D01*
G01Y998780D02*
X221378D01*
G01X227262Y998740D02*
X221378D01*
G01X226319Y998583D02*
X227303D01*
G01X226358Y998543D02*
X227264D01*
G01Y996969D02*
X226358D01*
G01X227303Y996929D02*
X226319D01*
G01X227262Y996772D02*
X221378D01*
G01Y996732D02*
X227302D01*
G01Y995630D02*
X221378D01*
G01X227262Y995591D02*
X221378D01*
G01X226319Y995433D02*
X227303D01*
G01X226358Y995394D02*
X227264D01*
G01Y993819D02*
X226358D01*
G01X227303Y993780D02*
X226319D01*
G01X227262Y993622D02*
X221378D01*
G01Y993583D02*
X227302D01*
G01Y992480D02*
X221378D01*
G01X227262Y992441D02*
X221378D01*
G01X226319Y992283D02*
X227303D01*
G01X226358Y992244D02*
X227264D01*
G01Y990669D02*
X226358D01*
G01X227303Y990630D02*
X226319D01*
G01X227262Y990472D02*
X221378D01*
G01Y990433D02*
X227302D01*
G01X240157Y989469D02*
X236220D01*
G01X227302Y989331D02*
X221378D01*
G01X227262Y989291D02*
X221378D01*
G01X226319Y989134D02*
X227303D01*
G01X226358Y989094D02*
X227264D01*
G01X241339Y988287D02*
X237402D01*
G01X240728Y988012D02*
X239744D01*
G01X239746Y987520D02*
X245079D01*
G01Y987480D02*
X240731D01*
G01X227756Y987126D02*
X224409D01*
G01X245079Y986142D02*
X239746D01*
G01X239744Y985650D02*
X240728D01*
G01Y983012D02*
X239744D01*
G01X239746Y982520D02*
X245079D01*
G01Y982480D02*
X240731D01*
G01X245079Y981142D02*
X239746D01*
G01X239744Y980650D02*
X240728D01*
G01Y978012D02*
X239744D01*
G01X239746Y977520D02*
X245079D01*
G01Y977480D02*
X240731D01*
G01X245079Y976142D02*
X239746D01*
G01X239744Y975650D02*
X240728D01*
G01Y973012D02*
X239744D01*
G01X239746Y972520D02*
X245079D01*
G01Y972480D02*
X240731D01*
G01X245079Y971142D02*
X239746D01*
G01X239744Y970650D02*
X240728D01*
G01Y968012D02*
X239744D01*
G01X239746Y967520D02*
X245079D01*
G01Y967480D02*
X240731D01*
G01X245079Y966142D02*
X239746D01*
G01X239744Y965650D02*
X240728D01*
G01Y963012D02*
X239744D01*
G01X239746Y962520D02*
X245079D01*
G01Y962480D02*
X240731D01*
G01X245079Y961142D02*
X239746D01*
G01X239744Y960650D02*
X240728D01*
G01Y958012D02*
X239744D01*
G01X239746Y957520D02*
X245079D01*
G01Y957480D02*
X240731D01*
G01X245079Y956142D02*
X239746D01*
G01X239744Y955650D02*
X240728D01*
G01X236220Y953012D02*
X230709D01*
G01X239744Y1017715D02*
X240699Y1017717D01*
G01X240728Y1015946D02*
X239744Y1015945D01*
G01Y1012715D02*
X240699Y1012717D01*
G01X240728Y1010946D02*
X239744Y1010945D01*
G01Y987715D02*
X240699Y987717D01*
G01X240728Y985946D02*
X239744Y985945D01*
G01Y982715D02*
X240699Y982717D01*
G01X240728Y980946D02*
X239744Y980945D01*
G01Y977715D02*
X240699Y977717D01*
G01X240728Y975946D02*
X239744Y975945D01*
G01Y972715D02*
X240699Y972717D01*
G01X240728Y970946D02*
X239744Y970945D01*
G01Y967715D02*
X240699Y967717D01*
G01X240728Y965946D02*
X239744Y965945D01*
G01Y962715D02*
X240699Y962717D01*
G01X240728Y960946D02*
X239744Y960945D01*
G01Y957715D02*
X240699Y957717D01*
G01X240728Y955946D02*
X239744Y955945D01*
G01X240157Y989469D02*
X241339Y988287D01*
G01X236220Y989469D02*
X237402Y988287D01*
G01X227262Y1005039D02*
X227266Y1005028D01*
G01X240157Y1009193D02*
X241339Y1010374D01*
G01X236220Y1009193D02*
X237402Y1010374D01*
G01X245079Y1046142D02*
Y1047520D01*
G01Y1041142D02*
Y1042520D01*
G01Y1036142D02*
Y1037520D01*
G01Y1031142D02*
Y1032520D01*
G01Y1026142D02*
Y1027520D01*
G01Y1021142D02*
Y1022520D01*
G01Y1016142D02*
Y1017520D01*
G01Y1011142D02*
Y1012520D01*
G01Y986142D02*
Y987520D01*
G01Y981142D02*
Y982520D01*
G01Y976142D02*
Y977520D01*
G01Y971142D02*
Y972520D01*
G01Y966142D02*
Y967520D01*
G01Y961142D02*
Y962520D01*
G01Y956142D02*
Y957520D01*
G01X241909D02*
Y956142D01*
G01Y962520D02*
Y961142D01*
G01Y967520D02*
Y966142D01*
G01Y972520D02*
Y971142D01*
G01Y977520D02*
Y976142D01*
G01Y982520D02*
Y981142D01*
G01Y987520D02*
Y986142D01*
G01Y1012520D02*
Y1011142D01*
G01Y1017520D02*
Y1016142D01*
G01Y1022520D02*
Y1021142D01*
G01Y1027520D02*
Y1026142D01*
G01Y1032520D02*
Y1031142D01*
G01Y1037520D02*
Y1036142D01*
G01Y1042520D02*
Y1041142D01*
G01Y1047520D02*
Y1046142D01*
G01X241339Y1010374D02*
Y988287D01*
G01X240728Y1045650D02*
Y1048012D01*
G01Y1040650D02*
Y1043012D01*
G01Y1035650D02*
Y1038012D01*
G01Y1030650D02*
Y1033012D01*
G01Y1025650D02*
Y1028012D01*
G01Y1020650D02*
Y1023012D01*
G01Y1015650D02*
Y1018012D01*
G01Y1010650D02*
Y1013012D01*
G01Y985650D02*
Y988012D01*
G01Y980650D02*
Y983012D01*
G01Y975650D02*
Y978012D01*
G01Y970650D02*
Y973012D01*
G01Y965650D02*
Y968012D01*
G01Y960650D02*
Y963012D01*
G01Y955650D02*
Y958012D01*
G01Y967494D02*
Y967637D01*
G01Y962494D02*
Y962637D01*
G01Y977494D02*
Y977637D01*
G01Y972494D02*
Y972637D01*
G01Y987494D02*
Y987637D01*
G01Y982494D02*
Y982637D01*
G01Y1017494D02*
Y1017637D01*
G01Y1012494D02*
Y1012637D01*
G01Y1027494D02*
Y1027637D01*
G01Y1022494D02*
Y1022637D01*
G01Y1037494D02*
Y1037637D01*
G01Y1032494D02*
Y1032637D01*
G01Y1042494D02*
Y1042637D01*
G01X240157Y1009193D02*
Y989469D01*
G01X239744Y958012D02*
Y955650D01*
G01Y963012D02*
Y960650D01*
G01Y968012D02*
Y965650D01*
G01Y973012D02*
Y970650D01*
G01Y978012D02*
Y975650D01*
G01Y983012D02*
Y980650D01*
G01Y988012D02*
Y985650D01*
G01Y1013012D02*
Y1010650D01*
G01Y1018012D02*
Y1015650D01*
G01Y1023012D02*
Y1020650D01*
G01Y1028012D02*
Y1025650D01*
G01Y1033012D02*
Y1030650D01*
G01Y1038012D02*
Y1035650D01*
G01Y1043012D02*
Y1040650D01*
G01Y1048012D02*
Y1045650D01*
G01X227303Y990435D02*
Y990446D01*
G01Y993585D02*
Y993596D01*
G01Y996734D02*
Y996746D01*
G01Y999884D02*
Y999895D01*
G01Y1003033D02*
Y1003045D01*
G01Y1006183D02*
Y1006194D01*
G01Y1009333D02*
Y1009344D01*
G01X240728Y957494D02*
X240729Y957502D01*
G01X240728Y962494D02*
X240729Y962502D01*
G01X240728Y967494D02*
X240729Y967502D01*
G01X240728Y972494D02*
X240729Y972502D01*
G01X240728Y977494D02*
X240729Y977502D01*
G01X240728Y982494D02*
X240729Y982502D01*
G01X240728Y987494D02*
X240729Y987502D01*
G01X240728Y1012494D02*
X240729Y1012502D01*
G01X240728Y1017494D02*
X240729Y1017502D01*
G01X240728Y1022494D02*
X240729Y1022502D01*
G01X240728Y1027494D02*
X240729Y1027502D01*
G01X240728Y1032494D02*
X240729Y1032502D01*
G01X240728Y1037494D02*
X240729Y1037502D01*
G01X240728Y1042494D02*
X240729Y1042502D01*
G01X237402Y1086831D02*
Y1010374D01*
G01X236220Y989469D02*
Y953012D01*
G01Y1085650D02*
Y1009193D01*
G01X230709Y953012D02*
Y1085650D01*
G01X227756Y1090571D02*
Y1011535D01*
G01X227303Y1008031D02*
Y1009528D01*
G01Y1004881D02*
Y1006378D01*
G01Y1001732D02*
Y1003228D01*
G01Y998582D02*
Y1000079D01*
G01Y995433D02*
Y996929D01*
G01Y992283D02*
Y993780D01*
G01Y989133D02*
Y990630D01*
G01X227264Y989280D02*
Y989133D01*
G01Y990630D02*
Y990483D01*
G01Y995579D02*
Y995432D01*
G01Y992430D02*
Y992283D01*
G01Y993780D02*
Y993633D01*
G01Y998729D02*
Y998582D01*
G01Y1000079D02*
Y999932D01*
G01Y996930D02*
Y996783D01*
G01Y1001878D02*
Y1001731D01*
G01Y1003229D02*
Y1003082D01*
G01Y1008178D02*
Y1008031D01*
G01Y1009528D02*
Y1009381D01*
G01Y1005028D02*
Y1004881D01*
G01Y1006378D02*
Y1006231D01*
G01X226358Y1008031D02*
Y1008178D01*
G01Y1009381D02*
Y1009528D01*
G01Y1004881D02*
Y1005028D01*
G01Y1006231D02*
Y1006378D01*
G01Y1001731D02*
Y1001878D01*
G01Y1003082D02*
Y1003229D01*
G01Y998582D02*
Y998729D01*
G01Y999932D02*
Y1000079D01*
G01Y996783D02*
Y996930D01*
G01Y995432D02*
Y995579D01*
G01Y992283D02*
Y992430D01*
G01Y993633D02*
Y993780D01*
G01Y989133D02*
Y989280D01*
G01Y990483D02*
Y990630D01*
G01X226319D02*
Y989134D01*
G01Y993780D02*
Y992283D01*
G01Y1000079D02*
Y998583D01*
G01Y996929D02*
Y995433D01*
G01Y1003228D02*
Y1001732D01*
G01Y1009528D02*
Y1008031D01*
G01Y1006378D02*
Y1004882D01*
G01X225138Y990472D02*
Y989291D01*
G01Y996772D02*
Y995591D01*
G01Y993622D02*
Y992441D01*
G01Y999921D02*
Y998740D01*
G01Y1003071D02*
Y1001890D01*
G01Y1009370D02*
Y1008189D01*
G01Y1006220D02*
Y1005039D01*
G01X224803Y1011535D02*
Y987126D01*
G01X224409D02*
Y1011535D01*
G01X221378Y1008189D02*
Y1009370D01*
G01Y1005039D02*
Y1006220D01*
G01Y1001890D02*
Y1003071D01*
G01Y998740D02*
Y999921D01*
G01Y995591D02*
Y996772D01*
G01Y992441D02*
Y993622D01*
G01Y989291D02*
Y990472D01*
G01X227303Y1008215D02*
Y1008226D01*
G01Y1005065D02*
Y1005076D01*
G01Y1001916D02*
Y1001926D01*
G01Y998766D02*
Y998777D01*
G01Y995617D02*
Y995627D01*
G01Y992467D02*
Y992478D01*
G01Y989317D02*
Y989328D01*
G01X239745Y1081140D02*
X239746Y1081142D01*
G01X239744Y1081134D02*
X239745Y1081140D01*
G01X239744Y1081126D02*
Y1081134D01*
G01X239745Y1076140D02*
X239746Y1076142D01*
G01X239744Y1076134D02*
X239745Y1076140D01*
G01X239744Y1076126D02*
Y1076134D01*
G01X239745Y1071140D02*
X239746Y1071142D01*
G01X239744Y1071134D02*
X239745Y1071140D01*
G01X239744Y1071126D02*
Y1071134D01*
G01X239745Y1066140D02*
X239746Y1066142D01*
G01X239744Y1066134D02*
X239745Y1066140D01*
G01X239744Y1066126D02*
Y1066134D01*
G01X239745Y1061140D02*
X239746Y1061142D01*
G01X239744Y1061134D02*
X239745Y1061140D01*
G01X239744Y1061126D02*
Y1061134D01*
G01X239745Y1056140D02*
X239746Y1056142D01*
G01X239744Y1056134D02*
X239745Y1056140D01*
G01X239744Y1056126D02*
Y1056134D01*
G01X239745Y1051140D02*
X239746Y1051142D01*
G01X239744Y1051134D02*
X239745Y1051140D01*
G01X239744Y1051126D02*
Y1051134D01*
G01X240729Y1081134D02*
X240728Y1081125D01*
G01X240730Y1081140D02*
X240729Y1081134D01*
G01X240731Y1081142D02*
X240730Y1081140D01*
G01X240729Y1076134D02*
X240728Y1076125D01*
G01X240730Y1076140D02*
X240729Y1076134D01*
G01X240731Y1076142D02*
X240730Y1076140D01*
G01X240729Y1071134D02*
X240728Y1071125D01*
G01X240730Y1071140D02*
X240729Y1071134D01*
G01X240731Y1071142D02*
X240730Y1071140D01*
G01X240729Y1066134D02*
X240728Y1066125D01*
G01X240730Y1066140D02*
X240729Y1066134D01*
G01X240731Y1066142D02*
X240730Y1066140D01*
G01X240729Y1061134D02*
X240728Y1061125D01*
G01X240730Y1061140D02*
X240729Y1061134D01*
G01X240731Y1061142D02*
X240730Y1061140D01*
G01X240729Y1056134D02*
X240728Y1056125D01*
G01X240730Y1056140D02*
X240729Y1056134D01*
G01X240731Y1056142D02*
X240730Y1056140D01*
G01X240729Y1051134D02*
X240728Y1051125D01*
G01X240730Y1051140D02*
X240729Y1051134D01*
G01X240731Y1051142D02*
X240730Y1051140D01*
G01X240695Y1047618D02*
X240699Y1047717D01*
G01X240690Y1047546D02*
X240695Y1047618D01*
G01X240692Y1047520D02*
X240690Y1047546D01*
G01X240695Y1052618D02*
X240699Y1052717D01*
G01X240690Y1052546D02*
X240695Y1052618D01*
G01X240692Y1052520D02*
X240690Y1052546D01*
G01X240695Y1057618D02*
X240699Y1057717D01*
G01X240690Y1057546D02*
X240695Y1057618D01*
G01X240692Y1057520D02*
X240690Y1057546D01*
G01X240695Y1062618D02*
X240699Y1062717D01*
G01X240690Y1062546D02*
X240695Y1062618D01*
G01X240692Y1062520D02*
X240690Y1062546D01*
G01X240695Y1067618D02*
X240699Y1067717D01*
G01X240690Y1067546D02*
X240695Y1067618D01*
G01X240692Y1067520D02*
X240690Y1067546D01*
G01X240695Y1072618D02*
X240699Y1072717D01*
G01X240690Y1072546D02*
X240695Y1072618D01*
G01X240692Y1072520D02*
X240690Y1072546D01*
G01X240695Y1077618D02*
X240699Y1077717D01*
G01X240690Y1077546D02*
X240695Y1077618D01*
G01X240692Y1077520D02*
X240690Y1077546D01*
G01X240695Y1082618D02*
X240699Y1082717D01*
G01X240690Y1082546D02*
X240695Y1082618D01*
G01X240692Y1082520D02*
X240690Y1082546D01*
G01X240711Y1052515D02*
X240692Y1052520D01*
G01X240726Y1052500D02*
X240711Y1052515D01*
G01X240731Y1052480D02*
X240726Y1052500D01*
G01X240711Y1057515D02*
X240692Y1057520D01*
G01X240726Y1057500D02*
X240711Y1057515D01*
G01X240731Y1057480D02*
X240726Y1057500D01*
G01X240711Y1062515D02*
X240692Y1062520D01*
G01X240726Y1062500D02*
X240711Y1062515D01*
G01X240731Y1062480D02*
X240726Y1062500D01*
G01X240711Y1067515D02*
X240692Y1067520D01*
G01X240726Y1067500D02*
X240711Y1067515D01*
G01X240731Y1067480D02*
X240726Y1067500D01*
G01X240711Y1072515D02*
X240692Y1072520D01*
G01X240726Y1072500D02*
X240711Y1072515D01*
G01X240731Y1072480D02*
X240726Y1072500D01*
G01X240711Y1077515D02*
X240692Y1077520D01*
G01X240726Y1077500D02*
X240711Y1077515D01*
G01X240731Y1077480D02*
X240726Y1077500D01*
G01X240711Y1082515D02*
X240692Y1082520D01*
G01X240726Y1082500D02*
X240711Y1082515D01*
G01X240731Y1082480D02*
X240726Y1082500D01*
G01X239744Y1047527D02*
Y1047536D01*
G01X239745Y1047521D02*
X239744Y1047527D01*
G01Y1052527D02*
Y1052536D01*
G01X239745Y1052521D02*
X239744Y1052527D01*
G01X239746Y1052520D02*
X239745Y1052521D01*
G01X239744Y1057527D02*
Y1057536D01*
G01X239745Y1057521D02*
X239744Y1057527D01*
G01X239746Y1057520D02*
X239745Y1057521D01*
G01X239744Y1062527D02*
Y1062536D01*
G01X239745Y1062521D02*
X239744Y1062527D01*
G01X239746Y1062520D02*
X239745Y1062521D01*
G01X239744Y1067527D02*
Y1067536D01*
G01X239745Y1067521D02*
X239744Y1067527D01*
G01X239746Y1067520D02*
X239745Y1067521D01*
G01X239744Y1072527D02*
Y1072536D01*
G01X239745Y1072521D02*
X239744Y1072527D01*
G01X239746Y1072520D02*
X239745Y1072521D01*
G01X239744Y1077527D02*
Y1077536D01*
G01X239745Y1077521D02*
X239744Y1077527D01*
G01X239746Y1077520D02*
X239745Y1077521D01*
G01X239744Y1082527D02*
Y1082536D01*
G01X239745Y1082521D02*
X239744Y1082527D01*
G01X239746Y1082520D02*
X239745Y1082521D01*
G01X240720Y1047663D02*
X240728Y1047637D01*
G01X240711Y1047690D02*
X240720Y1047663D01*
G01X240699Y1047717D02*
X240711Y1047690D01*
G01X240720Y1052663D02*
X240728Y1052637D01*
G01X240711Y1052690D02*
X240720Y1052663D01*
G01X240699Y1052717D02*
X240711Y1052690D01*
G01X240720Y1057663D02*
X240728Y1057637D01*
G01X240711Y1057690D02*
X240720Y1057663D01*
G01X240699Y1057717D02*
X240711Y1057690D01*
G01X240720Y1062663D02*
X240728Y1062637D01*
G01X240711Y1062690D02*
X240720Y1062663D01*
G01X240699Y1062717D02*
X240711Y1062690D01*
G01X240720Y1067663D02*
X240728Y1067637D01*
G01X240711Y1067690D02*
X240720Y1067663D01*
G01X240699Y1067717D02*
X240711Y1067690D01*
G01X240720Y1072663D02*
X240728Y1072637D01*
G01X240711Y1072690D02*
X240720Y1072663D01*
G01X240699Y1072717D02*
X240711Y1072690D01*
G01X240720Y1077663D02*
X240728Y1077637D01*
G01X240711Y1077690D02*
X240720Y1077663D01*
G01X240699Y1077717D02*
X240711Y1077690D01*
G01X240720Y1082663D02*
X240728Y1082637D01*
G01X240711Y1082690D02*
X240720Y1082663D01*
G01X240699Y1082717D02*
X240711Y1082690D01*
G01X240729Y1052487D02*
X240728Y1052494D01*
G01X240730Y1052482D02*
X240729Y1052487D01*
G01X240731Y1052480D02*
X240730Y1052482D01*
G01X240729Y1057487D02*
X240728Y1057494D01*
G01X240730Y1057482D02*
X240729Y1057487D01*
G01X240731Y1057480D02*
X240730Y1057482D01*
G01X240729Y1062487D02*
X240728Y1062494D01*
G01X240730Y1062482D02*
X240729Y1062487D01*
G01X240731Y1062480D02*
X240730Y1062482D01*
G01X240729Y1067487D02*
X240728Y1067494D01*
G01X240730Y1067482D02*
X240729Y1067487D01*
G01X240731Y1067480D02*
X240730Y1067482D01*
G01X240729Y1072487D02*
X240728Y1072494D01*
G01X240730Y1072482D02*
X240729Y1072487D01*
G01X240731Y1072480D02*
X240730Y1072482D01*
G01X240729Y1077487D02*
X240728Y1077494D01*
G01X240730Y1077482D02*
X240729Y1077487D01*
G01X240731Y1077480D02*
X240730Y1077482D01*
G01X240729Y1082487D02*
X240728Y1082494D01*
G01X240730Y1082482D02*
X240729Y1082487D01*
G01X240731Y1082480D02*
X240730Y1082482D01*
G01X240716Y1052511D02*
X240727Y1052496D01*
G01X240691Y1052520D02*
X240716Y1052511D01*
G01Y1057511D02*
X240727Y1057496D01*
G01X240691Y1057520D02*
X240716Y1057511D01*
G01Y1062511D02*
X240727Y1062496D01*
G01X240691Y1062520D02*
X240716Y1062511D01*
G01Y1067511D02*
X240727Y1067496D01*
G01X240691Y1067520D02*
X240716Y1067511D01*
G01Y1072511D02*
X240727Y1072496D01*
G01X240691Y1072520D02*
X240716Y1072511D01*
G01Y1077511D02*
X240727Y1077496D01*
G01X240691Y1077520D02*
X240716Y1077511D01*
G01Y1082511D02*
X240727Y1082496D01*
G01X240691Y1082520D02*
X240716Y1082511D01*
G01X239173Y1108012D02*
G03X238583Y1108602I-590J0D01*
G01X231890D02*
G03X231299Y1108012I0J-591D01*
G01X234055Y1106831D02*
G03Y1104862I0J-985D01*
G01X236417D02*
G03Y1106831I0J984D01*
G01X232677Y1098917D02*
G03X231496Y1097736I0J-1181D01*
G01X238976D02*
G03X237795Y1098917I-1181J0D01*
G01X237126Y1093642D02*
G03I-1890J0D01*
G01X246063Y1107421D02*
G03X244094Y1109390I-1969J0D01*
G01X226378D02*
G03X224409Y1107421I0J-1969D01*
G01X237598Y1093642D02*
G03I-2362J0D01*
G01X244094Y1109390D02*
X226378D01*
G01X238583Y1108602D02*
X231890D01*
G01X236417Y1106831D02*
X234055D01*
G01Y1104862D02*
X236417D01*
G01X239173Y1103484D02*
X231299D01*
G01Y1101909D02*
X239173D01*
G01X246063Y1098957D02*
X224409D01*
G01X232677Y1098917D02*
X237795D01*
G01X234055Y1094232D02*
X236417D01*
G01X234055Y1092539D02*
X236417D01*
G01X227756Y1090571D02*
X242126D01*
G01X227756Y1089193D02*
X231496D01*
G01X242126D02*
X238976D01*
G01X227756Y1088327D02*
X242717D01*
G01X229528Y1086831D02*
X237402D01*
G01X230709Y1085650D02*
X236220D01*
G01X240728Y1083012D02*
X239744D01*
G01X239746Y1082520D02*
X245079D01*
G01Y1082480D02*
X240731D01*
G01X245079Y1081142D02*
X239746D01*
G01X239744Y1080650D02*
X240728D01*
G01Y1078012D02*
X239744D01*
G01X239746Y1077520D02*
X245079D01*
G01Y1077480D02*
X240731D01*
G01X245079Y1076142D02*
X239746D01*
G01X239744Y1075650D02*
X240728D01*
G01Y1073012D02*
X239744D01*
G01X239746Y1072520D02*
X245079D01*
G01Y1072480D02*
X240731D01*
G01X245079Y1071142D02*
X239746D01*
G01X239744Y1070650D02*
X240728D01*
G01Y1068012D02*
X239744D01*
G01X239746Y1067520D02*
X245079D01*
G01Y1067480D02*
X240731D01*
G01X245079Y1066142D02*
X239746D01*
G01X239744Y1065650D02*
X240728D01*
G01Y1063012D02*
X239744D01*
G01X239746Y1062520D02*
X245079D01*
G01Y1062480D02*
X240731D01*
G01X245079Y1061142D02*
X239746D01*
G01X239744Y1060650D02*
X240728D01*
G01Y1058012D02*
X239744D01*
G01X239746Y1057520D02*
X245079D01*
G01Y1057480D02*
X240731D01*
G01X245079Y1056142D02*
X239746D01*
G01X239744Y1055650D02*
X240728D01*
G01Y1053012D02*
X239744D01*
G01X239746Y1052520D02*
X245079D01*
G01Y1052480D02*
X240731D01*
G01X245079Y1051142D02*
X239746D01*
G01X239744Y1050650D02*
X240728D01*
G01Y1048012D02*
X239744D01*
G01X239746Y1047520D02*
X245079D01*
G01Y1047480D02*
X240731D01*
G01X239744Y1082715D02*
X240699Y1082717D01*
G01X240728Y1080946D02*
X239744Y1080945D01*
G01Y1077715D02*
X240699Y1077717D01*
G01X240728Y1075946D02*
X239744Y1075945D01*
G01Y1072715D02*
X240699Y1072717D01*
G01X240728Y1070946D02*
X239744Y1070945D01*
G01Y1067715D02*
X240699Y1067717D01*
G01X240728Y1065946D02*
X239744Y1065945D01*
G01Y1062715D02*
X240699Y1062717D01*
G01X240728Y1060946D02*
X239744Y1060945D01*
G01Y1057715D02*
X240699Y1057717D01*
G01X240728Y1055946D02*
X239744Y1055945D01*
G01Y1052715D02*
X240699Y1052717D01*
G01X240728Y1050946D02*
X239744Y1050945D01*
G01Y1047715D02*
X240699Y1047717D01*
G01X229528Y1086831D02*
X230709Y1085650D01*
G01X224409Y1091673D02*
X227756Y1088327D01*
G01X236417Y1092539D02*
X237721Y1090571D01*
G01X234055Y1094232D02*
X231745Y1098461D01*
G01X246063Y1091673D02*
Y1107421D01*
G01X245079Y1081142D02*
Y1082520D01*
G01Y1076142D02*
Y1077520D01*
G01Y1071142D02*
Y1072520D01*
G01Y1066142D02*
Y1067520D01*
G01Y1061142D02*
Y1062520D01*
G01Y1056142D02*
Y1057520D01*
G01Y1051142D02*
Y1052520D01*
G01X241909D02*
Y1051142D01*
G01Y1057520D02*
Y1056142D01*
G01Y1062520D02*
Y1061142D01*
G01Y1067520D02*
Y1066142D01*
G01Y1072520D02*
Y1071142D01*
G01Y1077520D02*
Y1076142D01*
G01Y1082520D02*
Y1081142D01*
G01X240728Y1080650D02*
Y1083012D01*
G01Y1075650D02*
Y1078012D01*
G01Y1070650D02*
Y1073012D01*
G01Y1065650D02*
Y1068012D01*
G01Y1060650D02*
Y1063012D01*
G01Y1055650D02*
Y1058012D01*
G01Y1050650D02*
Y1053012D01*
G01Y1047494D02*
Y1047637D01*
G01Y1057494D02*
Y1057637D01*
G01Y1052494D02*
Y1052637D01*
G01Y1067494D02*
Y1067637D01*
G01Y1062494D02*
Y1062637D01*
G01Y1077494D02*
Y1077637D01*
G01Y1072494D02*
Y1072637D01*
G01Y1082494D02*
Y1082637D01*
G01X239744Y1053012D02*
Y1050650D01*
G01Y1058012D02*
Y1055650D01*
G01Y1063012D02*
Y1060650D01*
G01Y1068012D02*
Y1065650D01*
G01Y1073012D02*
Y1070650D01*
G01Y1078012D02*
Y1075650D01*
G01Y1083012D02*
Y1080650D01*
G01X239173Y1101909D02*
Y1108012D01*
G01X246063Y1091673D02*
X242717Y1088327D01*
G01X236220Y1085650D02*
X237402Y1086831D01*
G01X232752Y1090571D02*
X234055Y1092539D01*
G01X238728Y1098461D02*
X236417Y1094232D01*
G01X240728Y1047494D02*
X240729Y1047502D01*
G01X240728Y1052494D02*
X240729Y1052502D01*
G01X240728Y1057494D02*
X240729Y1057502D01*
G01X240728Y1062494D02*
X240729Y1062502D01*
G01X240728Y1067494D02*
X240729Y1067502D01*
G01X240728Y1072494D02*
X240729Y1072502D01*
G01X240728Y1077494D02*
X240729Y1077502D01*
G01X240728Y1082494D02*
X240729Y1082502D01*
G01X238976Y1097736D02*
Y1089193D01*
G01X236417Y1094232D02*
Y1092539D01*
G01X234055D02*
Y1094232D01*
G01X231496Y1089193D02*
Y1097736D01*
G01X231299Y1101909D02*
Y1108012D01*
G01X224409Y1107421D02*
Y1091673D01*
G01X246535Y1336220D02*
G03Y1304724I0J-15748D01*
G01X271437Y1320472D02*
G03I-4902J0D01*
G01X252635D02*
G03I-6100J0D01*
G01X252795D02*
G03I-6260J0D01*
G01X266535Y1304724D02*
G03Y1336220I0J15748D01*
G01X277535Y1326272D02*
X270535D01*
G01X271485Y1321822D02*
X261585D01*
G01Y1319122D02*
X271485D01*
G01X289035Y1311456D02*
X309035D01*
G01X289035Y1310276D02*
X281535D01*
G01X270535Y1309772D02*
X281535D01*
G01X236535Y1306772D02*
X541535D01*
G01X246535Y1304724D02*
X266535D01*
G01X289035Y1310276D02*
Y1311456D01*
G01X281535Y1361172D02*
Y1309772D01*
G01X277535Y1361172D02*
Y1326272D01*
G01X271485Y1319122D02*
Y1321822D01*
G01X270535Y1326272D02*
Y1309772D01*
G01X266535Y1334172D02*
Y1306772D01*
G01X261585Y1321822D02*
Y1319122D01*
G01X236535Y1306772D02*
Y1334172D01*
G01X265035Y1364172D02*
X513035D01*
G01X277535Y1361172D02*
X281535D01*
G01X289035Y1360670D02*
X281535D01*
G01X289035Y1360472D02*
X309035D01*
G01X246535Y1336220D02*
X266535D01*
G01X273035Y1334172D02*
X236535D01*
G01X289035Y1360472D02*
Y1360670D01*
G01X273035Y1334172D02*
Y1364172D01*
G01X272535Y1334172D02*
Y1364172D01*
G01X265035Y1334172D02*
Y1364172D01*
G01X284646Y1515748D02*
G03X280709Y1519685I-3937J0D01*
G01X284646Y1500000D02*
Y1515748D01*
G01Y1500000D02*
G03X288583Y1496063I3937J0D01*
G01X493307D02*
X288583D01*
G01X233858Y1497059D02*
G03Y1494280I0J-1389D01*
G01Y1498764D02*
G03Y1492575I0J-3094D01*
G01X284646Y1500000D02*
G03X288583Y1496063I3937J0D01*
G01X284646Y1515748D02*
G03X280709Y1519685I-3937J0D01*
G01X232598Y1499606D02*
G03Y1491732I1260J-3937D01*
G01X229724Y1499606D02*
G03Y1491732I4134J-3937D01*
G01X221260Y1523622D02*
X255118D01*
G01Y1521654D02*
X251575D01*
G01X233858Y1520210D02*
X217323D01*
G01X221260Y1510954D02*
X244488D01*
G01X202756D02*
X213386D01*
G01X231791Y1505512D02*
X235925D01*
G01X215256D02*
X219390D01*
G01X198720D02*
X202854D01*
G01X213386Y1505210D02*
X217323D01*
G01X198819D02*
X202756D01*
G01X233858Y1499606D02*
X229724D01*
G01X493307Y1496063D02*
X288583D01*
G01X244488Y1492913D02*
X255118D01*
G01X229724Y1491732D02*
X233858D01*
G01X224409Y1485827D02*
X210236D01*
G01X240945D02*
X226772D01*
G01X202854Y1469783D02*
X198720D01*
G01X219390D02*
X215256D01*
G01X235925D02*
X231791D01*
G01X202854Y1468996D02*
X198720D01*
G01X219390D02*
X215256D01*
G01X235925D02*
X231791D01*
G01X202854Y1464862D02*
X198720D01*
G01X219390D02*
X215256D01*
G01X235925D02*
X231791D01*
G01X202854Y1448130D02*
X198720D01*
G01X219390D02*
X215256D01*
G01X235925D02*
X231791D01*
G01X202854Y1447343D02*
X198720D01*
G01X219390D02*
X215256D01*
G01X235925D02*
X231791D01*
G01X202854Y1443209D02*
X198720D01*
G01X219390D02*
X215256D01*
G01X235925D02*
X231791D01*
G01X284646Y1515748D02*
Y1500000D01*
G01X255118Y1492913D02*
Y1526772D01*
G01X253425Y1519685D02*
Y1521604D01*
G01X251575Y1526772D02*
Y1521654D01*
G01X244488Y1510954D02*
Y1471260D01*
G01X240945Y1516929D02*
Y1485827D01*
G01X239724Y1523622D02*
Y1471260D01*
G01X237008Y1485827D02*
Y1512992D01*
G01X236220Y1523622D02*
Y1471260D01*
G01X235925Y1443209D02*
Y1471260D01*
G01Y1505512D02*
Y1485827D01*
G01X233858Y1498764D02*
Y1497059D01*
G01Y1510954D02*
Y1526772D01*
G01Y1491732D02*
Y1499606D01*
G01Y1494279D02*
Y1492574D01*
G01X231791Y1471260D02*
Y1443209D01*
G01Y1505512D02*
Y1485827D01*
G01X230709D02*
Y1512992D01*
G01X226772Y1485827D02*
Y1512992D01*
G01X224409Y1485827D02*
Y1512992D01*
G01X221260Y1523622D02*
Y1509843D01*
G01X220472Y1485827D02*
Y1512992D01*
G01X219390Y1443209D02*
Y1471260D01*
G01Y1505512D02*
Y1485827D01*
G01X217323Y1526772D02*
Y1505210D01*
G01X215256Y1471260D02*
Y1443209D01*
G01Y1505512D02*
Y1485827D01*
G01X214173D02*
Y1512992D01*
G01X213386Y1505210D02*
Y1523622D01*
G01X210236Y1485827D02*
Y1512992D01*
G01X207874Y1485827D02*
Y1512992D01*
G01X203937Y1485827D02*
Y1512992D01*
G01X202854Y1443209D02*
Y1471260D01*
G01Y1505512D02*
Y1485827D01*
G01X202756Y1523622D02*
Y1505210D01*
G01X198819D02*
Y1523622D01*
G01X198720Y1471260D02*
Y1443209D01*
G01Y1505512D02*
Y1485827D01*
G01X197638D02*
Y1512992D01*
G01X251575Y1521654D02*
X240945Y1516929D01*
G01X251575Y1526772D02*
X240945Y1516929D01*
G01X255118Y1523622D02*
X244488Y1510954D01*
G01X258597Y1808346D02*
Y1789409D01*
G01X351484Y91259D02*
X351475Y91260D01*
G01X351493Y91256D02*
X351484Y91259D01*
G01X351501Y91250D02*
X351493Y91256D01*
G01X351484Y84959D02*
X351475Y84961D01*
G01X351493Y84956D02*
X351484Y84959D01*
G01X351501Y84951D02*
X351493Y84956D01*
G01X351484Y88109D02*
X351475Y88110D01*
G01X351493Y88106D02*
X351484Y88109D01*
G01X351501Y88100D02*
X351493Y88106D01*
G01X350570Y83774D02*
X350571Y83768D01*
G01X350570Y83778D02*
Y83774D01*
G01X350569Y83780D02*
X350570Y83778D01*
G01Y86924D02*
X350571Y86918D01*
G01X350570Y86928D02*
Y86924D01*
G01X350569Y86929D02*
X350570Y86928D01*
G01Y90074D02*
X350571Y90067D01*
G01X350570Y90078D02*
Y90074D01*
G01X350569Y90079D02*
X350570Y90078D01*
G01Y93223D02*
X350571Y93217D01*
G01X350570Y93227D02*
Y93223D01*
G01X350569Y93228D02*
X350570Y93227D01*
G01X364941Y51975D02*
Y51982D01*
G01X364942Y51970D02*
X364941Y51975D01*
G01X364943Y51969D02*
X364942Y51970D01*
G01X364941Y56975D02*
Y56982D01*
G01X364942Y56970D02*
X364941Y56975D01*
G01X364943Y56969D02*
X364942Y56970D01*
G01X364941Y61975D02*
Y61982D01*
G01X364942Y61970D02*
X364941Y61975D01*
G01X364943Y61969D02*
X364942Y61970D01*
G01X364941Y66975D02*
Y66982D01*
G01X364942Y66970D02*
X364941Y66975D01*
G01X364943Y66969D02*
X364942Y66970D01*
G01X364941Y71975D02*
Y71982D01*
G01X364942Y71970D02*
X364941Y71975D01*
G01X364943Y71969D02*
X364942Y71970D01*
G01X364941Y76975D02*
Y76982D01*
G01X364942Y76970D02*
X364941Y76975D01*
G01X364943Y76969D02*
X364942Y76970D01*
G01X364941Y81975D02*
Y81982D01*
G01X364942Y81970D02*
X364941Y81975D01*
G01X364943Y81969D02*
X364942Y81970D01*
G01X350531Y86959D02*
Y86955D01*
G01X350533Y86952D02*
X350531Y86959D01*
G01X350545Y86937D02*
X350533Y86952D01*
G01X350570Y86929D02*
X350545Y86937D01*
G01X350531Y90108D02*
Y90104D01*
G01X350533Y90102D02*
X350531Y90108D01*
G01X350544Y90087D02*
X350533Y90102D01*
G01X350569Y90079D02*
X350544Y90087D01*
G01X350531Y83809D02*
Y83806D01*
G01X350533Y83803D02*
X350531Y83809D01*
G01X350544Y83788D02*
X350533Y83803D01*
G01X350569Y83780D02*
X350544Y83788D01*
G01X364928Y51999D02*
X364939Y51984D01*
G01X364904Y52008D02*
X364928Y51999D01*
G01Y56999D02*
X364939Y56984D01*
G01X364904Y57008D02*
X364928Y56999D01*
G01Y61999D02*
X364939Y61984D01*
G01X364904Y62008D02*
X364928Y61999D01*
G01Y66999D02*
X364939Y66984D01*
G01X364904Y67008D02*
X364928Y66999D01*
G01Y71999D02*
X364939Y71984D01*
G01X364904Y72008D02*
X364928Y71999D01*
G01Y76999D02*
X364939Y76984D01*
G01X364904Y77008D02*
X364928Y76999D01*
G01Y81999D02*
X364939Y81984D01*
G01X364904Y82008D02*
X364928Y81999D01*
G01X350531Y93258D02*
Y93254D01*
G01X350533Y93252D02*
X350531Y93258D01*
G01X350543Y93238D02*
X350533Y93252D01*
G01X350566Y93228D02*
X350543Y93238D01*
G01X350554Y86931D02*
X350569Y86929D01*
G01X350543Y86939D02*
X350554Y86931D01*
G01X350531Y86957D02*
X350543Y86939D01*
G01X350554Y90081D02*
X350569Y90079D01*
G01X350542Y90089D02*
X350554Y90081D01*
G01X350530Y90109D02*
X350542Y90089D01*
G01X351516Y83813D02*
Y83805D01*
G01X351515Y83817D02*
X351516Y83813D01*
G01X351514Y83819D02*
X351515Y83817D01*
G01X351516Y86963D02*
Y86955D01*
G01X351515Y86967D02*
X351516Y86963D01*
G01X351514Y86969D02*
X351515Y86967D01*
G01X351516Y90112D02*
Y90104D01*
G01X351515Y90117D02*
X351516Y90112D01*
G01X351514Y90118D02*
X351515Y90117D01*
G01X351516Y93262D02*
Y93254D01*
G01X351515Y93266D02*
X351516Y93262D01*
G01X351514Y93268D02*
X351515Y93266D01*
G01X350554Y83782D02*
X350569Y83780D01*
G01X350541Y83791D02*
X350554Y83782D01*
G01X350530Y83811D02*
X350541Y83791D01*
G01X351515Y84941D02*
X351516Y84935D01*
G01X351513Y84948D02*
X351515Y84941D01*
G01X351510Y84954D02*
X351513Y84948D01*
G01X351515Y88091D02*
X351516Y88084D01*
G01X351513Y88097D02*
X351515Y88091D01*
G01X351510Y88103D02*
X351513Y88097D01*
G01X351515Y91241D02*
X351516Y91234D01*
G01X351513Y91247D02*
X351515Y91241D01*
G01X351510Y91253D02*
X351513Y91247D01*
G01X351477Y83774D02*
Y83768D01*
G01X351476Y83778D02*
X351477Y83774D01*
G01X351475Y83780D02*
X351476Y83778D01*
G01X351477Y86924D02*
Y86918D01*
G01X351476Y86928D02*
X351477Y86924D01*
G01X351475Y86929D02*
X351476Y86928D01*
G01X351477Y90074D02*
Y90067D01*
G01X351476Y90077D02*
X351477Y90074D01*
G01X351475Y90079D02*
X351476Y90077D01*
G01X351477Y93223D02*
Y93217D01*
G01X351476Y93227D02*
X351477Y93223D01*
G01X351475Y93228D02*
X351476Y93227D01*
G01X363957Y52015D02*
Y52024D01*
G01Y52009D02*
Y52015D01*
G01X363958Y52008D02*
X363957Y52009D01*
G01Y57015D02*
Y57024D01*
G01Y57009D02*
Y57015D01*
G01X363958Y57008D02*
X363957Y57009D01*
G01Y62015D02*
Y62024D01*
G01Y62009D02*
Y62015D01*
G01X363958Y62008D02*
X363957Y62009D01*
G01Y67015D02*
Y67024D01*
G01Y67009D02*
Y67015D01*
G01X363958Y67008D02*
X363957Y67009D01*
G01Y72015D02*
Y72024D01*
G01Y72009D02*
Y72015D01*
G01X363958Y72008D02*
X363957Y72009D01*
G01Y77015D02*
Y77024D01*
G01Y77009D02*
Y77015D01*
G01X363958Y77008D02*
X363957Y77009D01*
G01Y82015D02*
Y82024D01*
G01Y82009D02*
Y82015D01*
G01X363958Y82008D02*
X363957Y82009D01*
G01X364933Y52152D02*
X364941Y52125D01*
G01X364923Y52178D02*
X364933Y52152D01*
G01X364912Y52205D02*
X364923Y52178D01*
G01X364933Y57152D02*
X364941Y57125D01*
G01X364923Y57178D02*
X364933Y57152D01*
G01X364912Y57205D02*
X364923Y57178D01*
G01X364933Y62152D02*
X364941Y62125D01*
G01X364923Y62178D02*
X364933Y62152D01*
G01X364912Y62205D02*
X364923Y62178D01*
G01X364933Y67152D02*
X364941Y67125D01*
G01X364923Y67178D02*
X364933Y67152D01*
G01X364912Y67205D02*
X364923Y67178D01*
G01X364933Y72152D02*
X364941Y72125D01*
G01X364923Y72178D02*
X364933Y72152D01*
G01X364912Y72205D02*
X364923Y72178D01*
G01X364933Y77152D02*
X364941Y77125D01*
G01X364923Y77178D02*
X364933Y77152D01*
G01X364912Y77205D02*
X364923Y77178D01*
G01X364933Y82152D02*
X364941Y82125D01*
G01X364923Y82178D02*
X364933Y82152D01*
G01X364912Y82205D02*
X364923Y82178D01*
G01X350532Y83798D02*
X350531Y83805D01*
G01X350535Y83791D02*
X350532Y83798D01*
G01X350538Y83785D02*
X350535Y83791D01*
G01X350543Y83779D02*
X350538Y83785D01*
G01X350549Y83774D02*
X350543Y83779D01*
G01X350556Y83771D02*
X350549Y83774D01*
G01X350563Y83769D02*
X350556Y83771D01*
G01X350571Y83768D02*
X350563Y83769D01*
G01X350532Y86948D02*
X350531Y86955D01*
G01X350535Y86941D02*
X350532Y86948D01*
G01X350538Y86934D02*
X350535Y86941D01*
G01X350543Y86929D02*
X350538Y86934D01*
G01X350549Y86924D02*
X350543Y86929D01*
G01X350556Y86920D02*
X350549Y86924D01*
G01X350563Y86919D02*
X350556Y86920D01*
G01X350571Y86918D02*
X350563Y86919D01*
G01X351485Y84959D02*
X351495Y84955D01*
G01X351475Y84961D02*
X351485Y84959D01*
G01Y88109D02*
X351495Y88105D01*
G01X351475Y88110D02*
X351485Y88109D01*
G01Y91258D02*
X351495Y91254D01*
G01X351475Y91260D02*
X351485Y91258D01*
G01X350549Y93233D02*
X350569Y93228D01*
G01X350536Y93246D02*
X350549Y93233D01*
G01X350529Y93263D02*
X350536Y93246D01*
G01X364924Y52003D02*
X364904Y52008D01*
G01X364938Y51988D02*
X364924Y52003D01*
G01X364943Y51969D02*
X364938Y51988D01*
G01X364924Y57003D02*
X364904Y57008D01*
G01X364938Y56988D02*
X364924Y57003D01*
G01X364943Y56969D02*
X364938Y56988D01*
G01X364924Y62003D02*
X364904Y62008D01*
G01X364938Y61988D02*
X364924Y62003D01*
G01X364943Y61969D02*
X364938Y61988D01*
G01X364924Y67003D02*
X364904Y67008D01*
G01X364938Y66988D02*
X364924Y67003D01*
G01X364943Y66969D02*
X364938Y66988D01*
G01X364924Y72003D02*
X364904Y72008D01*
G01X364938Y71988D02*
X364924Y72003D01*
G01X364943Y71969D02*
X364938Y71988D01*
G01X364924Y77003D02*
X364904Y77008D01*
G01X364938Y76988D02*
X364924Y77003D01*
G01X364943Y76969D02*
X364938Y76988D01*
G01X364924Y82003D02*
X364904Y82008D01*
G01X364938Y81988D02*
X364924Y82003D01*
G01X364943Y81969D02*
X364938Y81988D01*
G01X364908Y52106D02*
X364912Y52205D01*
G01X364902Y52034D02*
X364908Y52106D01*
G01X364904Y52008D02*
X364902Y52034D01*
G01X364908Y57106D02*
X364912Y57205D01*
G01X364902Y57034D02*
X364908Y57106D01*
G01X364904Y57008D02*
X364902Y57034D01*
G01X364908Y62106D02*
X364912Y62205D01*
G01X364902Y62034D02*
X364908Y62106D01*
G01X364904Y62008D02*
X364902Y62034D01*
G01X364908Y67106D02*
X364912Y67205D01*
G01X364902Y67034D02*
X364908Y67106D01*
G01X364904Y67008D02*
X364902Y67034D01*
G01X364908Y72106D02*
X364912Y72205D01*
G01X364902Y72034D02*
X364908Y72106D01*
G01X364904Y72008D02*
X364902Y72034D01*
G01X364908Y77106D02*
X364912Y77205D01*
G01X364902Y77034D02*
X364908Y77106D01*
G01X364904Y77008D02*
X364902Y77034D01*
G01X364908Y82106D02*
X364912Y82205D01*
G01X364902Y82034D02*
X364908Y82106D01*
G01X364904Y82008D02*
X364902Y82034D01*
G01X351493Y83772D02*
X351496Y83774D01*
G01X351490Y83770D02*
X351493Y83772D01*
G01X351487Y83770D02*
X351490D01*
G01X351483Y83769D02*
X351487Y83770D01*
G01X351480Y83769D02*
X351483D01*
G01X351476Y83768D02*
X351480Y83769D01*
G01X350554Y84968D02*
X350551Y84967D01*
G01X350557Y84969D02*
X350554Y84968D01*
G01X350561Y84970D02*
X350557Y84969D01*
G01X350564Y84971D02*
X350561Y84970D01*
G01X350567Y84972D02*
X350564Y84971D01*
G01X350571Y84972D02*
X350567D01*
G01X351493Y86921D02*
X351496Y86923D01*
G01X351490Y86920D02*
X351493Y86921D01*
G01X351487Y86919D02*
X351490Y86920D01*
G01X351483Y86919D02*
X351487D01*
G01X351480Y86918D02*
X351483Y86919D01*
G01X351476Y86918D02*
X351480D01*
G01X350554Y88118D02*
X350551Y88116D01*
G01X350557Y88119D02*
X350554Y88118D01*
G01X350561Y88120D02*
X350557Y88119D01*
G01X350564Y88121D02*
X350561Y88120D01*
G01X350567Y88121D02*
X350564D01*
G01X350571D02*
X350567D01*
G01X351493Y90071D02*
X351496Y90073D01*
G01X351490Y90070D02*
X351493Y90071D01*
G01X351487Y90069D02*
X351490Y90070D01*
G01X351483Y90068D02*
X351487Y90069D01*
G01X351480Y90068D02*
X351483D01*
G01X351476Y90067D02*
X351480Y90068D01*
G01X349784Y86969D02*
X349350D01*
G01X350158D02*
X349784D01*
G01Y93268D02*
X349350D01*
G01X350158D02*
X349784D01*
G01X351506Y84959D02*
X351510Y84954D01*
G01X351502Y84963D02*
X351506Y84959D01*
G01X351496Y84967D02*
X351502Y84963D01*
G01X351490Y84970D02*
X351496Y84967D01*
G01X351483Y84971D02*
X351490Y84970D01*
G01X351476Y84972D02*
X351483Y84971D01*
G01X351506Y88109D02*
X351510Y88103D01*
G01X351502Y88113D02*
X351506Y88109D01*
G01X351496Y88117D02*
X351502Y88113D01*
G01X351490Y88119D02*
X351496Y88117D01*
G01X351483Y88121D02*
X351490Y88119D01*
G01X351476Y88121D02*
X351483D01*
G01X351506Y91258D02*
X351510Y91253D01*
G01X351502Y91263D02*
X351506Y91258D01*
G01X351496Y91266D02*
X351502Y91263D01*
G01X351490Y91269D02*
X351496Y91266D01*
G01X351483Y91270D02*
X351490Y91269D01*
G01X351476Y91271D02*
X351483Y91270D01*
G01X350532Y90097D02*
X350531Y90104D01*
G01X350535Y90090D02*
X350532Y90097D01*
G01X350538Y90084D02*
X350535Y90090D01*
G01X350543Y90078D02*
X350538Y90084D01*
G01X350549Y90074D02*
X350543Y90078D01*
G01X350556Y90070D02*
X350549Y90074D01*
G01X350563Y90068D02*
X350556Y90070D01*
G01X350571Y90067D02*
X350563Y90068D01*
G01X350532Y93247D02*
X350531Y93254D01*
G01X350535Y93240D02*
X350532Y93247D01*
G01X350538Y93233D02*
X350535Y93240D01*
G01X350543Y93228D02*
X350538Y93233D01*
G01X350549Y93223D02*
X350543Y93228D01*
G01X350556Y93220D02*
X350549Y93223D01*
G01X350563Y93218D02*
X350556Y93220D01*
G01X350571Y93217D02*
X350563Y93218D01*
G01X351508Y91242D02*
X351501Y91250D01*
G01X351513Y91231D02*
X351508Y91242D01*
G01X351515Y91220D02*
X351513Y91231D01*
G01X351508Y84943D02*
X351501Y84951D01*
G01X351513Y84932D02*
X351508Y84943D01*
G01X351515Y84921D02*
X351513Y84932D01*
G01X351508Y88092D02*
X351501Y88100D01*
G01X351513Y88082D02*
X351508Y88092D01*
G01X351515Y88071D02*
X351513Y88082D01*
G01X350572Y91444D02*
X350571Y91457D01*
G01X350569Y91431D02*
X350572Y91444D01*
G01X350569Y91417D02*
Y91431D01*
G01X350572Y88294D02*
X350571Y88307D01*
G01X350569Y88281D02*
X350572Y88294D01*
G01X350569Y88268D02*
Y88281D01*
G01X350572Y85145D02*
X350571Y85157D01*
G01X350569Y85132D02*
X350572Y85145D01*
G01X350569Y85118D02*
Y85132D01*
G01X363957Y80628D02*
X363958Y80630D01*
G01X363957Y80622D02*
Y80628D01*
G01Y80614D02*
Y80622D01*
G01Y75628D02*
X363958Y75630D01*
G01X363957Y75622D02*
Y75628D01*
G01Y75614D02*
Y75622D01*
G01Y70628D02*
X363958Y70630D01*
G01X363957Y70622D02*
Y70628D01*
G01Y70614D02*
Y70622D01*
G01Y65628D02*
X363958Y65630D01*
G01X363957Y65622D02*
Y65628D01*
G01Y65614D02*
Y65622D01*
G01Y60628D02*
X363958Y60630D01*
G01X363957Y60622D02*
Y60628D01*
G01Y60614D02*
Y60622D01*
G01Y55628D02*
X363958Y55630D01*
G01X363957Y55622D02*
Y55628D01*
G01Y55614D02*
Y55622D01*
G01Y50628D02*
X363958Y50630D01*
G01X363957Y50622D02*
Y50628D01*
G01Y50614D02*
Y50622D01*
G01X350569Y93057D02*
X350567Y93070D01*
G01X350572Y93044D02*
X350569Y93057D01*
G01X350571Y93031D02*
X350572Y93044D01*
G01X350569Y89907D02*
X350567Y89921D01*
G01X350572Y89894D02*
X350569Y89907D01*
G01X350571Y89882D02*
X350572Y89894D01*
G01X350569Y86757D02*
X350567Y86771D01*
G01X350572Y86745D02*
X350569Y86757D01*
G01X350571Y86732D02*
X350572Y86745D01*
G01X350569Y83608D02*
X350567Y83622D01*
G01X350572Y83595D02*
X350569Y83608D01*
G01X350571Y83583D02*
X350572Y83595D01*
G01X351479Y91431D02*
X351480Y91417D01*
G01X351476Y91444D02*
X351479Y91431D01*
G01X351476Y91457D02*
Y91444D01*
G01X351479Y88281D02*
X351480Y88268D01*
G01X351476Y88294D02*
X351479Y88281D01*
G01X351476Y88307D02*
Y88294D01*
G01X351479Y85132D02*
X351480Y85118D01*
G01X351476Y85145D02*
X351479Y85132D01*
G01X351476Y85157D02*
Y85145D01*
G01X350531Y90112D02*
Y90105D01*
G01X350530Y90117D02*
X350531Y90112D01*
G01X350530Y90109D02*
Y90117D01*
G01X350554Y91267D02*
X350551Y91266D01*
G01X350557Y91269D02*
X350554Y91267D01*
G01X350561Y91270D02*
X350557Y91269D01*
G01X350564Y91270D02*
X350561D01*
G01X350567Y91271D02*
X350564Y91270D01*
G01X350571Y91271D02*
X350567D01*
G01X351493Y93220D02*
X351496Y93222D01*
G01X351490Y93219D02*
X351493Y93220D01*
G01X351487Y93219D02*
X351490D01*
G01X351483Y93218D02*
X351487Y93219D01*
G01X351480Y93217D02*
X351483Y93218D01*
G01X351476Y93217D02*
X351480D01*
G01X351476Y93044D02*
Y93031D01*
G01X351478Y93057D02*
X351476Y93044D01*
G01X351480Y93070D02*
X351478Y93057D01*
G01X351476Y89894D02*
Y89882D01*
G01X351478Y89907D02*
X351476Y89894D01*
G01X351480Y89921D02*
X351478Y89907D01*
G01X351476Y86745D02*
Y86732D01*
G01X351478Y86757D02*
X351476Y86745D01*
G01X351480Y86771D02*
X351478Y86757D01*
G01X351476Y83595D02*
Y83583D01*
G01X351478Y83608D02*
X351476Y83595D01*
G01X351480Y83622D02*
X351478Y83608D01*
G01X350531Y83813D02*
Y83806D01*
G01X350530Y83817D02*
X350531Y83813D01*
G01X350530Y83811D02*
Y83817D01*
G01X350534Y84941D02*
X350529Y84921D01*
G01X350549Y84955D02*
X350534Y84941D01*
G01X350569Y84961D02*
X350549Y84955D01*
G01X350534Y88091D02*
X350529Y88071D01*
G01X350549Y88105D02*
X350534Y88091D01*
G01X350569Y88110D02*
X350549Y88105D01*
G01X350534Y91240D02*
X350529Y91220D01*
G01X350549Y91254D02*
X350534Y91240D01*
G01X350569Y91260D02*
X350549Y91254D01*
G01X351509Y83799D02*
X351514Y83819D01*
G01X351494Y83785D02*
X351509Y83799D01*
G01X351475Y83780D02*
X351494Y83785D01*
G01X351509Y86949D02*
X351514Y86969D01*
G01X351494Y86934D02*
X351509Y86949D01*
G01X351475Y86929D02*
X351494Y86934D01*
G01X351509Y90098D02*
X351514Y90118D01*
G01X351494Y90084D02*
X351509Y90098D01*
G01X351475Y90079D02*
X351494Y90084D01*
G01X351509Y93248D02*
X351514Y93268D01*
G01X351494Y93233D02*
X351509Y93248D01*
G01X351475Y93228D02*
X351494Y93233D01*
G01X350544Y91251D02*
X350569Y91260D01*
G01X350533Y91237D02*
X350544Y91251D01*
G01X350531Y91230D02*
X350533Y91237D01*
G01X350544Y88102D02*
X350569Y88110D01*
G01X350533Y88087D02*
X350544Y88102D01*
G01X350531Y88080D02*
X350533Y88087D01*
G01X350544Y84952D02*
X350569Y84961D01*
G01X350533Y84937D02*
X350544Y84952D01*
G01X350531Y84931D02*
X350533Y84937D01*
G01X351516Y91227D02*
Y91234D01*
G01X351515Y91222D02*
X351516Y91227D01*
G01X351515Y91220D02*
Y91222D01*
G01X351516Y88077D02*
Y88084D01*
G01X351515Y88072D02*
X351516Y88077D01*
G01X351515Y88071D02*
Y88072D01*
G01X351516Y84928D02*
Y84935D01*
G01X351515Y84923D02*
X351516Y84928D01*
G01X351515Y84921D02*
Y84923D01*
G01X350531Y93262D02*
Y93254D01*
G01X350530Y93266D02*
X350531Y93262D01*
G01X350529Y93263D02*
X350530Y93266D01*
G01X350531Y86963D02*
Y86955D01*
G01X350530Y86967D02*
X350531Y86963D01*
G01X350529Y86965D02*
X350530Y86967D01*
G01X351476Y91265D02*
Y91271D01*
G01Y91261D02*
Y91265D01*
G01X351475Y91260D02*
X351476Y91261D01*
G01Y88115D02*
Y88121D01*
G01Y88111D02*
Y88115D01*
G01X351475Y88110D02*
X351476Y88111D01*
G01Y84966D02*
Y84972D01*
G01Y84962D02*
Y84966D01*
G01X351475Y84961D02*
X351476Y84962D01*
G01X364941Y80622D02*
Y80613D01*
G01X364942Y80628D02*
X364941Y80622D01*
G01X364944Y80630D02*
X364942Y80628D01*
G01X364941Y75622D02*
Y75613D01*
G01X364942Y75628D02*
X364941Y75622D01*
G01X364944Y75630D02*
X364942Y75628D01*
G01X364941Y70622D02*
Y70613D01*
G01X364942Y70628D02*
X364941Y70622D01*
G01X364944Y70630D02*
X364942Y70628D01*
G01X364941Y65622D02*
Y65613D01*
G01X364942Y65628D02*
X364941Y65622D01*
G01X364944Y65630D02*
X364942Y65628D01*
G01X364941Y60622D02*
Y60613D01*
G01X364942Y60628D02*
X364941Y60622D01*
G01X364944Y60630D02*
X364942Y60628D01*
G01X364941Y55622D02*
Y55613D01*
G01X364942Y55628D02*
X364941Y55622D01*
G01X364944Y55630D02*
X364942Y55628D01*
G01X364941Y50622D02*
Y50613D01*
G01X364942Y50628D02*
X364941Y50622D01*
G01X364944Y50630D02*
X364942Y50628D01*
G01X350531Y91226D02*
Y91234D01*
G01X350530Y91222D02*
X350531Y91226D01*
G01X350529Y91220D02*
X350530Y91222D01*
G01X350531Y88077D02*
Y88084D01*
G01X350530Y88072D02*
X350531Y88077D01*
G01X350529Y88071D02*
X350530Y88072D01*
G01X350531Y84927D02*
Y84935D01*
G01X350530Y84923D02*
X350531Y84927D01*
G01X350529Y84921D02*
X350530Y84923D01*
G01X351513Y93242D02*
X351516Y93254D01*
G01X351507Y93230D02*
X351513Y93242D01*
G01X351496Y93222D02*
X351507Y93230D01*
G01X351513Y90092D02*
X351516Y90104D01*
G01X351507Y90081D02*
X351513Y90092D01*
G01X351496Y90073D02*
X351507Y90081D01*
G01X351513Y86943D02*
X351516Y86955D01*
G01X351507Y86931D02*
X351513Y86943D01*
G01X351496Y86923D02*
X351507Y86931D01*
G01X351513Y83793D02*
X351516Y83805D01*
G01X351507Y83781D02*
X351513Y83793D01*
G01X351496Y83774D02*
X351507Y83781D01*
G01X350570Y91265D02*
Y91271D01*
G01Y91261D02*
Y91265D01*
G01X350569Y91260D02*
X350570Y91261D01*
G01Y88115D02*
Y88121D01*
G01Y88111D02*
Y88115D01*
G01X350569Y88110D02*
X350570Y88111D01*
G01Y84965D02*
Y84972D01*
G01Y84962D02*
Y84965D01*
G01X350569Y84961D02*
X350570Y84962D01*
G01X350532Y91240D02*
X350531Y91234D01*
G01X350534Y91246D02*
X350532Y91240D01*
G01X350537Y91252D02*
X350534Y91246D01*
G01X350541Y91257D02*
X350537Y91252D01*
G01X350545Y91262D02*
X350541Y91257D01*
G01X350551Y91266D02*
X350545Y91262D01*
G01X350532Y88091D02*
X350531Y88084D01*
G01X350534Y88097D02*
X350532Y88091D01*
G01X350537Y88103D02*
X350534Y88097D01*
G01X350541Y88108D02*
X350537Y88103D01*
G01X350545Y88113D02*
X350541Y88108D01*
G01X350551Y88116D02*
X350545Y88113D01*
G01X350532Y84941D02*
X350531Y84935D01*
G01X350534Y84947D02*
X350532Y84941D01*
G01X350537Y84953D02*
X350534Y84947D01*
G01X350541Y84958D02*
X350537Y84953D01*
G01X350545Y84963D02*
X350541Y84958D01*
G01X350551Y84967D02*
X350545Y84963D01*
G01X351487Y93230D02*
X351475Y93228D01*
G01X351497Y93235D02*
X351487Y93230D01*
G01Y90081D02*
X351475Y90079D01*
G01X351497Y90085D02*
X351487Y90081D01*
G01Y86931D02*
X351475Y86929D01*
G01X351497Y86936D02*
X351487Y86931D01*
G01Y83781D02*
X351475Y83780D01*
G01X351497Y83786D02*
X351487Y83781D01*
G01X368307Y23760D02*
G03X370276Y25728I0J1969D01*
G01X355512Y25138D02*
G03X356102Y24547I591J0D01*
G01X362795D02*
G03X363386Y25138I0J591D01*
G01X360630Y26319D02*
G03Y28287I0J984D01*
G01X358268D02*
G03Y26319I0J-984D01*
G01X360551Y39508D02*
G03I-1102J0D01*
G01X362008Y34232D02*
G03X363189Y35413I0J1181D01*
G01X355709D02*
G03X356890Y34232I1181J0D01*
G01X361024Y39508D02*
G03I-1575J0D01*
G01X348622Y25728D02*
G03X350591Y23760I1968J0D01*
G01X354921Y47500D02*
X353740Y46319D01*
G01X351969Y44823D02*
X348622Y41476D01*
G01X361933Y42579D02*
X360630Y40610D01*
G01X355957Y34688D02*
X358268Y38917D01*
G01X351515Y84923D02*
X351516Y84935D01*
G01X351515Y88073D02*
X351516Y88084D01*
G01X351515Y91222D02*
X351516Y91234D01*
G01X364941Y51982D02*
Y51991D01*
G01Y56982D02*
Y56991D01*
G01Y61982D02*
Y61991D01*
G01Y66982D02*
Y66991D01*
G01Y71982D02*
Y71991D01*
G01Y76982D02*
Y76991D01*
G01Y81982D02*
Y81991D01*
G01X370276Y25728D02*
Y41476D01*
G01X369291Y80630D02*
Y82008D01*
G01Y75630D02*
Y77008D01*
G01Y70630D02*
Y72008D01*
G01Y65630D02*
Y67008D01*
G01Y60630D02*
Y62008D01*
G01Y55630D02*
Y57008D01*
G01Y50630D02*
Y52008D01*
G01X366929Y182815D02*
Y44823D01*
G01X366339Y185059D02*
Y42579D01*
G01X366122Y52008D02*
Y50630D01*
G01Y57008D02*
Y55630D01*
G01Y62008D02*
Y60630D01*
G01Y67008D02*
Y65630D01*
G01Y72008D02*
Y70630D01*
G01Y77008D02*
Y75630D01*
G01Y82008D02*
Y80630D01*
G01X365551Y104862D02*
Y82776D01*
G01X364941Y56982D02*
Y57125D01*
G01Y51982D02*
Y52125D01*
G01Y66982D02*
Y67125D01*
G01Y61982D02*
Y62125D01*
G01Y76982D02*
Y77125D01*
G01Y71982D02*
Y72125D01*
G01Y81982D02*
Y82125D01*
G01Y80138D02*
Y82500D01*
G01Y75138D02*
Y77500D01*
G01Y70138D02*
Y72500D01*
G01Y65138D02*
Y67500D01*
G01Y60138D02*
Y62500D01*
G01Y55138D02*
Y57500D01*
G01Y50138D02*
Y52500D01*
G01X364370Y103681D02*
Y83957D01*
G01X363957Y52500D02*
Y50138D01*
G01Y57500D02*
Y55138D01*
G01Y62500D02*
Y60138D01*
G01Y67500D02*
Y65138D01*
G01Y72500D02*
Y70138D01*
G01Y77500D02*
Y75138D01*
G01Y82500D02*
Y80138D01*
G01X363386Y31240D02*
Y25138D01*
G01X363189Y43957D02*
Y35413D01*
G01X361614Y82776D02*
Y46319D01*
G01X360630Y40610D02*
Y38917D01*
G01X360433Y83957D02*
Y47500D01*
G01X358268Y38917D02*
Y40610D01*
G01X355709Y35413D02*
Y43957D01*
G01X355512Y31240D02*
Y25138D01*
G01X354921Y47500D02*
Y180138D01*
G01X353740Y46319D02*
Y181319D01*
G01X351969Y81614D02*
Y42579D01*
G01X351516Y93070D02*
Y94567D01*
G01Y89921D02*
Y91417D01*
G01Y86771D02*
Y88268D01*
G01Y83622D02*
Y85118D01*
G01X351476Y86918D02*
Y86771D01*
G01Y83768D02*
Y83621D01*
G01Y85119D02*
Y84972D01*
G01Y90067D02*
Y89920D01*
G01Y91418D02*
Y91271D01*
G01Y88268D02*
Y88121D01*
G01Y93217D02*
Y93070D01*
G01X350571D02*
Y93217D01*
G01Y89920D02*
Y90067D01*
G01Y91271D02*
Y91418D01*
G01Y88121D02*
Y88268D01*
G01Y86771D02*
Y86918D01*
G01Y83621D02*
Y83768D01*
G01Y84972D02*
Y85119D01*
G01X350531Y85118D02*
Y83622D01*
G01Y91417D02*
Y89921D01*
G01Y88268D02*
Y86772D01*
G01Y94567D02*
Y93071D01*
G01X349350Y88110D02*
Y86929D01*
G01Y84961D02*
Y83780D01*
G01Y91260D02*
Y90079D01*
G01Y94409D02*
Y93228D01*
G01X349016Y106024D02*
Y81614D01*
G01X348622D02*
Y106024D01*
G01Y41476D02*
Y25728D01*
G01X345591Y93228D02*
Y94409D01*
G01Y90079D02*
Y91260D01*
G01Y86929D02*
Y88110D01*
G01Y83780D02*
Y84961D01*
G01X351516Y93254D02*
X351515Y93265D01*
G01X351516Y90105D02*
X351515Y90115D01*
G01X351516Y86955D02*
X351515Y86966D01*
G01X351516Y83806D02*
X351515Y83816D01*
G01X350529Y93263D02*
X350418Y93268D01*
G01X350529Y86965D02*
X350418Y86969D01*
G01X351514Y93268D02*
X345591D01*
G01X351475Y93228D02*
X345591D01*
G01X350531Y93071D02*
X351516D01*
G01X350571Y93031D02*
X351476D01*
G01Y91457D02*
X350571D01*
G01X351516Y91417D02*
X350531D01*
G01X351475Y91260D02*
X345591D01*
G01Y91220D02*
X351515D01*
G01X351514Y90118D02*
X345591D01*
G01X351475Y90079D02*
X345591D01*
G01X350531Y89921D02*
X351516D01*
G01X350571Y89882D02*
X351476D01*
G01Y88307D02*
X350571D01*
G01X351516Y88268D02*
X350531D01*
G01X351475Y88110D02*
X345591D01*
G01Y88071D02*
X351515D01*
G01X351514Y86969D02*
X345591D01*
G01X351475Y86929D02*
X345591D01*
G01X350531Y86772D02*
X351516D01*
G01X350571Y86732D02*
X351476D01*
G01Y85157D02*
X350571D01*
G01X351516Y85118D02*
X350531D01*
G01X351475Y84961D02*
X345591D01*
G01Y84921D02*
X351515D01*
G01X364370Y83957D02*
X360433D01*
G01X351514Y83819D02*
X345591D01*
G01X351475Y83780D02*
X345591D01*
G01X350531Y83622D02*
X351516D01*
G01X350571Y83583D02*
X351476D01*
G01X365551Y82776D02*
X361614D01*
G01X364941Y82500D02*
X363957D01*
G01X363958Y82008D02*
X369291D01*
G01Y81969D02*
X364943D01*
G01X351969Y81614D02*
X348622D01*
G01X369291Y80630D02*
X363958D01*
G01X363957Y80138D02*
X364941D01*
G01Y77500D02*
X363957D01*
G01X363958Y77008D02*
X369291D01*
G01Y76969D02*
X364943D01*
G01X369291Y75630D02*
X363958D01*
G01X363957Y75138D02*
X364941D01*
G01Y72500D02*
X363957D01*
G01X363958Y72008D02*
X369291D01*
G01Y71969D02*
X364943D01*
G01X369291Y70630D02*
X363958D01*
G01X363957Y70138D02*
X364941D01*
G01Y67500D02*
X363957D01*
G01X363958Y67008D02*
X369291D01*
G01Y66969D02*
X364943D01*
G01X369291Y65630D02*
X363958D01*
G01X363957Y65138D02*
X364941D01*
G01Y62500D02*
X363957D01*
G01X363958Y62008D02*
X369291D01*
G01Y61969D02*
X364943D01*
G01X369291Y60630D02*
X363958D01*
G01X363957Y60138D02*
X364941D01*
G01Y57500D02*
X363957D01*
G01X363958Y57008D02*
X369291D01*
G01Y56969D02*
X364943D01*
G01X369291Y55630D02*
X363958D01*
G01X363957Y55138D02*
X364941D01*
G01Y52500D02*
X363957D01*
G01X363958Y52008D02*
X369291D01*
G01Y51969D02*
X364943D01*
G01X369291Y50630D02*
X363958D01*
G01X363957Y50138D02*
X364941D01*
G01X360433Y47500D02*
X354921D01*
G01X361614Y46319D02*
X353740D01*
G01X366929Y44823D02*
X351969D01*
G01X363189Y43957D02*
X366339D01*
G01X355709D02*
X351969D01*
G01Y42579D02*
X366339D01*
G01X360630Y40610D02*
X358268D01*
G01X360630Y38917D02*
X358268D01*
G01X363957Y82204D02*
X364912Y82205D01*
G01X364941Y80434D02*
X363957Y80433D01*
G01Y77204D02*
X364912Y77205D01*
G01X364941Y75434D02*
X363957Y75433D01*
G01Y72204D02*
X364912Y72205D01*
G01X364941Y70434D02*
X363957Y70433D01*
G01Y67204D02*
X364912Y67205D01*
G01X364941Y65434D02*
X363957Y65433D01*
G01Y62204D02*
X364912Y62205D01*
G01X364941Y60434D02*
X363957Y60433D01*
G01Y57204D02*
X364912Y57205D01*
G01X364941Y55434D02*
X363957Y55433D01*
G01Y52204D02*
X364912Y52205D01*
G01X364941Y50434D02*
X363957Y50433D01*
G01X362008Y34232D02*
X356890D01*
G01X370276Y34193D02*
X348622D01*
G01X363386Y31240D02*
X355512D01*
G01Y29665D02*
X363386D01*
G01X360630Y28287D02*
X358268D01*
G01Y26319D02*
X360630D01*
G01X362795Y24547D02*
X356102D01*
G01X368307Y23760D02*
X350591D01*
G01X360630Y38917D02*
X362940Y34688D01*
G01X358268Y40610D02*
X356964Y42579D01*
G01X364370Y83957D02*
X365551Y82776D01*
G01X360433Y83957D02*
X361614Y82776D01*
G01X366929Y44823D02*
X370276Y41476D01*
G01X360433Y47500D02*
X361614Y46319D01*
G01X351484Y94408D02*
X351475Y94409D01*
G01X351493Y94405D02*
X351484Y94408D01*
G01X351501Y94400D02*
X351493Y94405D01*
G01X351484Y97558D02*
X351475Y97559D01*
G01X351493Y97555D02*
X351484Y97558D01*
G01X351501Y97549D02*
X351493Y97555D01*
G01X351484Y100707D02*
X351475Y100709D01*
G01X351493Y100704D02*
X351484Y100707D01*
G01X351501Y100699D02*
X351493Y100704D01*
G01X350570Y96373D02*
X350571Y96367D01*
G01X350570Y96377D02*
Y96373D01*
G01X350569Y96378D02*
X350570Y96377D01*
G01Y99522D02*
X350571Y99516D01*
G01X350570Y99526D02*
Y99522D01*
G01X350569Y99528D02*
X350570Y99526D01*
G01Y102672D02*
X350571Y102666D01*
G01X350570Y102676D02*
Y102672D01*
G01X350569Y102677D02*
X350570Y102676D01*
G01X350531Y96407D02*
Y96404D01*
G01X350533Y96401D02*
X350531Y96407D01*
G01X350544Y96386D02*
X350533Y96401D01*
G01X350569Y96378D02*
X350544Y96386D01*
G01X350531Y99557D02*
Y99553D01*
G01X350533Y99551D02*
X350531Y99557D01*
G01X350544Y99536D02*
X350533Y99551D01*
G01X350569Y99528D02*
X350544Y99536D01*
G01X350531Y102707D02*
Y102703D01*
G01X350533Y102701D02*
X350531Y102707D01*
G01X350544Y102685D02*
X350533Y102701D01*
G01X350569Y102677D02*
X350544Y102685D01*
G01X364928Y106999D02*
X364939Y106984D01*
G01X364904Y107008D02*
X364928Y106999D01*
G01Y111999D02*
X364939Y111984D01*
G01X364904Y112008D02*
X364928Y111999D01*
G01X351484Y103857D02*
X351475Y103858D01*
G01X351493Y103854D02*
X351484Y103857D01*
G01X351501Y103848D02*
X351493Y103854D01*
G01X364941Y106975D02*
Y106982D01*
G01X364942Y106970D02*
X364941Y106975D01*
G01X364943Y106969D02*
X364942Y106970D01*
G01X364941Y111975D02*
Y111982D01*
G01X364942Y111970D02*
X364941Y111975D01*
G01X364943Y111969D02*
X364942Y111970D01*
G01X364941Y116975D02*
Y116982D01*
G01X364942Y116970D02*
X364941Y116975D01*
G01X364943Y116969D02*
X364942Y116970D01*
G01X364941Y121975D02*
Y121982D01*
G01X364942Y121970D02*
X364941Y121975D01*
G01X364943Y121969D02*
X364942Y121970D01*
G01X364941Y126975D02*
Y126982D01*
G01X364942Y126970D02*
X364941Y126975D01*
G01X364943Y126969D02*
X364942Y126970D01*
G01X364941Y131975D02*
Y131982D01*
G01X364942Y131970D02*
X364941Y131975D01*
G01X364943Y131969D02*
X364942Y131970D01*
G01X364941Y136975D02*
Y136982D01*
G01X364942Y136970D02*
X364941Y136975D01*
G01X364943Y136969D02*
X364942Y136970D01*
G01X364941Y141975D02*
Y141982D01*
G01X364942Y141970D02*
X364941Y141975D01*
G01X364943Y141969D02*
X364942Y141970D01*
G01X364941Y146975D02*
Y146982D01*
G01X364942Y146970D02*
X364941Y146975D01*
G01X364943Y146969D02*
X364942Y146970D01*
G01X364941Y151975D02*
Y151982D01*
G01X364942Y151970D02*
X364941Y151975D01*
G01X364943Y151969D02*
X364942Y151970D01*
G01X364941Y156975D02*
Y156982D01*
G01X364942Y156970D02*
X364941Y156975D01*
G01X364943Y156969D02*
X364942Y156970D01*
G01X364941Y161975D02*
Y161982D01*
G01X364942Y161970D02*
X364941Y161975D01*
G01X364943Y161969D02*
X364942Y161970D01*
G01X364941Y166975D02*
Y166982D01*
G01X364942Y166970D02*
X364941Y166975D01*
G01X364943Y166969D02*
X364942Y166970D01*
G01X364941Y171975D02*
Y171982D01*
G01X364942Y171970D02*
X364941Y171975D01*
G01X364943Y171969D02*
X364942Y171970D01*
G01X364941Y176975D02*
Y176982D01*
G01X364942Y176970D02*
X364941Y176975D01*
G01X364943Y176969D02*
X364942Y176970D01*
G01X350554Y96380D02*
X350569Y96378D01*
G01X350543Y96388D02*
X350554Y96380D01*
G01X350531Y96406D02*
X350543Y96388D01*
G01X350554Y99530D02*
X350569Y99528D01*
G01X350542Y99538D02*
X350554Y99530D01*
G01X350530Y99558D02*
X350542Y99538D01*
G01X351516Y96411D02*
Y96404D01*
G01X351515Y96416D02*
X351516Y96411D01*
G01X351514Y96417D02*
X351515Y96416D01*
G01X351516Y99561D02*
Y99553D01*
G01X351515Y99565D02*
X351516Y99561D01*
G01X351514Y99567D02*
X351515Y99565D01*
G01X351516Y102711D02*
Y102703D01*
G01X351515Y102715D02*
X351516Y102711D01*
G01X351514Y102717D02*
X351515Y102715D01*
G01X350554Y102680D02*
X350569Y102677D01*
G01X350541Y102688D02*
X350554Y102680D01*
G01X350530Y102708D02*
X350541Y102688D01*
G01X351515Y94390D02*
X351516Y94383D01*
G01X351513Y94396D02*
X351515Y94390D01*
G01X351510Y94402D02*
X351513Y94396D01*
G01X351515Y97540D02*
X351516Y97533D01*
G01X351513Y97546D02*
X351515Y97540D01*
G01X351510Y97552D02*
X351513Y97546D01*
G01X351515Y100689D02*
X351516Y100683D01*
G01X351513Y100696D02*
X351515Y100689D01*
G01X351510Y100702D02*
X351513Y100696D01*
G01X351515Y103839D02*
X351516Y103832D01*
G01X351513Y103845D02*
X351515Y103839D01*
G01X351510Y103851D02*
X351513Y103845D01*
G01X351477Y96373D02*
Y96367D01*
G01X351476Y96376D02*
X351477Y96373D01*
G01X351475Y96378D02*
X351476Y96376D01*
G01X351477Y102672D02*
Y102666D01*
G01X351476Y102676D02*
X351477Y102672D01*
G01X351475Y102677D02*
X351476Y102676D01*
G01X363957Y107015D02*
Y107024D01*
G01Y107009D02*
Y107015D01*
G01X363958Y107008D02*
X363957Y107009D01*
G01Y112015D02*
Y112024D01*
G01Y112009D02*
Y112015D01*
G01X363958Y112008D02*
X363957Y112009D01*
G01Y117015D02*
Y117024D01*
G01Y117009D02*
Y117015D01*
G01X363958Y117008D02*
X363957Y117009D01*
G01Y122015D02*
Y122024D01*
G01Y122009D02*
Y122015D01*
G01X363958Y122008D02*
X363957Y122009D01*
G01X364933Y107152D02*
X364941Y107125D01*
G01X364923Y107178D02*
X364933Y107152D01*
G01X364912Y107205D02*
X364923Y107178D01*
G01X364933Y112152D02*
X364941Y112125D01*
G01X364923Y112178D02*
X364933Y112152D01*
G01X364912Y112205D02*
X364923Y112178D01*
G01X351485Y94408D02*
X351495Y94404D01*
G01X351475Y94409D02*
X351485Y94408D01*
G01Y97557D02*
X351495Y97554D01*
G01X351475Y97559D02*
X351485Y97557D01*
G01Y100707D02*
X351495Y100703D01*
G01X351475Y100709D02*
X351485Y100707D01*
G01Y103857D02*
X351495Y103853D01*
G01X351475Y103858D02*
X351485Y103857D01*
G01X364928Y116999D02*
X364939Y116984D01*
G01X364904Y117008D02*
X364928Y116999D01*
G01Y121999D02*
X364939Y121984D01*
G01X364904Y122008D02*
X364928Y121999D01*
G01Y126999D02*
X364939Y126984D01*
G01X364904Y127008D02*
X364928Y126999D01*
G01Y131999D02*
X364939Y131984D01*
G01X364904Y132008D02*
X364928Y131999D01*
G01Y136999D02*
X364939Y136984D01*
G01X364904Y137008D02*
X364928Y136999D01*
G01Y141999D02*
X364939Y141984D01*
G01X364904Y142008D02*
X364928Y141999D01*
G01Y146999D02*
X364939Y146984D01*
G01X364904Y147008D02*
X364928Y146999D01*
G01Y151999D02*
X364939Y151984D01*
G01X364904Y152008D02*
X364928Y151999D01*
G01Y156999D02*
X364939Y156984D01*
G01X364904Y157008D02*
X364928Y156999D01*
G01Y161999D02*
X364939Y161984D01*
G01X364904Y162008D02*
X364928Y161999D01*
G01Y166999D02*
X364939Y166984D01*
G01X364904Y167008D02*
X364928Y166999D01*
G01Y171999D02*
X364939Y171984D01*
G01X364904Y172008D02*
X364928Y171999D01*
G01Y176999D02*
X364939Y176984D01*
G01X364904Y177008D02*
X364928Y176999D01*
G01X363957Y127015D02*
Y127024D01*
G01Y127009D02*
Y127015D01*
G01X363958Y127008D02*
X363957Y127009D01*
G01Y132015D02*
Y132024D01*
G01Y132009D02*
Y132015D01*
G01X363958Y132008D02*
X363957Y132009D01*
G01Y137015D02*
Y137024D01*
G01Y137009D02*
Y137015D01*
G01X363958Y137008D02*
X363957Y137009D01*
G01Y142015D02*
Y142024D01*
G01Y142009D02*
Y142015D01*
G01X363958Y142008D02*
X363957Y142009D01*
G01Y147015D02*
Y147024D01*
G01Y147009D02*
Y147015D01*
G01X363958Y147008D02*
X363957Y147009D01*
G01Y152015D02*
Y152024D01*
G01Y152009D02*
Y152015D01*
G01X363958Y152008D02*
X363957Y152009D01*
G01Y157015D02*
Y157024D01*
G01Y157009D02*
Y157015D01*
G01X363958Y157008D02*
X363957Y157009D01*
G01Y162015D02*
Y162024D01*
G01Y162009D02*
Y162015D01*
G01X363958Y162008D02*
X363957Y162009D01*
G01Y167015D02*
Y167024D01*
G01Y167009D02*
Y167015D01*
G01X363958Y167008D02*
X363957Y167009D01*
G01Y172015D02*
Y172024D01*
G01Y172009D02*
Y172015D01*
G01X363958Y172008D02*
X363957Y172009D01*
G01Y177015D02*
Y177024D01*
G01Y177009D02*
Y177015D01*
G01X363958Y177008D02*
X363957Y177009D01*
G01X364933Y117152D02*
X364941Y117125D01*
G01X364923Y117178D02*
X364933Y117152D01*
G01X364912Y117205D02*
X364923Y117178D01*
G01X364933Y122152D02*
X364941Y122125D01*
G01X364923Y122178D02*
X364933Y122152D01*
G01X364912Y122205D02*
X364923Y122178D01*
G01X364933Y127152D02*
X364941Y127125D01*
G01X364923Y127178D02*
X364933Y127152D01*
G01X364912Y127205D02*
X364923Y127178D01*
G01X364933Y132152D02*
X364941Y132125D01*
G01X364923Y132178D02*
X364933Y132152D01*
G01X364912Y132205D02*
X364923Y132178D01*
G01X364933Y137152D02*
X364941Y137125D01*
G01X364923Y137178D02*
X364933Y137152D01*
G01X364912Y137205D02*
X364923Y137178D01*
G01X364933Y142152D02*
X364941Y142125D01*
G01X364923Y142178D02*
X364933Y142152D01*
G01X364912Y142205D02*
X364923Y142178D01*
G01X364933Y147152D02*
X364941Y147125D01*
G01X364923Y147178D02*
X364933Y147152D01*
G01X364912Y147205D02*
X364923Y147178D01*
G01X364933Y152152D02*
X364941Y152125D01*
G01X364923Y152178D02*
X364933Y152152D01*
G01X364912Y152205D02*
X364923Y152178D01*
G01X364933Y157152D02*
X364941Y157125D01*
G01X364923Y157178D02*
X364933Y157152D01*
G01X364912Y157205D02*
X364923Y157178D01*
G01X364933Y162152D02*
X364941Y162125D01*
G01X364923Y162178D02*
X364933Y162152D01*
G01X364912Y162205D02*
X364923Y162178D01*
G01X364933Y167152D02*
X364941Y167125D01*
G01X364923Y167178D02*
X364933Y167152D01*
G01X364912Y167205D02*
X364923Y167178D01*
G01X364933Y172152D02*
X364941Y172125D01*
G01X364923Y172178D02*
X364933Y172152D01*
G01X364912Y172205D02*
X364923Y172178D01*
G01X364933Y177152D02*
X364941Y177125D01*
G01X364923Y177178D02*
X364933Y177152D01*
G01X364912Y177205D02*
X364923Y177178D01*
G01X364924Y107003D02*
X364904Y107008D01*
G01X364938Y106988D02*
X364924Y107003D01*
G01X364943Y106969D02*
X364938Y106988D01*
G01X364924Y112003D02*
X364904Y112008D01*
G01X364938Y111988D02*
X364924Y112003D01*
G01X364943Y111969D02*
X364938Y111988D01*
G01X364924Y117003D02*
X364904Y117008D01*
G01X364938Y116988D02*
X364924Y117003D01*
G01X364943Y116969D02*
X364938Y116988D01*
G01X364924Y122003D02*
X364904Y122008D01*
G01X364938Y121988D02*
X364924Y122003D01*
G01X364943Y121969D02*
X364938Y121988D01*
G01X364924Y127003D02*
X364904Y127008D01*
G01X364938Y126988D02*
X364924Y127003D01*
G01X364943Y126969D02*
X364938Y126988D01*
G01X364924Y132003D02*
X364904Y132008D01*
G01X364938Y131988D02*
X364924Y132003D01*
G01X364943Y131969D02*
X364938Y131988D01*
G01X364924Y137003D02*
X364904Y137008D01*
G01X364938Y136988D02*
X364924Y137003D01*
G01X364943Y136969D02*
X364938Y136988D01*
G01X364924Y142003D02*
X364904Y142008D01*
G01X364938Y141988D02*
X364924Y142003D01*
G01X364943Y141969D02*
X364938Y141988D01*
G01X364924Y147003D02*
X364904Y147008D01*
G01X364938Y146988D02*
X364924Y147003D01*
G01X364943Y146969D02*
X364938Y146988D01*
G01X364924Y152003D02*
X364904Y152008D01*
G01X364938Y151988D02*
X364924Y152003D01*
G01X364943Y151969D02*
X364938Y151988D01*
G01X364924Y157003D02*
X364904Y157008D01*
G01X364938Y156988D02*
X364924Y157003D01*
G01X364943Y156969D02*
X364938Y156988D01*
G01X364924Y162003D02*
X364904Y162008D01*
G01X364938Y161988D02*
X364924Y162003D01*
G01X364943Y161969D02*
X364938Y161988D01*
G01X364924Y167003D02*
X364904Y167008D01*
G01X364938Y166988D02*
X364924Y167003D01*
G01X364943Y166969D02*
X364938Y166988D01*
G01X364924Y172003D02*
X364904Y172008D01*
G01X364938Y171988D02*
X364924Y172003D01*
G01X364943Y171969D02*
X364938Y171988D01*
G01X364924Y177003D02*
X364904Y177008D01*
G01X364938Y176988D02*
X364924Y177003D01*
G01X364943Y176969D02*
X364938Y176988D01*
G01X364908Y107106D02*
X364912Y107205D01*
G01X364902Y107034D02*
X364908Y107106D01*
G01X364904Y107008D02*
X364902Y107034D01*
G01X349784Y96417D02*
X349350D01*
G01X350158D02*
X349784D01*
G01X351506Y94408D02*
X351510Y94402D01*
G01X351502Y94412D02*
X351506Y94408D01*
G01X351496Y94416D02*
X351502Y94412D01*
G01X351490Y94419D02*
X351496Y94416D01*
G01X351483Y94420D02*
X351490Y94419D01*
G01X351476Y94420D02*
X351483D01*
G01X351506Y97557D02*
X351510Y97552D01*
G01X351502Y97562D02*
X351506Y97557D01*
G01X351496Y97565D02*
X351502Y97562D01*
G01X351490Y97568D02*
X351496Y97565D01*
G01X351483Y97570D02*
X351490Y97568D01*
G01X351476Y97570D02*
X351483D01*
G01X351506Y100707D02*
X351510Y100702D01*
G01X351502Y100711D02*
X351506Y100707D01*
G01X351496Y100715D02*
X351502Y100711D01*
G01X351490Y100718D02*
X351496Y100715D01*
G01X351483Y100719D02*
X351490Y100718D01*
G01X351476Y100720D02*
X351483Y100719D01*
G01X351506Y103857D02*
X351510Y103851D01*
G01X351502Y103861D02*
X351506Y103857D01*
G01X351496Y103865D02*
X351502Y103861D01*
G01X351490Y103867D02*
X351496Y103865D01*
G01X351483Y103869D02*
X351490Y103867D01*
G01X351476Y103869D02*
X351483D01*
G01X350532Y96396D02*
X350531Y96404D01*
G01X350535Y96389D02*
X350532Y96396D01*
G01X350538Y96383D02*
X350535Y96389D01*
G01X350543Y96378D02*
X350538Y96383D01*
G01X350549Y96373D02*
X350543Y96378D01*
G01X350556Y96369D02*
X350549Y96373D01*
G01X350563Y96367D02*
X350556Y96369D01*
G01X350571Y96367D02*
X350563D01*
G01X350532Y99546D02*
X350531Y99553D01*
G01X350535Y99539D02*
X350532Y99546D01*
G01X350538Y99533D02*
X350535Y99539D01*
G01X350543Y99527D02*
X350538Y99533D01*
G01X350549Y99522D02*
X350543Y99527D01*
G01X350556Y99519D02*
X350549Y99522D01*
G01X350563Y99517D02*
X350556Y99519D01*
G01X350571Y99516D02*
X350563Y99517D01*
G01X350532Y102696D02*
X350531Y102703D01*
G01X350535Y102689D02*
X350532Y102696D01*
G01X350538Y102682D02*
X350535Y102689D01*
G01X350543Y102677D02*
X350538Y102682D01*
G01X350549Y102672D02*
X350543Y102677D01*
G01X350556Y102669D02*
X350549Y102672D01*
G01X350563Y102667D02*
X350556Y102669D01*
G01X350571Y102666D02*
X350563Y102667D01*
G01X351508Y94391D02*
X351501Y94400D01*
G01X351513Y94381D02*
X351508Y94391D01*
G01X351515Y94370D02*
X351513Y94381D01*
G01X351508Y97541D02*
X351501Y97549D01*
G01X351513Y97531D02*
X351508Y97541D01*
G01X351515Y97520D02*
X351513Y97531D01*
G01X351508Y100691D02*
X351501Y100699D01*
G01X351513Y100680D02*
X351508Y100691D01*
G01X351515Y100669D02*
X351513Y100680D01*
G01X351508Y103840D02*
X351501Y103848D01*
G01X351513Y103830D02*
X351508Y103840D01*
G01X351515Y103819D02*
X351513Y103830D01*
G01X364908Y112106D02*
X364912Y112205D01*
G01X364902Y112034D02*
X364908Y112106D01*
G01X364904Y112008D02*
X364902Y112034D01*
G01X364908Y117106D02*
X364912Y117205D01*
G01X364902Y117034D02*
X364908Y117106D01*
G01X364904Y117008D02*
X364902Y117034D01*
G01X364908Y122106D02*
X364912Y122205D01*
G01X364902Y122034D02*
X364908Y122106D01*
G01X364904Y122008D02*
X364902Y122034D01*
G01X364908Y127106D02*
X364912Y127205D01*
G01X364902Y127034D02*
X364908Y127106D01*
G01X364904Y127008D02*
X364902Y127034D01*
G01X364908Y132106D02*
X364912Y132205D01*
G01X364902Y132034D02*
X364908Y132106D01*
G01X364904Y132008D02*
X364902Y132034D01*
G01X364908Y137106D02*
X364912Y137205D01*
G01X364902Y137034D02*
X364908Y137106D01*
G01X364904Y137008D02*
X364902Y137034D01*
G01X364908Y142106D02*
X364912Y142205D01*
G01X364902Y142034D02*
X364908Y142106D01*
G01X364904Y142008D02*
X364902Y142034D01*
G01X364908Y147106D02*
X364912Y147205D01*
G01X364902Y147034D02*
X364908Y147106D01*
G01X364904Y147008D02*
X364902Y147034D01*
G01X364908Y152106D02*
X364912Y152205D01*
G01X364902Y152034D02*
X364908Y152106D01*
G01X364904Y152008D02*
X364902Y152034D01*
G01X364908Y157106D02*
X364912Y157205D01*
G01X364902Y157034D02*
X364908Y157106D01*
G01X364904Y157008D02*
X364902Y157034D01*
G01X364908Y162106D02*
X364912Y162205D01*
G01X364902Y162034D02*
X364908Y162106D01*
G01X364904Y162008D02*
X364902Y162034D01*
G01X364908Y167106D02*
X364912Y167205D01*
G01X364902Y167034D02*
X364908Y167106D01*
G01X364904Y167008D02*
X364902Y167034D01*
G01X364908Y172106D02*
X364912Y172205D01*
G01X364902Y172034D02*
X364908Y172106D01*
G01X364904Y172008D02*
X364902Y172034D01*
G01X364908Y177106D02*
X364912Y177205D01*
G01X364902Y177034D02*
X364908Y177106D01*
G01X364904Y177008D02*
X364902Y177034D01*
G01X350531Y96411D02*
Y96404D01*
G01X350530Y96416D02*
X350531Y96411D01*
G01Y96406D02*
X350530Y96416D01*
G01X350572Y104043D02*
X350571Y104055D01*
G01X350569Y104030D02*
X350572Y104043D01*
G01X350569Y104016D02*
Y104030D01*
G01X350572Y100893D02*
X350571Y100906D01*
G01X350569Y100880D02*
X350572Y100893D01*
G01X350569Y100866D02*
Y100880D01*
G01X350572Y97743D02*
X350571Y97756D01*
G01X350569Y97730D02*
X350572Y97743D01*
G01X350569Y97717D02*
Y97730D01*
G01X350572Y94594D02*
X350571Y94606D01*
G01X350569Y94581D02*
X350572Y94594D01*
G01X350569Y94567D02*
Y94581D01*
G01X363957Y175628D02*
X363958Y175630D01*
G01X363957Y175622D02*
Y175628D01*
G01Y175614D02*
Y175622D01*
G01Y170628D02*
X363958Y170630D01*
G01X363957Y170622D02*
Y170628D01*
G01Y170614D02*
Y170622D01*
G01Y165628D02*
X363958Y165630D01*
G01X363957Y165622D02*
Y165628D01*
G01Y165614D02*
Y165622D01*
G01Y160628D02*
X363958Y160630D01*
G01X363957Y160622D02*
Y160628D01*
G01Y160614D02*
Y160622D01*
G01Y155628D02*
X363958Y155630D01*
G01X363957Y155622D02*
Y155628D01*
G01Y155614D02*
Y155622D01*
G01Y150628D02*
X363958Y150630D01*
G01X363957Y150622D02*
Y150628D01*
G01Y150614D02*
Y150622D01*
G01Y145628D02*
X363958Y145630D01*
G01X363957Y145622D02*
Y145628D01*
G01Y145614D02*
Y145622D01*
G01Y140628D02*
X363958Y140630D01*
G01X363957Y140622D02*
Y140628D01*
G01Y140614D02*
Y140622D01*
G01Y135628D02*
X363958Y135630D01*
G01X363957Y135622D02*
Y135628D01*
G01Y135614D02*
Y135622D01*
G01Y130628D02*
X363958Y130630D01*
G01X363957Y130622D02*
Y130628D01*
G01Y130614D02*
Y130622D01*
G01Y125628D02*
X363958Y125630D01*
G01X363957Y125622D02*
Y125628D01*
G01Y125614D02*
Y125622D01*
G01Y120628D02*
X363958Y120630D01*
G01X363957Y120622D02*
Y120628D01*
G01Y120614D02*
Y120622D01*
G01Y115628D02*
X363958Y115630D01*
G01X363957Y115622D02*
Y115628D01*
G01Y115614D02*
Y115622D01*
G01Y110628D02*
X363958Y110630D01*
G01X363957Y110622D02*
Y110628D01*
G01Y110614D02*
Y110622D01*
G01Y105628D02*
X363958Y105630D01*
G01X363957Y105622D02*
Y105628D01*
G01Y105614D02*
Y105622D01*
G01X350531Y102711D02*
Y102703D01*
G01X350530Y102715D02*
X350531Y102711D01*
G01X350530Y102707D02*
Y102715D01*
G01X350569Y102506D02*
X350567Y102519D01*
G01X350572Y102493D02*
X350569Y102506D01*
G01X350571Y102480D02*
X350572Y102493D01*
G01X350569Y99356D02*
X350567Y99370D01*
G01X350572Y99343D02*
X350569Y99356D01*
G01X350571Y99331D02*
X350572Y99343D01*
G01X350569Y96206D02*
X350567Y96220D01*
G01X350572Y96194D02*
X350569Y96206D01*
G01X350571Y96181D02*
X350572Y96194D01*
G01X351479Y104030D02*
X351480Y104016D01*
G01X351476Y104043D02*
X351479Y104030D01*
G01X351476Y104055D02*
Y104043D01*
G01X351479Y100880D02*
X351480Y100866D01*
G01X351476Y100893D02*
X351479Y100880D01*
G01X351476Y100906D02*
Y100893D01*
G01X351479Y97730D02*
X351480Y97717D01*
G01X351476Y97743D02*
X351479Y97730D01*
G01X351476Y97756D02*
Y97743D01*
G01X351479Y94581D02*
X351480Y94567D01*
G01X351476Y94594D02*
X351479Y94581D01*
G01X351476Y94606D02*
Y94594D01*
G01X350531Y99561D02*
Y99554D01*
G01X350530Y99565D02*
X350531Y99561D01*
G01X350530Y99558D02*
Y99565D01*
G01X351515Y99546D02*
X351516Y99553D01*
G01X351513Y99539D02*
X351515Y99546D01*
G01X351509Y99533D02*
X351513Y99539D01*
G01X351504Y99527D02*
X351509Y99533D01*
G01X351498Y99522D02*
X351504Y99527D01*
G01X351491Y99519D02*
X351498Y99522D01*
G01X351484Y99517D02*
X351491Y99519D01*
G01X351476Y99516D02*
X351484Y99517D01*
G01X350554Y94417D02*
X350551Y94415D01*
G01X350557Y94418D02*
X350554Y94417D01*
G01X350561Y94419D02*
X350557Y94418D01*
G01X350564Y94420D02*
X350561Y94419D01*
G01X350567Y94420D02*
X350564D01*
G01X350571D02*
X350567D01*
G01X351493Y96370D02*
X351496Y96372D01*
G01X351490Y96369D02*
X351493Y96370D01*
G01X351487Y96368D02*
X351490Y96369D01*
G01X351483Y96367D02*
X351487Y96368D01*
G01X351480Y96367D02*
X351483D01*
G01X351476D02*
X351480D01*
G01X350554Y97567D02*
X350551Y97565D01*
G01X350557Y97568D02*
X350554Y97567D01*
G01X350561Y97569D02*
X350557Y97568D01*
G01X350564Y97570D02*
X350561Y97569D01*
G01X350567Y97570D02*
X350564D01*
G01X350571D02*
X350567D01*
G01X350554Y100716D02*
X350551Y100715D01*
G01X350557Y100717D02*
X350554Y100716D01*
G01X350561Y100719D02*
X350557Y100717D01*
G01X350564Y100719D02*
X350561D01*
G01X350567Y100720D02*
X350564Y100719D01*
G01X350571Y100720D02*
X350567D01*
G01X351493Y102669D02*
X351496Y102671D01*
G01X351490Y102668D02*
X351493Y102669D01*
G01X351487Y102667D02*
X351490Y102668D01*
G01X351483Y102667D02*
X351487D01*
G01X351480Y102666D02*
X351483Y102667D01*
G01X351476Y102666D02*
X351480D01*
G01X350554Y103866D02*
X350551Y103864D01*
G01X350557Y103867D02*
X350554Y103866D01*
G01X350561Y103868D02*
X350557Y103867D01*
G01X350564Y103869D02*
X350561Y103868D01*
G01X350567Y103869D02*
X350564D01*
G01X350571D02*
X350567D01*
G01X351476Y102493D02*
Y102480D01*
G01X351478Y102506D02*
X351476Y102493D01*
G01X351480Y102519D02*
X351478Y102506D01*
G01X351476Y99343D02*
Y99331D01*
G01X351478Y99356D02*
X351476Y99343D01*
G01X351480Y99370D02*
X351478Y99356D01*
G01X351476Y96194D02*
Y96181D01*
G01X351478Y96206D02*
X351476Y96194D01*
G01X351480Y96220D02*
X351478Y96206D01*
G01X350534Y94390D02*
X350529Y94370D01*
G01X350549Y94404D02*
X350534Y94390D01*
G01X350569Y94409D02*
X350549Y94404D01*
G01X350534Y97539D02*
X350529Y97520D01*
G01X350549Y97554D02*
X350534Y97539D01*
G01X350569Y97559D02*
X350549Y97554D01*
G01X351509Y96398D02*
X351514Y96417D01*
G01X351494Y96383D02*
X351509Y96398D01*
G01X351475Y96378D02*
X351494Y96383D01*
G01X350544Y103850D02*
X350569Y103858D01*
G01X350533Y103835D02*
X350544Y103850D01*
G01X350531Y103828D02*
X350533Y103835D01*
G01X350544Y100700D02*
X350569Y100709D01*
G01X350533Y100685D02*
X350544Y100700D01*
G01X350531Y100679D02*
X350533Y100685D01*
G01X350544Y97550D02*
X350569Y97559D01*
G01X350533Y97536D02*
X350544Y97550D01*
G01X350531Y97529D02*
X350533Y97536D01*
G01X350544Y94401D02*
X350569Y94409D01*
G01X350533Y94386D02*
X350544Y94401D01*
G01X350531Y94380D02*
X350533Y94386D01*
G01X350534Y100689D02*
X350529Y100669D01*
G01X350549Y100703D02*
X350534Y100689D01*
G01X350569Y100709D02*
X350549Y100703D01*
G01X350534Y103839D02*
X350529Y103819D01*
G01X350549Y103853D02*
X350534Y103839D01*
G01X350569Y103858D02*
X350549Y103853D01*
G01X351509Y99547D02*
X351514Y99567D01*
G01X351494Y99533D02*
X351509Y99547D01*
G01X351475Y99528D02*
X351494Y99533D01*
G01X351509Y102697D02*
X351514Y102717D01*
G01X351494Y102682D02*
X351509Y102697D01*
G01X351475Y102677D02*
X351494Y102682D01*
G01X351516Y103825D02*
Y103832D01*
G01X351515Y103820D02*
X351516Y103825D01*
G01X351515Y103819D02*
Y103820D01*
G01X351516Y100676D02*
Y100683D01*
G01X351515Y100671D02*
X351516Y100676D01*
G01X351515Y100669D02*
Y100671D01*
G01X351516Y97526D02*
Y97533D01*
G01X351515Y97521D02*
X351516Y97526D01*
G01X351515Y97520D02*
Y97521D01*
G01X351516Y94376D02*
Y94383D01*
G01X351515Y94372D02*
X351516Y94376D01*
G01X351515Y94370D02*
Y94372D01*
G01X351476Y103863D02*
Y103869D01*
G01Y103859D02*
Y103863D01*
G01X351475Y103858D02*
X351476Y103859D01*
G01Y100714D02*
Y100720D01*
G01Y100710D02*
Y100714D01*
G01X351475Y100709D02*
X351476Y100710D01*
G01Y97564D02*
Y97570D01*
G01Y97560D02*
Y97564D01*
G01X351475Y97559D02*
X351476Y97560D01*
G01Y94415D02*
Y94420D01*
G01Y94411D02*
Y94415D01*
G01X351475Y94409D02*
X351476Y94411D01*
G01X364941Y175622D02*
Y175613D01*
G01X364942Y175628D02*
X364941Y175622D01*
G01X364944Y175630D02*
X364942Y175628D01*
G01X364941Y170622D02*
Y170613D01*
G01X364942Y170628D02*
X364941Y170622D01*
G01X364944Y170630D02*
X364942Y170628D01*
G01X364941Y165622D02*
Y165613D01*
G01X364942Y165628D02*
X364941Y165622D01*
G01X364944Y165630D02*
X364942Y165628D01*
G01X364941Y160622D02*
Y160613D01*
G01X364942Y160628D02*
X364941Y160622D01*
G01X364944Y160630D02*
X364942Y160628D01*
G01X364941Y155622D02*
Y155613D01*
G01X364942Y155628D02*
X364941Y155622D01*
G01X364944Y155630D02*
X364942Y155628D01*
G01X364941Y150622D02*
Y150613D01*
G01X364942Y150628D02*
X364941Y150622D01*
G01X364944Y150630D02*
X364942Y150628D01*
G01X364941Y145622D02*
Y145613D01*
G01X364942Y145628D02*
X364941Y145622D01*
G01X364944Y145630D02*
X364942Y145628D01*
G01X364941Y140622D02*
Y140613D01*
G01X364942Y140628D02*
X364941Y140622D01*
G01X364944Y140630D02*
X364942Y140628D01*
G01X364941Y135622D02*
Y135613D01*
G01X364942Y135628D02*
X364941Y135622D01*
G01X364944Y135630D02*
X364942Y135628D01*
G01X364941Y130622D02*
Y130613D01*
G01X364942Y130628D02*
X364941Y130622D01*
G01X364944Y130630D02*
X364942Y130628D01*
G01X364941Y125622D02*
Y125613D01*
G01X364942Y125628D02*
X364941Y125622D01*
G01X364944Y125630D02*
X364942Y125628D01*
G01X364941Y120622D02*
Y120613D01*
G01X364942Y120628D02*
X364941Y120622D01*
G01X364944Y120630D02*
X364942Y120628D01*
G01X364941Y115622D02*
Y115613D01*
G01X364942Y115628D02*
X364941Y115622D01*
G01X364944Y115630D02*
X364942Y115628D01*
G01X364941Y110622D02*
Y110613D01*
G01X364942Y110628D02*
X364941Y110622D01*
G01X364944Y110630D02*
X364942Y110628D01*
G01X364941Y105622D02*
Y105613D01*
G01X364942Y105628D02*
X364941Y105622D01*
G01X364944Y105630D02*
X364942Y105628D01*
G01X350531Y103825D02*
Y103832D01*
G01X350530Y103820D02*
X350531Y103825D01*
G01X350529Y103819D02*
X350530Y103820D01*
G01X350531Y100675D02*
Y100683D01*
G01X350530Y100671D02*
X350531Y100675D01*
G01X350529Y100669D02*
X350530Y100671D01*
G01X350531Y97526D02*
Y97533D01*
G01X350530Y97521D02*
X350531Y97526D01*
G01X350529Y97520D02*
X350530Y97521D01*
G01X350531Y94376D02*
Y94383D01*
G01X350530Y94372D02*
X350531Y94376D01*
G01X350529Y94370D02*
X350530Y94372D01*
G01X351513Y102691D02*
X351516Y102703D01*
G01X351507Y102679D02*
X351513Y102691D01*
G01X351496Y102671D02*
X351507Y102679D01*
G01X351513Y96391D02*
X351516Y96404D01*
G01X351507Y96380D02*
X351513Y96391D01*
G01X351496Y96372D02*
X351507Y96380D01*
G01X350570Y103863D02*
Y103869D01*
G01Y103859D02*
Y103863D01*
G01X350569Y103858D02*
X350570Y103859D01*
G01Y100713D02*
Y100720D01*
G01Y100710D02*
Y100713D01*
G01X350569Y100709D02*
X350570Y100710D01*
G01Y97564D02*
Y97570D01*
G01Y97560D02*
Y97564D01*
G01X350569Y97559D02*
X350570Y97560D01*
G01Y94414D02*
Y94420D01*
G01Y94411D02*
Y94414D01*
G01X350569Y94409D02*
X350570Y94411D01*
G01X350532Y103839D02*
X350531Y103832D01*
G01X350534Y103845D02*
X350532Y103839D01*
G01X350537Y103851D02*
X350534Y103845D01*
G01X350541Y103856D02*
X350537Y103851D01*
G01X350545Y103861D02*
X350541Y103856D01*
G01X350551Y103864D02*
X350545Y103861D01*
G01X350532Y100689D02*
X350531Y100683D01*
G01X350534Y100695D02*
X350532Y100689D01*
G01X350537Y100701D02*
X350534Y100695D01*
G01X350541Y100706D02*
X350537Y100701D01*
G01X350545Y100711D02*
X350541Y100706D01*
G01X350551Y100715D02*
X350545Y100711D01*
G01X350532Y97539D02*
X350531Y97533D01*
G01X350534Y97546D02*
X350532Y97539D01*
G01X350537Y97552D02*
X350534Y97546D01*
G01X350541Y97557D02*
X350537Y97552D01*
G01X350545Y97561D02*
X350541Y97557D01*
G01X350551Y97565D02*
X350545Y97561D01*
G01X350532Y94390D02*
X350531Y94383D01*
G01X350534Y94396D02*
X350532Y94390D01*
G01X350537Y94402D02*
X350534Y94396D01*
G01X350541Y94407D02*
X350537Y94402D01*
G01X350545Y94412D02*
X350541Y94407D01*
G01X350551Y94415D02*
X350545Y94412D01*
G01X351487Y102679D02*
X351475Y102677D01*
G01X351497Y102684D02*
X351487Y102679D01*
G01Y99530D02*
X351475Y99528D01*
G01X351497Y99534D02*
X351487Y99530D01*
G01Y96380D02*
X351475Y96378D01*
G01X351497Y96385D02*
X351487Y96380D01*
G01X361339Y188130D02*
G03I-1890J0D01*
G01X361811D02*
G03I-2362J0D01*
G01X364370Y103681D02*
X365551Y104862D01*
G01X360433Y103681D02*
X361614Y104862D01*
G01X370276Y186161D02*
X366929Y182815D01*
G01X360433Y180138D02*
X361614Y181319D01*
G01X356964Y185059D02*
X358268Y187028D01*
G01X362940Y192950D02*
X360630Y188720D01*
G01X358268Y187028D02*
X360630D01*
G01X351969Y185059D02*
X366339D01*
G01X351969Y183681D02*
X355709D01*
G01X366339D02*
X363189D01*
G01X351969Y182815D02*
X366929D01*
G01X353740Y181319D02*
X361614D01*
G01X354921Y180138D02*
X360433D01*
G01X364941Y177500D02*
X363957D01*
G01X363958Y177008D02*
X369291D01*
G01Y176969D02*
X364943D01*
G01X369291Y175630D02*
X363958D01*
G01X363957Y175138D02*
X364941D01*
G01Y172500D02*
X363957D01*
G01X363958Y172008D02*
X369291D01*
G01Y171969D02*
X364943D01*
G01X369291Y170630D02*
X363958D01*
G01X363957Y170138D02*
X364941D01*
G01Y167500D02*
X363957D01*
G01X363958Y167008D02*
X369291D01*
G01Y166969D02*
X364943D01*
G01X369291Y165630D02*
X363958D01*
G01X363957Y165138D02*
X364941D01*
G01Y162500D02*
X363957D01*
G01X363958Y162008D02*
X369291D01*
G01Y161969D02*
X364943D01*
G01X369291Y160630D02*
X363958D01*
G01X363957Y160138D02*
X364941D01*
G01Y157500D02*
X363957D01*
G01X363958Y157008D02*
X369291D01*
G01Y156969D02*
X364943D01*
G01X369291Y155630D02*
X363958D01*
G01X363957Y155138D02*
X364941D01*
G01Y152500D02*
X363957D01*
G01X363958Y152008D02*
X369291D01*
G01Y151969D02*
X364943D01*
G01X369291Y150630D02*
X363958D01*
G01X363957Y150138D02*
X364941D01*
G01Y147500D02*
X363957D01*
G01X363958Y147008D02*
X369291D01*
G01Y146969D02*
X364943D01*
G01X369291Y145630D02*
X363958D01*
G01X363957Y145138D02*
X364941D01*
G01Y142500D02*
X363957D01*
G01X363958Y142008D02*
X369291D01*
G01Y141969D02*
X364943D01*
G01X369291Y140630D02*
X363958D01*
G01X363957Y140138D02*
X364941D01*
G01Y137500D02*
X363957D01*
G01X363958Y137008D02*
X369291D01*
G01Y136969D02*
X364943D01*
G01X369291Y135630D02*
X363958D01*
G01X363957Y135138D02*
X364941D01*
G01Y132500D02*
X363957D01*
G01X363958Y132008D02*
X369291D01*
G01Y131969D02*
X364943D01*
G01X369291Y130630D02*
X363958D01*
G01X363957Y130138D02*
X364941D01*
G01Y127500D02*
X363957D01*
G01X363958Y127008D02*
X369291D01*
G01Y126969D02*
X364943D01*
G01X369291Y125630D02*
X363958D01*
G01X363957Y125138D02*
X364941D01*
G01Y122500D02*
X363957D01*
G01X363958Y122008D02*
X369291D01*
G01Y121969D02*
X364943D01*
G01X369291Y120630D02*
X363958D01*
G01X363957Y120138D02*
X364941D01*
G01Y117500D02*
X363957D01*
G01Y177204D02*
X364912Y177205D01*
G01X364941Y175434D02*
X363957Y175433D01*
G01Y172204D02*
X364912Y172205D01*
G01X364941Y170434D02*
X363957Y170433D01*
G01Y167204D02*
X364912Y167205D01*
G01X364941Y165434D02*
X363957Y165433D01*
G01Y162204D02*
X364912Y162205D01*
G01X364941Y160434D02*
X363957Y160433D01*
G01Y157204D02*
X364912Y157205D01*
G01X364941Y155434D02*
X363957Y155433D01*
G01Y152204D02*
X364912Y152205D01*
G01X364941Y150434D02*
X363957Y150433D01*
G01Y147204D02*
X364912Y147205D01*
G01X364941Y145434D02*
X363957Y145433D01*
G01Y142204D02*
X364912Y142205D01*
G01X364941Y140434D02*
X363957Y140433D01*
G01Y137204D02*
X364912Y137205D01*
G01X364941Y135434D02*
X363957Y135433D01*
G01Y132204D02*
X364912Y132205D01*
G01X364941Y130434D02*
X363957Y130433D01*
G01Y127204D02*
X364912Y127205D01*
G01X364941Y125434D02*
X363957Y125433D01*
G01Y122204D02*
X364912Y122205D01*
G01X364941Y120434D02*
X363957Y120433D01*
G01Y117204D02*
X364912Y117205D01*
G01X351515Y94372D02*
X351516Y94383D01*
G01X351515Y97522D02*
X351516Y97533D01*
G01X351515Y100671D02*
X351516Y100683D01*
G01X351515Y103821D02*
X351516Y103832D01*
G01X364941Y106982D02*
Y106991D01*
G01Y111982D02*
Y111991D01*
G01Y116982D02*
Y116991D01*
G01Y121982D02*
Y121991D01*
G01Y126982D02*
Y126991D01*
G01Y131982D02*
Y131991D01*
G01Y136982D02*
Y136991D01*
G01Y141982D02*
Y141991D01*
G01Y146982D02*
Y146991D01*
G01Y151982D02*
Y151991D01*
G01Y156982D02*
Y156991D01*
G01Y161982D02*
Y161991D01*
G01Y166982D02*
Y166991D01*
G01Y171982D02*
Y171991D01*
G01Y176982D02*
Y176991D01*
G01X370276Y186161D02*
Y201909D01*
G01X369291Y175630D02*
Y177008D01*
G01Y170630D02*
Y172008D01*
G01Y165630D02*
Y167008D01*
G01Y160630D02*
Y162008D01*
G01Y155630D02*
Y157008D01*
G01Y150630D02*
Y152008D01*
G01Y145630D02*
Y147008D01*
G01Y140630D02*
Y142008D01*
G01Y135630D02*
Y137008D01*
G01Y130630D02*
Y132008D01*
G01Y125630D02*
Y127008D01*
G01Y120630D02*
Y122008D01*
G01Y115630D02*
Y117008D01*
G01Y110630D02*
Y112008D01*
G01Y105630D02*
Y107008D01*
G01X366122D02*
Y105630D01*
G01Y112008D02*
Y110630D01*
G01Y117008D02*
Y115630D01*
G01Y122008D02*
Y120630D01*
G01Y127008D02*
Y125630D01*
G01Y132008D02*
Y130630D01*
G01Y137008D02*
Y135630D01*
G01Y142008D02*
Y140630D01*
G01Y147008D02*
Y145630D01*
G01Y152008D02*
Y150630D01*
G01Y157008D02*
Y155630D01*
G01Y162008D02*
Y160630D01*
G01Y167008D02*
Y165630D01*
G01Y172008D02*
Y170630D01*
G01Y177008D02*
Y175630D01*
G01X364941Y106982D02*
Y107125D01*
G01Y116982D02*
Y117125D01*
G01Y111982D02*
Y112125D01*
G01Y121982D02*
Y122125D01*
G01Y131982D02*
Y132125D01*
G01Y126982D02*
Y127125D01*
G01Y141982D02*
Y142125D01*
G01Y136982D02*
Y137125D01*
G01Y151982D02*
Y152125D01*
G01Y146982D02*
Y147125D01*
G01Y161982D02*
Y162125D01*
G01Y156982D02*
Y157125D01*
G01Y171982D02*
Y172125D01*
G01Y166982D02*
Y167125D01*
G01Y176982D02*
Y177125D01*
G01Y175138D02*
Y177500D01*
G01Y170138D02*
Y172500D01*
G01Y165138D02*
Y167500D01*
G01Y160138D02*
Y162500D01*
G01Y155138D02*
Y157500D01*
G01Y150138D02*
Y152500D01*
G01Y145138D02*
Y147500D01*
G01Y140138D02*
Y142500D01*
G01Y135138D02*
Y137500D01*
G01Y130138D02*
Y132500D01*
G01Y125138D02*
Y127500D01*
G01Y120138D02*
Y122500D01*
G01Y115138D02*
Y117500D01*
G01Y110138D02*
Y112500D01*
G01Y105138D02*
Y107500D01*
G01X363957D02*
Y105138D01*
G01Y112500D02*
Y110138D01*
G01Y117500D02*
Y115138D01*
G01Y122500D02*
Y120138D01*
G01Y127500D02*
Y125138D01*
G01Y132500D02*
Y130138D01*
G01Y137500D02*
Y135138D01*
G01Y142500D02*
Y140138D01*
G01Y147500D02*
Y145138D01*
G01Y152500D02*
Y150138D01*
G01Y157500D02*
Y155138D01*
G01Y162500D02*
Y160138D01*
G01Y167500D02*
Y165138D01*
G01Y172500D02*
Y170138D01*
G01Y177500D02*
Y175138D01*
G01X363189Y192224D02*
Y183681D01*
G01X361614Y181319D02*
Y104862D01*
G01X360630Y188720D02*
Y187028D01*
G01X360433Y180138D02*
Y103681D01*
G01X358268Y187028D02*
Y188720D01*
G01X355709Y183681D02*
Y192224D01*
G01X351969Y185059D02*
Y106024D01*
G01X351516Y102519D02*
Y104016D01*
G01Y99370D02*
Y100866D01*
G01Y96220D02*
Y97717D01*
G01X351476Y96367D02*
Y96220D01*
G01Y94567D02*
Y94420D01*
G01Y99516D02*
Y99369D01*
G01Y100867D02*
Y100720D01*
G01Y97717D02*
Y97570D01*
G01Y102666D02*
Y102519D01*
G01Y104016D02*
Y103869D01*
G01X350571Y102519D02*
Y102666D01*
G01Y103869D02*
Y104016D01*
G01Y99369D02*
Y99516D01*
G01Y100720D02*
Y100867D01*
G01Y97570D02*
Y97717D01*
G01Y96220D02*
Y96367D01*
G01Y94420D02*
Y94567D01*
G01X350531Y100866D02*
Y99370D01*
G01Y97717D02*
Y96220D01*
G01Y104016D02*
Y102520D01*
G01X349350Y97559D02*
Y96378D01*
G01Y100709D02*
Y99528D01*
G01Y103858D02*
Y102677D01*
G01X348622Y201909D02*
Y186161D01*
G01X345591Y102677D02*
Y103858D01*
G01Y99528D02*
Y100709D01*
G01Y96378D02*
Y97559D01*
G01X351516Y102703D02*
X351515Y102714D01*
G01X351516Y99554D02*
X351515Y99564D01*
G01X351516Y96404D02*
X351515Y96415D01*
G01X350418Y102717D02*
X350530Y102708D01*
G01X350529Y96414D02*
X350418Y96417D01*
G01X363958Y117008D02*
X369291D01*
G01Y116969D02*
X364943D01*
G01X369291Y115630D02*
X363958D01*
G01X363957Y115138D02*
X364941D01*
G01Y112500D02*
X363957D01*
G01X363958Y112008D02*
X369291D01*
G01Y111969D02*
X364943D01*
G01X369291Y110630D02*
X363958D01*
G01X363957Y110138D02*
X364941D01*
G01Y107500D02*
X363957D01*
G01X363958Y107008D02*
X369291D01*
G01Y106969D02*
X364943D01*
G01X351969Y106024D02*
X348622D01*
G01X369291Y105630D02*
X363958D01*
G01X363957Y105138D02*
X364941D01*
G01X361614Y104862D02*
X365551D01*
G01X351476Y104055D02*
X350571D01*
G01X351516Y104016D02*
X350531D01*
G01X351475Y103858D02*
X345591D01*
G01Y103819D02*
X351515D01*
G01X360433Y103681D02*
X364370D01*
G01X351514Y102717D02*
X345591D01*
G01X351475Y102677D02*
X345591D01*
G01X350531Y102520D02*
X351516D01*
G01X350571Y102480D02*
X351476D01*
G01Y100906D02*
X350571D01*
G01X351516Y100866D02*
X350531D01*
G01X351475Y100709D02*
X345591D01*
G01Y100669D02*
X351515D01*
G01X351514Y99567D02*
X345591D01*
G01X351475Y99528D02*
X345591D01*
G01X350531Y99370D02*
X351516D01*
G01X350571Y99331D02*
X351476D01*
G01Y97756D02*
X350571D01*
G01X351516Y97717D02*
X350531D01*
G01X351475Y97559D02*
X345591D01*
G01Y97520D02*
X351515D01*
G01X351514Y96417D02*
X345591D01*
G01X351475Y96378D02*
X345591D01*
G01X350531Y96220D02*
X351516D01*
G01X350571Y96181D02*
X351476D01*
G01Y94606D02*
X350571D01*
G01X351516Y94567D02*
X350531D01*
G01X351475Y94409D02*
X345591D01*
G01Y94370D02*
X351515D01*
G01X364941Y115434D02*
X363957Y115433D01*
G01Y112204D02*
X364912Y112205D01*
G01X364941Y110434D02*
X363957Y110433D01*
G01Y107204D02*
X364912Y107205D01*
G01X364941Y105434D02*
X363957Y105433D01*
G01X351475Y99528D02*
X351478Y99516D01*
G01X358268Y188720D02*
X355957Y192950D01*
G01X360630Y187028D02*
X361933Y185059D01*
G01X353740Y181319D02*
X354921Y180138D01*
G01X348622Y186161D02*
X351969Y182815D01*
G01X362327Y264712D02*
G03X396138I16905J-13531D01*
G01X389213Y277843D02*
G03X369252I-9981J-3040D01*
G01X362327Y264712D02*
G03X369252Y277843I-30737J24602D01*
G01X389213D02*
G03X369252I-9981J-3040D01*
G01X362327Y264712D02*
G03X396138I16905J-13531D01*
G01X370276Y201909D02*
G03X368307Y203878I-1969J0D01*
G01X319488Y260630D02*
G03X320669I590J0D01*
G01Y254331D02*
G03X319488I-591J0D01*
G01X317520D02*
G03X316339I-590J0D01*
G01Y260630D02*
G03X317520I590J0D01*
G01X319488D02*
G03X320669I590J0D01*
G01Y254331D02*
G03X319488I-591J0D01*
G01X317520D02*
G03X316339I-590J0D01*
G01Y260630D02*
G03X317520I590J0D01*
G01X362327Y264712D02*
G03X369252Y277843I-30737J24602D01*
G01X363386Y202500D02*
G03X362795Y203091I-591J0D01*
G01X356102D02*
G03X355512Y202500I1J-591D01*
G01X358268Y201319D02*
G03Y199350I0J-985D01*
G01X360630D02*
G03Y201319I0J984D01*
G01X356890Y193406D02*
G03X355709Y192224I0J-1181D01*
G01X363189D02*
G03X362008Y193406I-1181J1D01*
G01X350591Y203878D02*
G03X348622Y201909I0J-1969D01*
G01X316339Y260630D02*
X315551D01*
G01X316339D02*
X315551D01*
G01X319488D02*
X317520D01*
G01X319488D02*
X317520D01*
G01X321457D02*
X320669D01*
G01X321457D02*
X320669D01*
G01X321457Y259646D02*
X315551D01*
G01Y259449D02*
X321457D01*
G01X315551Y255512D02*
X321457D01*
G01Y255315D02*
X315551D01*
G01X320669Y254331D02*
X321457D01*
G01X320669D02*
X321457D01*
G01X317520D02*
X319488D01*
G01X317520D02*
X319488D01*
G01X315551D02*
X316339D01*
G01X315551D02*
X316339D01*
G01X368307Y203878D02*
X350591D01*
G01X362795Y203091D02*
X356102D01*
G01X360630Y201319D02*
X358268D01*
G01Y199350D02*
X360630D01*
G01X363386Y197972D02*
X355512D01*
G01Y196398D02*
X363386D01*
G01X370276Y193445D02*
X348622D01*
G01X356890Y193406D02*
X362008D01*
G01X358268Y188720D02*
X360630D01*
G01X363386Y196398D02*
Y202500D01*
G01X355512Y196398D02*
Y202500D01*
G01X321457Y254331D02*
Y260630D01*
G01Y254331D02*
Y260630D01*
G01X315551Y254331D02*
Y260630D01*
G01D02*
Y254331D01*
G01X351516Y536569D02*
Y536561D01*
G01X351515Y536573D02*
X351516Y536569D01*
G01X351514Y536575D02*
X351515Y536573D01*
G01X350554Y536538D02*
X350569Y536535D01*
G01X350541Y536547D02*
X350554Y536538D01*
G01X350530Y536567D02*
X350541Y536547D01*
G01X351515Y537697D02*
X351516Y537691D01*
G01X351513Y537704D02*
X351515Y537697D01*
G01X351510Y537709D02*
X351513Y537704D01*
G01X351515Y540847D02*
X351516Y540840D01*
G01X351513Y540853D02*
X351515Y540847D01*
G01X351510Y540859D02*
X351513Y540853D01*
G01X351515Y543996D02*
X351516Y543990D01*
G01X351513Y544003D02*
X351515Y543996D01*
G01X351510Y544009D02*
X351513Y544003D01*
G01X351515Y547146D02*
X351516Y547139D01*
G01X351513Y547152D02*
X351515Y547146D01*
G01X351510Y547158D02*
X351513Y547152D01*
G01X351477Y536530D02*
Y536524D01*
G01X351476Y536534D02*
X351477Y536530D01*
G01X351475Y536535D02*
X351476Y536534D01*
G01X351477Y539680D02*
Y539674D01*
G01X351476Y539683D02*
X351477Y539680D01*
G01X351475Y539685D02*
X351476Y539683D01*
G01X351477Y542830D02*
Y542823D01*
G01X351476Y542833D02*
X351477Y542830D01*
G01X351475Y542835D02*
X351476Y542833D01*
G01X351477Y545979D02*
Y545973D01*
G01X351476Y545983D02*
X351477Y545979D01*
G01X351475Y545984D02*
X351476Y545983D01*
G01X351477Y549129D02*
Y549122D01*
G01X351476Y549132D02*
X351477Y549129D01*
G01X351475Y549134D02*
X351476Y549132D01*
G01X363957Y504771D02*
Y504780D01*
G01Y504765D02*
Y504771D01*
G01X363958Y504764D02*
X363957Y504765D01*
G01Y509771D02*
Y509780D01*
G01Y509765D02*
Y509771D01*
G01X363958Y509764D02*
X363957Y509765D01*
G01Y514771D02*
Y514780D01*
G01Y514765D02*
Y514771D01*
G01X363958Y514764D02*
X363957Y514765D01*
G01Y519771D02*
Y519780D01*
G01Y519765D02*
Y519771D01*
G01X363958Y519764D02*
X363957Y519765D01*
G01Y524771D02*
Y524780D01*
G01Y524765D02*
Y524771D01*
G01X363958Y524764D02*
X363957Y524765D01*
G01Y529771D02*
Y529780D01*
G01Y529765D02*
Y529771D01*
G01X363958Y529764D02*
X363957Y529765D01*
G01X364933Y504907D02*
X364941Y504881D01*
G01X364923Y504934D02*
X364933Y504907D01*
G01X364912Y504961D02*
X364923Y504934D01*
G01X364933Y509907D02*
X364941Y509881D01*
G01X364923Y509934D02*
X364933Y509907D01*
G01X364912Y509961D02*
X364923Y509934D01*
G01X364933Y514907D02*
X364941Y514881D01*
G01X364923Y514934D02*
X364933Y514907D01*
G01X364912Y514961D02*
X364923Y514934D01*
G01X364933Y519907D02*
X364941Y519881D01*
G01X364923Y519934D02*
X364933Y519907D01*
G01X364912Y519961D02*
X364923Y519934D01*
G01X364933Y524907D02*
X364941Y524881D01*
G01X364923Y524934D02*
X364933Y524907D01*
G01X364912Y524961D02*
X364923Y524934D01*
G01X350549Y545989D02*
X350569Y545984D01*
G01X350536Y546002D02*
X350549Y545989D01*
G01X350529Y546019D02*
X350536Y546002D01*
G01X364924Y504759D02*
X364904Y504764D01*
G01X364938Y504744D02*
X364924Y504759D01*
G01X364943Y504724D02*
X364938Y504744D01*
G01X364924Y509759D02*
X364904Y509764D01*
G01X364938Y509744D02*
X364924Y509759D01*
G01X364943Y509724D02*
X364938Y509744D01*
G01X364908Y504862D02*
X364912Y504961D01*
G01X364902Y504790D02*
X364908Y504862D01*
G01X364904Y504764D02*
X364902Y504790D01*
G01X364908Y509862D02*
X364912Y509961D01*
G01X364902Y509790D02*
X364908Y509862D01*
G01X364904Y509764D02*
X364902Y509790D01*
G01X364908Y514862D02*
X364912Y514961D01*
G01X364902Y514790D02*
X364908Y514862D01*
G01X364904Y514764D02*
X364902Y514790D01*
G01X364908Y519862D02*
X364912Y519961D01*
G01X364902Y519790D02*
X364908Y519862D01*
G01X364904Y519764D02*
X364902Y519790D01*
G01X364908Y524862D02*
X364912Y524961D01*
G01X364902Y524790D02*
X364908Y524862D01*
G01X364904Y524764D02*
X364902Y524790D01*
G01X364908Y529862D02*
X364912Y529961D01*
G01X364902Y529790D02*
X364908Y529862D01*
G01X364904Y529764D02*
X364902Y529790D01*
G01X364908Y534862D02*
X364912Y534961D01*
G01X364902Y534790D02*
X364908Y534862D01*
G01X364904Y534764D02*
X364902Y534790D01*
G01X364908Y559862D02*
X364912Y559961D01*
G01X364902Y559790D02*
X364908Y559862D01*
G01X364904Y559764D02*
X364902Y559790D01*
G01X364908Y564862D02*
X364912Y564961D01*
G01X364902Y564790D02*
X364908Y564862D01*
G01X364904Y564764D02*
X364902Y564790D01*
G01X364908Y569862D02*
X364912Y569961D01*
G01X364902Y569790D02*
X364908Y569862D01*
G01X364904Y569764D02*
X364902Y569790D01*
G01X350531Y549167D02*
Y549160D01*
G01X350530Y549172D02*
X350531Y549167D01*
G01Y549162D02*
X350530Y549172D01*
G01X350572Y556798D02*
X350571Y556811D01*
G01X350569Y556785D02*
X350572Y556798D01*
G01X350569Y556772D02*
Y556785D01*
G01X350572Y553649D02*
X350571Y553661D01*
G01X350569Y553636D02*
X350572Y553649D01*
G01X350569Y553622D02*
Y553636D01*
G01X350572Y550499D02*
X350571Y550512D01*
G01X350569Y550486D02*
X350572Y550499D01*
G01X350569Y550472D02*
Y550486D01*
G01X350572Y547350D02*
X350571Y547362D01*
G01X350569Y547337D02*
X350572Y547350D01*
G01X350569Y547323D02*
Y547337D01*
G01X350572Y544200D02*
X350571Y544213D01*
G01X350569Y544187D02*
X350572Y544200D01*
G01X350569Y544173D02*
Y544187D01*
G01X350572Y541050D02*
X350571Y541063D01*
G01X350569Y541037D02*
X350572Y541050D01*
G01X350569Y541024D02*
Y541037D01*
G01X350572Y537901D02*
X350571Y537913D01*
G01X350569Y537888D02*
X350572Y537901D01*
G01X350569Y537874D02*
Y537888D01*
G01X363957Y568384D02*
X363958Y568386D01*
G01X363957Y568378D02*
Y568384D01*
G01Y568370D02*
Y568378D01*
G01Y563384D02*
X363958Y563386D01*
G01X363957Y563378D02*
Y563384D01*
G01Y563370D02*
Y563378D01*
G01Y558384D02*
X363958Y558386D01*
G01X363957Y558378D02*
Y558384D01*
G01Y558370D02*
Y558378D01*
G01Y533384D02*
X363958Y533386D01*
G01X363957Y533378D02*
Y533384D01*
G01Y533370D02*
Y533378D01*
G01Y528384D02*
X363958Y528386D01*
G01X363957Y528378D02*
Y528384D01*
G01Y528370D02*
Y528378D01*
G01Y523384D02*
X363958Y523386D01*
G01X363957Y523378D02*
Y523384D01*
G01Y523370D02*
Y523378D01*
G01Y518384D02*
X363958Y518386D01*
G01X363957Y518378D02*
Y518384D01*
G01Y518370D02*
Y518378D01*
G01Y513384D02*
X363958Y513386D01*
G01X363957Y513378D02*
Y513384D01*
G01Y513370D02*
Y513378D01*
G01Y508384D02*
X363958Y508386D01*
G01X363957Y508378D02*
Y508384D01*
G01Y508370D02*
Y508378D01*
G01Y503384D02*
X363958Y503386D01*
G01X363957Y503378D02*
Y503384D01*
G01Y503370D02*
Y503378D01*
G01X350531Y555467D02*
Y555459D01*
G01X350530Y555471D02*
X350531Y555467D01*
G01X350530Y555463D02*
Y555471D01*
G01X350569Y555261D02*
X350567Y555275D01*
G01X350572Y555249D02*
X350569Y555261D01*
G01X350571Y555236D02*
X350572Y555249D01*
G01X350569Y552112D02*
X350567Y552126D01*
G01X350572Y552099D02*
X350569Y552112D01*
G01X350571Y552087D02*
X350572Y552099D01*
G01X350569Y548962D02*
X350567Y548976D01*
G01X350572Y548950D02*
X350569Y548962D01*
G01X350571Y548937D02*
X350572Y548950D01*
G01X350569Y545813D02*
X350567Y545826D01*
G01X350572Y545800D02*
X350569Y545813D01*
G01X350571Y545787D02*
X350572Y545800D01*
G01X350569Y542663D02*
X350567Y542677D01*
G01X350572Y542650D02*
X350569Y542663D01*
G01X350571Y542638D02*
X350572Y542650D01*
G01X350569Y539513D02*
X350567Y539527D01*
G01X350572Y539501D02*
X350569Y539513D01*
G01X350571Y539488D02*
X350572Y539501D01*
G01X350569Y536364D02*
X350567Y536378D01*
G01X350572Y536351D02*
X350569Y536364D01*
G01X350571Y536339D02*
X350572Y536351D01*
G01X351479Y556785D02*
X351480Y556772D01*
G01X351476Y556798D02*
X351479Y556785D01*
G01X351476Y556811D02*
Y556798D01*
G01X351479Y553636D02*
X351480Y553622D01*
G01X351476Y553649D02*
X351479Y553636D01*
G01X351476Y553661D02*
Y553649D01*
G01X351479Y550486D02*
X351480Y550472D01*
G01X351476Y550499D02*
X351479Y550486D01*
G01X351476Y550512D02*
Y550499D01*
G01X351479Y547337D02*
X351480Y547323D01*
G01X351476Y547350D02*
X351479Y547337D01*
G01X351476Y547362D02*
Y547350D01*
G01X351479Y544187D02*
X351480Y544173D01*
G01X351476Y544200D02*
X351479Y544187D01*
G01X351476Y544213D02*
Y544200D01*
G01X351479Y541037D02*
X351480Y541024D01*
G01X351476Y541050D02*
X351479Y541037D01*
G01X351476Y541063D02*
Y541050D01*
G01X351479Y537888D02*
X351480Y537874D01*
G01X351476Y537901D02*
X351479Y537888D01*
G01X351476Y537913D02*
Y537901D01*
G01X350531Y542868D02*
Y542861D01*
G01X350530Y542872D02*
X350531Y542868D01*
G01X350530Y542865D02*
Y542872D01*
G01X350531Y552317D02*
Y552309D01*
G01X350530Y552321D02*
X350531Y552317D01*
G01X350530Y552314D02*
Y552321D01*
G01X351476Y555249D02*
Y555236D01*
G01X351478Y555261D02*
X351476Y555249D01*
G01X351480Y555275D02*
X351478Y555261D01*
G01X351476Y552099D02*
Y552087D01*
G01X351478Y552112D02*
X351476Y552099D01*
G01X351480Y552126D02*
X351478Y552112D01*
G01X351476Y548950D02*
Y548937D01*
G01X351478Y548962D02*
X351476Y548950D01*
G01X351480Y548976D02*
X351478Y548962D01*
G01X351476Y545800D02*
Y545787D01*
G01X351478Y545813D02*
X351476Y545800D01*
G01X351480Y545826D02*
X351478Y545813D01*
G01X351476Y542650D02*
Y542638D01*
G01X351478Y542663D02*
X351476Y542650D01*
G01X351480Y542677D02*
X351478Y542663D01*
G01X351476Y539501D02*
Y539488D01*
G01X351478Y539513D02*
X351476Y539501D01*
G01X351480Y539527D02*
X351478Y539513D01*
G01X351476Y536351D02*
Y536339D01*
G01X351478Y536364D02*
X351476Y536351D01*
G01X351480Y536378D02*
X351478Y536364D01*
G01X350531Y536569D02*
Y536561D01*
G01X350530Y536573D02*
X350531Y536569D01*
G01X350530Y536567D02*
Y536573D01*
G01X350570Y536530D02*
X350571Y536524D01*
G01X350570Y536534D02*
Y536530D01*
G01X350569Y536535D02*
X350570Y536534D01*
G01Y539680D02*
X350571Y539674D01*
G01X350570Y539684D02*
Y539680D01*
G01X350569Y539685D02*
X350570Y539684D01*
G01Y542830D02*
X350571Y542823D01*
G01X350570Y542833D02*
Y542830D01*
G01X350569Y542835D02*
X350570Y542833D01*
G01Y545979D02*
X350571Y545973D01*
G01X350570Y545983D02*
Y545979D01*
G01X350569Y545984D02*
X350570Y545983D01*
G01Y549129D02*
X350571Y549122D01*
G01X350570Y549133D02*
Y549129D01*
G01X350569Y549134D02*
X350570Y549133D01*
G01Y552278D02*
X350571Y552272D01*
G01X350570Y552282D02*
Y552278D01*
G01X350569Y552283D02*
X350570Y552282D01*
G01X364941Y504731D02*
Y504738D01*
G01X364942Y504726D02*
X364941Y504731D01*
G01X364943Y504724D02*
X364942Y504726D01*
G01X364941Y509731D02*
Y509738D01*
G01X364942Y509726D02*
X364941Y509731D01*
G01X364943Y509724D02*
X364942Y509726D01*
G01X364941Y514731D02*
Y514738D01*
G01X364942Y514726D02*
X364941Y514731D01*
G01X364943Y514724D02*
X364942Y514726D01*
G01X364941Y519731D02*
Y519738D01*
G01X364942Y519726D02*
X364941Y519731D01*
G01X364943Y519724D02*
X364942Y519726D01*
G01X364941Y524731D02*
Y524738D01*
G01X364942Y524726D02*
X364941Y524731D01*
G01X364943Y524724D02*
X364942Y524726D01*
G01X364941Y529731D02*
Y529738D01*
G01X364942Y529726D02*
X364941Y529731D01*
G01X364943Y529724D02*
X364942Y529726D01*
G01X364941Y534731D02*
Y534738D01*
G01X364942Y534726D02*
X364941Y534731D01*
G01X364943Y534724D02*
X364942Y534726D01*
G01X364941Y559731D02*
Y559738D01*
G01X364942Y559726D02*
X364941Y559731D01*
G01X364943Y559724D02*
X364942Y559726D01*
G01X364941Y564731D02*
Y564738D01*
G01X364942Y564726D02*
X364941Y564731D01*
G01X364943Y564724D02*
X364942Y564726D01*
G01X364941Y569731D02*
Y569738D01*
G01X364942Y569726D02*
X364941Y569731D01*
G01X364943Y569724D02*
X364942Y569726D01*
G01X350554Y539687D02*
X350569Y539685D01*
G01X350543Y539694D02*
X350554Y539687D01*
G01X350531Y539713D02*
X350543Y539694D01*
G01X350554Y549136D02*
X350569Y549134D01*
G01X350543Y549144D02*
X350554Y549136D01*
G01X350531Y549162D02*
X350543Y549144D01*
G01X350554Y542837D02*
X350569Y542835D01*
G01X350542Y542845D02*
X350554Y542837D01*
G01X350530Y542865D02*
X350542Y542845D01*
G01X350554Y552286D02*
X350569Y552283D01*
G01X350542Y552294D02*
X350554Y552286D01*
G01X350530Y552314D02*
X350542Y552294D01*
G01X351516Y539719D02*
Y539711D01*
G01X351515Y539723D02*
X351516Y539719D01*
G01X351514Y539724D02*
X351515Y539723D01*
G01X351516Y542868D02*
Y542860D01*
G01X351515Y542872D02*
X351516Y542868D01*
G01X351514Y542874D02*
X351515Y542872D01*
G01X351516Y546018D02*
Y546010D01*
G01X351515Y546022D02*
X351516Y546018D01*
G01X351514Y546024D02*
X351515Y546022D01*
G01X351516Y549167D02*
Y549159D01*
G01X351515Y549172D02*
X351516Y549167D01*
G01X351514Y549173D02*
X351515Y549172D01*
G01X351516Y552317D02*
Y552309D01*
G01X351515Y552321D02*
X351516Y552317D01*
G01X351514Y552323D02*
X351515Y552321D01*
G01X351516Y555467D02*
Y555459D01*
G01X351515Y555471D02*
X351516Y555467D01*
G01X351514Y555472D02*
X351515Y555471D01*
G01X350554Y555436D02*
X350569Y555433D01*
G01X350541Y555444D02*
X350554Y555436D01*
G01X350530Y555464D02*
X350541Y555444D01*
G01X351515Y550296D02*
X351516Y550289D01*
G01X351513Y550302D02*
X351515Y550296D01*
G01X351510Y550308D02*
X351513Y550302D01*
G01X351515Y553445D02*
X351516Y553439D01*
G01X351513Y553452D02*
X351515Y553445D01*
G01X351510Y553457D02*
X351513Y553452D01*
G01X351515Y556595D02*
X351516Y556588D01*
G01X351513Y556601D02*
X351515Y556595D01*
G01X351510Y556607D02*
X351513Y556601D01*
G01X351477Y555428D02*
Y555422D01*
G01X351476Y555431D02*
X351477Y555428D01*
G01X351475Y555433D02*
X351476Y555431D01*
G01X363957Y534771D02*
Y534780D01*
G01Y534765D02*
Y534771D01*
G01X363958Y534764D02*
X363957Y534765D01*
G01Y559771D02*
Y559780D01*
G01Y559765D02*
Y559771D01*
G01X363958Y559764D02*
X363957Y559765D01*
G01Y564771D02*
Y564780D01*
G01Y564765D02*
Y564771D01*
G01X363958Y564764D02*
X363957Y564765D01*
G01Y569771D02*
Y569780D01*
G01Y569765D02*
Y569771D01*
G01X363958Y569764D02*
X363957Y569765D01*
G01X364933Y529907D02*
X364941Y529881D01*
G01X364923Y529934D02*
X364933Y529907D01*
G01X364912Y529961D02*
X364923Y529934D01*
G01X364933Y534907D02*
X364941Y534881D01*
G01X364923Y534934D02*
X364933Y534907D01*
G01X364912Y534961D02*
X364923Y534934D01*
G01X364933Y559907D02*
X364941Y559881D01*
G01X364923Y559934D02*
X364933Y559907D01*
G01X364912Y559961D02*
X364923Y559934D01*
G01X364933Y564907D02*
X364941Y564881D01*
G01X364923Y564934D02*
X364933Y564907D01*
G01X364912Y564961D02*
X364923Y564934D01*
G01X364933Y569907D02*
X364941Y569881D01*
G01X364923Y569934D02*
X364933Y569907D01*
G01X364912Y569961D02*
X364923Y569934D01*
G01X364924Y514759D02*
X364904Y514764D01*
G01X364938Y514744D02*
X364924Y514759D01*
G01X364943Y514724D02*
X364938Y514744D01*
G01X364924Y519759D02*
X364904Y519764D01*
G01X364938Y519744D02*
X364924Y519759D01*
G01X364943Y519724D02*
X364938Y519744D01*
G01X364924Y524759D02*
X364904Y524764D01*
G01X364938Y524744D02*
X364924Y524759D01*
G01X364943Y524724D02*
X364938Y524744D01*
G01X364924Y529759D02*
X364904Y529764D01*
G01X364938Y529744D02*
X364924Y529759D01*
G01X364943Y529724D02*
X364938Y529744D01*
G01X364924Y534759D02*
X364904Y534764D01*
G01X364938Y534744D02*
X364924Y534759D01*
G01X364943Y534724D02*
X364938Y534744D01*
G01X364924Y559759D02*
X364904Y559764D01*
G01X364938Y559744D02*
X364924Y559759D01*
G01X364943Y559724D02*
X364938Y559744D01*
G01X364924Y564759D02*
X364904Y564764D01*
G01X364938Y564744D02*
X364924Y564759D01*
G01X364943Y564724D02*
X364938Y564744D01*
G01X364924Y569759D02*
X364904Y569764D01*
G01X364938Y569744D02*
X364924Y569759D01*
G01X364943Y569724D02*
X364938Y569744D01*
G01X351508Y543998D02*
X351501Y544006D01*
G01X351513Y543987D02*
X351508Y543998D01*
G01X351515Y543976D02*
X351513Y543987D01*
G01X351508Y537698D02*
X351501Y537707D01*
G01X351513Y537688D02*
X351508Y537698D01*
G01X351515Y537677D02*
X351513Y537688D01*
G01X351508Y540848D02*
X351501Y540856D01*
G01X351513Y540838D02*
X351508Y540848D01*
G01X351515Y540827D02*
X351513Y540838D01*
G01X351508Y547147D02*
X351501Y547156D01*
G01X351513Y547137D02*
X351508Y547147D01*
G01X351515Y547126D02*
X351513Y547137D01*
G01X351508Y550297D02*
X351501Y550305D01*
G01X351513Y550287D02*
X351508Y550297D01*
G01X351515Y550276D02*
X351513Y550287D01*
G01X351508Y553446D02*
X351501Y553455D01*
G01X351513Y553436D02*
X351508Y553446D01*
G01X351515Y553425D02*
X351513Y553436D01*
G01X351508Y556596D02*
X351501Y556604D01*
G01X351513Y556586D02*
X351508Y556596D01*
G01X351515Y556575D02*
X351513Y556586D01*
G01X350544Y556606D02*
X350569Y556614D01*
G01X350533Y556591D02*
X350544Y556606D01*
G01X350531Y556584D02*
X350533Y556591D01*
G01X350544Y553456D02*
X350569Y553465D01*
G01X350533Y553441D02*
X350544Y553456D01*
G01X350531Y553435D02*
X350533Y553441D01*
G01X350544Y550306D02*
X350569Y550315D01*
G01X350533Y550292D02*
X350544Y550306D01*
G01X350531Y550285D02*
X350533Y550292D01*
G01X350544Y547157D02*
X350569Y547165D01*
G01X350533Y547142D02*
X350544Y547157D01*
G01X350531Y547135D02*
X350533Y547142D01*
G01X350544Y544007D02*
X350569Y544016D01*
G01X350533Y543993D02*
X350544Y544007D01*
G01X350531Y543986D02*
X350533Y543993D01*
G01X350544Y540857D02*
X350569Y540866D01*
G01X350533Y540843D02*
X350544Y540857D01*
G01X350531Y540836D02*
X350533Y540843D01*
G01X350544Y537708D02*
X350569Y537717D01*
G01X350533Y537693D02*
X350544Y537708D01*
G01X350531Y537687D02*
X350533Y537693D01*
G01X351484Y544015D02*
X351475Y544016D01*
G01X351493Y544011D02*
X351484Y544015D01*
G01X351501Y544006D02*
X351493Y544011D01*
G01X351484Y537715D02*
X351475Y537717D01*
G01X351493Y537712D02*
X351484Y537715D01*
G01X351501Y537707D02*
X351493Y537712D01*
G01X351484Y540865D02*
X351475Y540866D01*
G01X351493Y540862D02*
X351484Y540865D01*
G01X351501Y540856D02*
X351493Y540862D01*
G01X351484Y547164D02*
X351475Y547165D01*
G01X351493Y547161D02*
X351484Y547164D01*
G01X351501Y547156D02*
X351493Y547161D01*
G01X351484Y550314D02*
X351475Y550315D01*
G01X351493Y550311D02*
X351484Y550314D01*
G01X351501Y550305D02*
X351493Y550311D01*
G01X351484Y553463D02*
X351475Y553465D01*
G01X351493Y553460D02*
X351484Y553463D01*
G01X351501Y553455D02*
X351493Y553460D01*
G01X351484Y556613D02*
X351475Y556614D01*
G01X351493Y556610D02*
X351484Y556613D01*
G01X351501Y556604D02*
X351493Y556610D01*
G01X350570Y555428D02*
X350571Y555422D01*
G01X350570Y555432D02*
Y555428D01*
G01X350569Y555433D02*
X350570Y555432D01*
G01X351516Y556581D02*
Y556588D01*
G01X351515Y556576D02*
X351516Y556581D01*
G01X351515Y556575D02*
Y556576D01*
G01X351516Y553431D02*
Y553439D01*
G01X351515Y553427D02*
X351516Y553431D01*
G01X351515Y553425D02*
Y553427D01*
G01X351516Y550282D02*
Y550289D01*
G01X351515Y550277D02*
X351516Y550282D01*
G01X351515Y550276D02*
Y550277D01*
G01X351516Y547132D02*
Y547139D01*
G01X351515Y547128D02*
X351516Y547132D01*
G01X351515Y547126D02*
Y547128D01*
G01X351516Y543983D02*
Y543990D01*
G01X351515Y543978D02*
X351516Y543983D01*
G01X351515Y543976D02*
Y543978D01*
G01X351516Y540833D02*
Y540840D01*
G01X351515Y540828D02*
X351516Y540833D01*
G01X351515Y540827D02*
Y540828D01*
G01X351516Y537683D02*
Y537691D01*
G01X351515Y537679D02*
X351516Y537683D01*
G01X351515Y537677D02*
Y537679D01*
G01X350531Y546018D02*
Y546010D01*
G01X350530Y546022D02*
X350531Y546018D01*
G01X350529Y546019D02*
X350530Y546022D01*
G01X350531Y539719D02*
Y539711D01*
G01X350530Y539723D02*
X350531Y539719D01*
G01X350529Y539721D02*
X350530Y539723D01*
G01X351476Y556619D02*
Y556625D01*
G01Y556615D02*
Y556619D01*
G01X351475Y556614D02*
X351476Y556615D01*
G01Y553470D02*
Y553476D01*
G01Y553466D02*
Y553470D01*
G01X351475Y553465D02*
X351476Y553466D01*
G01Y550320D02*
Y550326D01*
G01Y550316D02*
Y550320D01*
G01X351475Y550315D02*
X351476Y550316D01*
G01X350531Y539715D02*
Y539711D01*
G01X350533Y539708D02*
X350531Y539715D01*
G01X350545Y539693D02*
X350533Y539708D01*
G01X350570Y539685D02*
X350545Y539693D01*
G01X350531Y542864D02*
Y542860D01*
G01X350533Y542858D02*
X350531Y542864D01*
G01X350544Y542843D02*
X350533Y542858D01*
G01X350569Y542835D02*
X350544Y542843D01*
G01X350531Y536565D02*
Y536561D01*
G01X350533Y536559D02*
X350531Y536565D01*
G01X350544Y536544D02*
X350533Y536559D01*
G01X350569Y536535D02*
X350544Y536544D01*
G01X364928Y504755D02*
X364939Y504740D01*
G01X364904Y504764D02*
X364928Y504755D01*
G01Y509755D02*
X364939Y509740D01*
G01X364904Y509764D02*
X364928Y509755D01*
G01X364939Y514740D02*
X364941Y514734D01*
G01X364928Y514755D02*
X364939Y514740D01*
G01X364904Y514764D02*
X364928Y514755D01*
G01Y519755D02*
X364939Y519740D01*
G01X364904Y519764D02*
X364928Y519755D01*
G01Y524755D02*
X364939Y524740D01*
G01X364904Y524764D02*
X364928Y524755D01*
G01Y529755D02*
X364939Y529740D01*
G01X364904Y529764D02*
X364928Y529755D01*
G01Y534755D02*
X364939Y534740D01*
G01X364904Y534764D02*
X364928Y534755D01*
G01X350531Y546014D02*
Y546010D01*
G01X350533Y546008D02*
X350531Y546014D01*
G01X350543Y545994D02*
X350533Y546008D01*
G01X350566Y545984D02*
X350543Y545994D01*
G01X351476Y547170D02*
Y547176D01*
G01Y547167D02*
Y547170D01*
G01X351475Y547165D02*
X351476Y547167D01*
G01Y544021D02*
Y544027D01*
G01Y544017D02*
Y544021D01*
G01X351475Y544016D02*
X351476Y544017D01*
G01Y540871D02*
Y540877D01*
G01Y540867D02*
Y540871D01*
G01X351475Y540866D02*
X351476Y540867D01*
G01Y537722D02*
Y537728D01*
G01Y537718D02*
Y537722D01*
G01X351475Y537717D02*
X351476Y537718D01*
G01X364941Y568378D02*
Y568369D01*
G01X364942Y568384D02*
X364941Y568378D01*
G01X364944Y568386D02*
X364942Y568384D01*
G01X364941Y563378D02*
Y563369D01*
G01X364942Y563384D02*
X364941Y563378D01*
G01X364944Y563386D02*
X364942Y563384D01*
G01X364941Y558378D02*
Y558369D01*
G01X364942Y558384D02*
X364941Y558378D01*
G01X364944Y558386D02*
X364942Y558384D01*
G01X364941Y533378D02*
Y533369D01*
G01X364942Y533384D02*
X364941Y533378D01*
G01X364944Y533386D02*
X364942Y533384D01*
G01X364941Y528378D02*
Y528369D01*
G01X364942Y528384D02*
X364941Y528378D01*
G01X364944Y528386D02*
X364942Y528384D01*
G01X364941Y523378D02*
Y523369D01*
G01X364942Y523384D02*
X364941Y523378D01*
G01X364944Y523386D02*
X364942Y523384D01*
G01X350531Y549163D02*
Y549159D01*
G01X350533Y549157D02*
X350531Y549163D01*
G01X350544Y549142D02*
X350533Y549157D01*
G01X350569Y549134D02*
X350544Y549142D01*
G01X350531Y552313D02*
Y552309D01*
G01X350533Y552307D02*
X350531Y552313D01*
G01X350544Y552292D02*
X350533Y552307D01*
G01X350569Y552283D02*
X350544Y552292D01*
G01X350531Y555463D02*
Y555459D01*
G01X350533Y555457D02*
X350531Y555463D01*
G01X350544Y555441D02*
X350533Y555457D01*
G01X350569Y555433D02*
X350544Y555441D01*
G01X364928Y559755D02*
X364939Y559740D01*
G01X364904Y559764D02*
X364928Y559755D01*
G01Y564755D02*
X364939Y564740D01*
G01X364904Y564764D02*
X364928Y564755D01*
G01Y569755D02*
X364939Y569740D01*
G01X364904Y569764D02*
X364928Y569755D01*
G01X364941Y518378D02*
Y518369D01*
G01X364942Y518384D02*
X364941Y518378D01*
G01X364944Y518386D02*
X364942Y518384D01*
G01X364941Y513378D02*
Y513369D01*
G01X364942Y513384D02*
X364941Y513378D01*
G01X364944Y513386D02*
X364942Y513384D01*
G01X364941Y508378D02*
Y508369D01*
G01X364942Y508384D02*
X364941Y508378D01*
G01X364944Y508386D02*
X364942Y508384D01*
G01X364941Y503378D02*
Y503369D01*
G01X364942Y503384D02*
X364941Y503378D01*
G01X364944Y503386D02*
X364942Y503384D01*
G01X350531Y556581D02*
Y556588D01*
G01X350530Y556576D02*
X350531Y556581D01*
G01X350529Y556575D02*
X350530Y556576D01*
G01X350531Y553431D02*
Y553439D01*
G01X350530Y553427D02*
X350531Y553431D01*
G01X350529Y553425D02*
X350530Y553427D01*
G01X350531Y550281D02*
Y550289D01*
G01X350530Y550277D02*
X350531Y550281D01*
G01X350529Y550276D02*
X350530Y550277D01*
G01X350531Y547132D02*
Y547139D01*
G01X350530Y547128D02*
X350531Y547132D01*
G01X350529Y547126D02*
X350530Y547128D01*
G01X350531Y543982D02*
Y543990D01*
G01X350530Y543978D02*
X350531Y543982D01*
G01X350529Y543976D02*
X350530Y543978D01*
G01X350531Y540833D02*
Y540840D01*
G01X350530Y540828D02*
X350531Y540833D01*
G01X350529Y540827D02*
X350530Y540828D01*
G01X350531Y537683D02*
Y537691D01*
G01X350530Y537679D02*
X350531Y537683D01*
G01X350529Y537677D02*
X350530Y537679D01*
G01X351506Y537715D02*
X351510Y537709D01*
G01X351502Y537719D02*
X351506Y537715D01*
G01X351496Y537723D02*
X351502Y537719D01*
G01X351490Y537726D02*
X351496Y537723D01*
G01X351483Y537727D02*
X351490Y537726D01*
G01X351476Y537728D02*
X351483Y537727D01*
G01X351506Y540865D02*
X351510Y540859D01*
G01X351502Y540869D02*
X351506Y540865D01*
G01X351496Y540872D02*
X351502Y540869D01*
G01X351490Y540875D02*
X351496Y540872D01*
G01X351483Y540877D02*
X351490Y540875D01*
G01X351476Y540877D02*
X351483D01*
G01X351506Y544014D02*
X351510Y544009D01*
G01X351502Y544019D02*
X351506Y544014D01*
G01X351496Y544022D02*
X351502Y544019D01*
G01X351490Y544025D02*
X351496Y544022D01*
G01X351483Y544026D02*
X351490Y544025D01*
G01X351476Y544027D02*
X351483Y544026D01*
G01X351506Y547164D02*
X351510Y547158D01*
G01X351502Y547168D02*
X351506Y547164D01*
G01X351496Y547172D02*
X351502Y547168D01*
G01X351490Y547174D02*
X351496Y547172D01*
G01X351483Y547176D02*
X351490Y547174D01*
G01X351476Y547176D02*
X351483D01*
G01X351506Y550313D02*
X351510Y550308D01*
G01X351502Y550318D02*
X351506Y550313D01*
G01X351496Y550321D02*
X351502Y550318D01*
G01X351490Y550324D02*
X351496Y550321D01*
G01X351483Y550326D02*
X351490Y550324D01*
G01X351476Y550326D02*
X351483D01*
G01X351506Y553463D02*
X351510Y553457D01*
G01X351502Y553467D02*
X351506Y553463D01*
G01X351496Y553471D02*
X351502Y553467D01*
G01X351490Y553474D02*
X351496Y553471D01*
G01X351483Y553475D02*
X351490Y553474D01*
G01X351476Y553476D02*
X351483Y553475D01*
G01X351506Y556613D02*
X351510Y556607D01*
G01X351502Y556617D02*
X351506Y556613D01*
G01X351496Y556620D02*
X351502Y556617D01*
G01X351490Y556623D02*
X351496Y556620D01*
G01X351483Y556625D02*
X351490Y556623D01*
G01X351476Y556625D02*
X351483D01*
G01X350532Y536554D02*
X350531Y536561D01*
G01X350535Y536547D02*
X350532Y536554D01*
G01X350538Y536541D02*
X350535Y536547D01*
G01X350543Y536535D02*
X350538Y536541D01*
G01X350549Y536530D02*
X350543Y536535D01*
G01X350556Y536527D02*
X350549Y536530D01*
G01X350563Y536525D02*
X350556Y536527D01*
G01X350571Y536524D02*
X350563Y536525D01*
G01X350532Y539704D02*
X350531Y539711D01*
G01X350535Y539696D02*
X350532Y539704D01*
G01X350538Y539690D02*
X350535Y539696D01*
G01X350543Y539685D02*
X350538Y539690D01*
G01X350549Y539680D02*
X350543Y539685D01*
G01X350556Y539676D02*
X350549Y539680D01*
G01X350563Y539674D02*
X350556Y539676D01*
G01X350571Y539674D02*
X350563D01*
G01X350532Y542853D02*
X350531Y542860D01*
G01X350535Y542846D02*
X350532Y542853D01*
G01X350538Y542840D02*
X350535Y542846D01*
G01X350543Y542834D02*
X350538Y542840D01*
G01X350549Y542830D02*
X350543Y542834D01*
G01X350556Y542826D02*
X350549Y542830D01*
G01X350563Y542824D02*
X350556Y542826D01*
G01X350571Y542823D02*
X350563Y542824D01*
G01X350532Y546003D02*
X350531Y546010D01*
G01X350535Y545996D02*
X350532Y546003D01*
G01X350538Y545989D02*
X350535Y545996D01*
G01X350543Y545984D02*
X350538Y545989D01*
G01X350549Y545979D02*
X350543Y545984D01*
G01X350556Y545976D02*
X350549Y545979D01*
G01X350563Y545974D02*
X350556Y545976D01*
G01X350571Y545973D02*
X350563Y545974D01*
G01X350532Y549152D02*
X350531Y549159D01*
G01X350535Y549145D02*
X350532Y549152D01*
G01X350538Y549139D02*
X350535Y549145D01*
G01X350543Y549133D02*
X350538Y549139D01*
G01X350549Y549129D02*
X350543Y549133D01*
G01X350556Y549125D02*
X350549Y549129D01*
G01X350563Y549123D02*
X350556Y549125D01*
G01X350571Y549122D02*
X350563Y549123D01*
G01X350532Y552302D02*
X350531Y552309D01*
G01X350535Y552295D02*
X350532Y552302D01*
G01X350538Y552289D02*
X350535Y552295D01*
G01X350543Y552283D02*
X350538Y552289D01*
G01X350549Y552278D02*
X350543Y552283D01*
G01X350556Y552275D02*
X350549Y552278D01*
G01X350563Y552273D02*
X350556Y552275D01*
G01X350571Y552272D02*
X350563Y552273D01*
G01X350532Y555452D02*
X350531Y555459D01*
G01X350535Y555444D02*
X350532Y555452D01*
G01X350538Y555438D02*
X350535Y555444D01*
G01X350543Y555433D02*
X350538Y555438D01*
G01X350549Y555428D02*
X350543Y555433D01*
G01X350556Y555424D02*
X350549Y555428D01*
G01X350563Y555422D02*
X350556Y555424D01*
G01X350571Y555422D02*
X350563D01*
G01X351485Y537715D02*
X351495Y537711D01*
G01X351475Y537717D02*
X351485Y537715D01*
G01Y540865D02*
X351495Y540861D01*
G01X351475Y540866D02*
X351485Y540865D01*
G01Y544014D02*
X351495Y544010D01*
G01X351475Y544016D02*
X351485Y544014D01*
G01Y547164D02*
X351495Y547160D01*
G01X351475Y547165D02*
X351485Y547164D01*
G01Y550313D02*
X351495Y550309D01*
G01X351475Y550315D02*
X351485Y550313D01*
G01Y553463D02*
X351495Y553459D01*
G01X351475Y553465D02*
X351485Y553463D01*
G01Y556613D02*
X351495Y556609D01*
G01X351475Y556614D02*
X351485Y556613D01*
G01X351513Y555446D02*
X351516Y555459D01*
G01X351507Y555435D02*
X351513Y555446D01*
G01X351496Y555427D02*
X351507Y555435D01*
G01X351513Y549147D02*
X351516Y549159D01*
G01X351507Y549136D02*
X351513Y549147D01*
G01X351496Y549128D02*
X351507Y549136D01*
G01X351513Y545998D02*
X351516Y546010D01*
G01X351507Y545986D02*
X351513Y545998D01*
G01X351496Y545978D02*
X351507Y545986D01*
G01X351513Y542848D02*
X351516Y542860D01*
G01X351507Y542837D02*
X351513Y542848D01*
G01X351496Y542829D02*
X351507Y542837D01*
G01X351513Y539698D02*
X351516Y539711D01*
G01X351507Y539687D02*
X351513Y539698D01*
G01X351496Y539679D02*
X351507Y539687D01*
G01X351513Y536549D02*
X351516Y536561D01*
G01X351507Y536537D02*
X351513Y536549D01*
G01X351496Y536530D02*
X351507Y536537D01*
G01X350570Y556619D02*
Y556625D01*
G01Y556615D02*
Y556619D01*
G01X350569Y556614D02*
X350570Y556615D01*
G01Y553469D02*
Y553476D01*
G01Y553466D02*
Y553469D01*
G01X350569Y553465D02*
X350570Y553466D01*
G01Y550320D02*
Y550326D01*
G01Y550316D02*
Y550320D01*
G01X350569Y550315D02*
X350570Y550316D01*
G01Y547170D02*
Y547176D01*
G01Y547167D02*
Y547170D01*
G01X350569Y547165D02*
X350570Y547167D01*
G01Y544020D02*
Y544027D01*
G01Y544017D02*
Y544020D01*
G01X350569Y544016D02*
X350570Y544017D01*
G01Y540871D02*
Y540877D01*
G01Y540867D02*
Y540871D01*
G01X350569Y540866D02*
X350570Y540867D01*
G01Y537721D02*
Y537728D01*
G01Y537718D02*
Y537721D01*
G01X350569Y537717D02*
X350570Y537718D01*
G01X350532Y556594D02*
X350531Y556588D01*
G01X350534Y556601D02*
X350532Y556594D01*
G01X350537Y556607D02*
X350534Y556601D01*
G01X350541Y556612D02*
X350537Y556607D01*
G01X350545Y556617D02*
X350541Y556612D01*
G01X350551Y556620D02*
X350545Y556617D01*
G01X350532Y553445D02*
X350531Y553439D01*
G01X350534Y553451D02*
X350532Y553445D01*
G01X350537Y553457D02*
X350534Y553451D01*
G01X350541Y553462D02*
X350537Y553457D01*
G01X350545Y553467D02*
X350541Y553462D01*
G01X350551Y553470D02*
X350545Y553467D01*
G01X350532Y550295D02*
X350531Y550289D01*
G01X350534Y550302D02*
X350532Y550295D01*
G01X350537Y550307D02*
X350534Y550302D01*
G01X350541Y550313D02*
X350537Y550307D01*
G01X350545Y550317D02*
X350541Y550313D01*
G01X350551Y550321D02*
X350545Y550317D01*
G01X350532Y547146D02*
X350531Y547139D01*
G01X350534Y547152D02*
X350532Y547146D01*
G01X350537Y547158D02*
X350534Y547152D01*
G01X350541Y547163D02*
X350537Y547158D01*
G01X350545Y547168D02*
X350541Y547163D01*
G01X350551Y547171D02*
X350545Y547168D01*
G01X350532Y543996D02*
X350531Y543990D01*
G01X350534Y544002D02*
X350532Y543996D01*
G01X350537Y544008D02*
X350534Y544002D01*
G01X350541Y544013D02*
X350537Y544008D01*
G01X350545Y544018D02*
X350541Y544013D01*
G01X350551Y544022D02*
X350545Y544018D01*
G01X350532Y540846D02*
X350531Y540840D01*
G01X350534Y540853D02*
X350532Y540846D01*
G01X350537Y540859D02*
X350534Y540853D01*
G01X350541Y540864D02*
X350537Y540859D01*
G01X350545Y540869D02*
X350541Y540864D01*
G01X350551Y540872D02*
X350545Y540869D01*
G01X350532Y537697D02*
X350531Y537691D01*
G01X350534Y537703D02*
X350532Y537697D01*
G01X350537Y537709D02*
X350534Y537703D01*
G01X350541Y537714D02*
X350537Y537709D01*
G01X350545Y537719D02*
X350541Y537714D01*
G01X350551Y537722D02*
X350545Y537719D01*
G01X351515Y552302D02*
X351516Y552309D01*
G01X351513Y552295D02*
X351515Y552302D01*
G01X351509Y552289D02*
X351513Y552295D01*
G01X351504Y552283D02*
X351509Y552289D01*
G01X351498Y552278D02*
X351504Y552283D01*
G01X351491Y552275D02*
X351498Y552278D01*
G01X351484Y552273D02*
X351491Y552275D01*
G01X351476Y552272D02*
X351484Y552273D01*
G01X351493Y536528D02*
X351496Y536530D01*
G01X351490Y536526D02*
X351493Y536528D01*
G01X351487Y536526D02*
X351490D01*
G01X351483Y536525D02*
X351487Y536526D01*
G01X351480Y536524D02*
X351483Y536525D01*
G01X351476Y536524D02*
X351480D01*
G01X350554Y537724D02*
X350551Y537722D01*
G01X350557Y537725D02*
X350554Y537724D01*
G01X350561Y537726D02*
X350557Y537725D01*
G01X350564Y537727D02*
X350561Y537726D01*
G01X350567Y537728D02*
X350564Y537727D01*
G01X350571Y537728D02*
X350567D01*
G01X351493Y539677D02*
X351496Y539679D01*
G01X351490Y539676D02*
X351493Y539677D01*
G01X351487Y539675D02*
X351490Y539676D01*
G01X351483Y539674D02*
X351487Y539675D01*
G01X351480Y539674D02*
X351483D01*
G01X351476D02*
X351480D01*
G01X350554Y540874D02*
X350551Y540872D01*
G01X350557Y540875D02*
X350554Y540874D01*
G01X350561Y540876D02*
X350557Y540875D01*
G01X350564Y540877D02*
X350561Y540876D01*
G01X350567Y540877D02*
X350564D01*
G01X350571D02*
X350567D01*
G01X351493Y542827D02*
X351496Y542829D01*
G01X351490Y542826D02*
X351493Y542827D01*
G01X351487Y542825D02*
X351490Y542826D01*
G01X351483Y542824D02*
X351487Y542825D01*
G01X351480Y542824D02*
X351483D01*
G01X351476Y542823D02*
X351480Y542824D01*
G01X350554Y544023D02*
X350551Y544022D01*
G01X350557Y544024D02*
X350554Y544023D01*
G01X350561Y544026D02*
X350557Y544024D01*
G01X350564Y544026D02*
X350561D01*
G01X350567Y544027D02*
X350564Y544026D01*
G01X350571Y544027D02*
X350567D01*
G01X351493Y545976D02*
X351496Y545978D01*
G01X351490Y545975D02*
X351493Y545976D01*
G01X351487Y545974D02*
X351490Y545975D01*
G01X351483Y545974D02*
X351487D01*
G01X351480Y545973D02*
X351483Y545974D01*
G01X351476Y545973D02*
X351480D01*
G01X350554Y547173D02*
X350551Y547171D01*
G01X350557Y547174D02*
X350554Y547173D01*
G01X350561Y547175D02*
X350557Y547174D01*
G01X350564Y547176D02*
X350561Y547175D01*
G01X350567Y547176D02*
X350564D01*
G01X350571D02*
X350567D01*
G01X351493Y549126D02*
X351496Y549128D01*
G01X351490Y549125D02*
X351493Y549126D01*
G01X351487Y549124D02*
X351490Y549125D01*
G01X351483Y549123D02*
X351487Y549124D01*
G01X351480Y549123D02*
X351483D01*
G01X351476Y549122D02*
X351480Y549123D01*
G01X350554Y550322D02*
X350551Y550321D01*
G01X350557Y550324D02*
X350554Y550322D01*
G01X350561Y550325D02*
X350557Y550324D01*
G01X350564Y550326D02*
X350561Y550325D01*
G01X350567Y550326D02*
X350564D01*
G01X350571D02*
X350567D01*
G01X350554Y553472D02*
X350551Y553470D01*
G01X350557Y553473D02*
X350554Y553472D01*
G01X350561Y553474D02*
X350557Y553473D01*
G01X350564Y553475D02*
X350561Y553474D01*
G01X350567Y553476D02*
X350564Y553475D01*
G01X350571Y553476D02*
X350567D01*
G01X351493Y555425D02*
X351496Y555427D01*
G01X351490Y555424D02*
X351493Y555425D01*
G01X351487Y555423D02*
X351490Y555424D01*
G01X351483Y555422D02*
X351487Y555423D01*
G01X351480Y555422D02*
X351483D01*
G01X351476D02*
X351480D01*
G01X350554Y556622D02*
X350551Y556620D01*
G01X350557Y556623D02*
X350554Y556622D01*
G01X350561Y556624D02*
X350557Y556623D01*
G01X350564Y556625D02*
X350561Y556624D01*
G01X350567Y556625D02*
X350564D01*
G01X350571D02*
X350567D01*
G01X349784Y539724D02*
X349350D01*
G01X350158D02*
X349784D01*
G01Y546024D02*
X349350D01*
G01X350158D02*
X349784D01*
G01Y549173D02*
X349350D01*
G01X350158D02*
X349784D01*
G01X351487Y555435D02*
X351475Y555433D01*
G01X351497Y555440D02*
X351487Y555435D01*
G01Y552285D02*
X351475Y552283D01*
G01X351497Y552290D02*
X351487Y552285D01*
G01Y549136D02*
X351475Y549134D01*
G01X351497Y549141D02*
X351487Y549136D01*
G01Y545986D02*
X351475Y545984D01*
G01X351497Y545991D02*
X351487Y545986D01*
G01Y542837D02*
X351475Y542835D01*
G01X351497Y542841D02*
X351487Y542837D01*
G01Y539687D02*
X351475Y539685D01*
G01X351497Y539692D02*
X351487Y539687D01*
G01Y536537D02*
X351475Y536535D01*
G01X351497Y536542D02*
X351487Y536537D01*
G01X350534Y537697D02*
X350529Y537677D01*
G01X350549Y537711D02*
X350534Y537697D01*
G01X350569Y537717D02*
X350549Y537711D01*
G01X350534Y540846D02*
X350529Y540827D01*
G01X350549Y540861D02*
X350534Y540846D01*
G01X350569Y540866D02*
X350549Y540861D01*
G01X350534Y543996D02*
X350529Y543976D01*
G01X350549Y544010D02*
X350534Y543996D01*
G01X350569Y544016D02*
X350549Y544010D01*
G01X350534Y547146D02*
X350529Y547126D01*
G01X350549Y547160D02*
X350534Y547146D01*
G01X350569Y547165D02*
X350549Y547160D01*
G01X350534Y550295D02*
X350529Y550276D01*
G01X350549Y550309D02*
X350534Y550295D01*
G01X350569Y550315D02*
X350549Y550309D01*
G01X350534Y553445D02*
X350529Y553425D01*
G01X350549Y553459D02*
X350534Y553445D01*
G01X350569Y553465D02*
X350549Y553459D01*
G01X350534Y556594D02*
X350529Y556575D01*
G01X350549Y556609D02*
X350534Y556594D01*
G01X350569Y556614D02*
X350549Y556609D01*
G01X351509Y536555D02*
X351514Y536575D01*
G01X351494Y536541D02*
X351509Y536555D01*
G01X351475Y536535D02*
X351494Y536541D01*
G01X351509Y539705D02*
X351514Y539724D01*
G01X351494Y539690D02*
X351509Y539705D01*
G01X351475Y539685D02*
X351494Y539690D01*
G01X351509Y542854D02*
X351514Y542874D01*
G01X351494Y542840D02*
X351509Y542854D01*
G01X351475Y542835D02*
X351494Y542840D01*
G01X351509Y546004D02*
X351514Y546024D01*
G01X351494Y545989D02*
X351509Y546004D01*
G01X351475Y545984D02*
X351494Y545989D01*
G01X351509Y549154D02*
X351514Y549173D01*
G01X351494Y549139D02*
X351509Y549154D01*
G01X351475Y549134D02*
X351494Y549139D01*
G01X351509Y552303D02*
X351514Y552323D01*
G01X351494Y552289D02*
X351509Y552303D01*
G01X351475Y552283D02*
X351494Y552289D01*
G01X351509Y555453D02*
X351514Y555472D01*
G01X351494Y555438D02*
X351509Y555453D01*
G01X351475Y555433D02*
X351494Y555438D01*
G01X355512Y477894D02*
G03X356102Y477303I591J0D01*
G01X362795D02*
G03X363386Y477894I0J591D01*
G01X360630Y479075D02*
G03Y481043I0J984D01*
G01X358268D02*
G03Y479075I0J-984D01*
G01X360551Y492264D02*
G03I-1102J0D01*
G01X362008Y486988D02*
G03X363189Y488169I0J1181D01*
G01X355709D02*
G03X356890Y486988I1181J0D01*
G01X361024Y492264D02*
G03I-1575J0D01*
G01X348622Y478484D02*
G03X350591Y476516I1968J0D01*
G01X368307D02*
G03X370276Y478484I0J1969D01*
G01X350529Y549170D02*
X350418Y549173D01*
G01X364941Y570256D02*
X363957D01*
G01X363958Y569764D02*
X369291D01*
G01Y569724D02*
X364943D01*
G01X369291Y568386D02*
X363958D01*
G01X363957Y567894D02*
X364941D01*
G01Y565256D02*
X363957D01*
G01X363958Y564764D02*
X369291D01*
G01Y564724D02*
X364943D01*
G01X369291Y563386D02*
X363958D01*
G01X363957Y562894D02*
X364941D01*
G01Y560256D02*
X363957D01*
G01X363958Y559764D02*
X369291D01*
G01Y559724D02*
X364943D01*
G01X351969Y558780D02*
X348622D01*
G01X369291Y558386D02*
X363958D01*
G01X363957Y557894D02*
X364941D01*
G01X361614Y557618D02*
X365551D01*
G01X351476Y556811D02*
X350571D01*
G01X351516Y556772D02*
X350531D01*
G01X351475Y556614D02*
X345591D01*
G01Y556575D02*
X351515D01*
G01X360433Y556437D02*
X364370D01*
G01X351514Y555472D02*
X345591D01*
G01X351475Y555433D02*
X345591D01*
G01X350531Y555276D02*
X351516D01*
G01X350571Y555236D02*
X351476D01*
G01Y553661D02*
X350571D01*
G01X351516Y553622D02*
X350531D01*
G01X351475Y553465D02*
X345591D01*
G01Y553425D02*
X351515D01*
G01X351514Y552323D02*
X345591D01*
G01X351475Y552283D02*
X345591D01*
G01X350531Y552126D02*
X351516D01*
G01X350571Y552087D02*
X351476D01*
G01Y550512D02*
X350571D01*
G01X351516Y550472D02*
X350531D01*
G01X351475Y550315D02*
X345591D01*
G01Y550276D02*
X351515D01*
G01X351514Y549173D02*
X345591D01*
G01X351475Y549134D02*
X345591D01*
G01X350531Y548976D02*
X351516D01*
G01X350571Y548937D02*
X351476D01*
G01Y547362D02*
X350571D01*
G01X351516Y547323D02*
X350531D01*
G01X351475Y547165D02*
X345591D01*
G01Y547126D02*
X351515D01*
G01X351514Y546024D02*
X345591D01*
G01X351475Y545984D02*
X345591D01*
G01X350531Y545827D02*
X351516D01*
G01X350571Y545787D02*
X351476D01*
G01Y544213D02*
X350571D01*
G01X351516Y544173D02*
X350531D01*
G01X351475Y544016D02*
X345591D01*
G01Y543976D02*
X351515D01*
G01X351514Y542874D02*
X345591D01*
G01X351475Y542835D02*
X345591D01*
G01X350531Y542677D02*
X351516D01*
G01X350571Y542638D02*
X351476D01*
G01Y541063D02*
X350571D01*
G01X351516Y541024D02*
X350531D01*
G01X351475Y540866D02*
X345591D01*
G01Y540827D02*
X351515D01*
G01X351514Y539724D02*
X345591D01*
G01X351475Y539685D02*
X345591D01*
G01X350531Y539528D02*
X351516D01*
G01X350571Y539488D02*
X351476D01*
G01Y537913D02*
X350571D01*
G01X351516Y537874D02*
X350531D01*
G01X351475Y537717D02*
X345591D01*
G01Y537677D02*
X351515D01*
G01X364370Y536713D02*
X360433D01*
G01X351514Y536575D02*
X345591D01*
G01X351475Y536535D02*
X345591D01*
G01X350531Y536378D02*
X351516D01*
G01X350571Y536339D02*
X351476D01*
G01X365551Y535531D02*
X361614D01*
G01X364941Y535256D02*
X363957D01*
G01X363958Y534764D02*
X369291D01*
G01Y534724D02*
X364943D01*
G01X351969Y534370D02*
X348622D01*
G01X369291Y533386D02*
X363958D01*
G01X363957Y532894D02*
X364941D01*
G01Y530256D02*
X363957D01*
G01X363958Y529764D02*
X369291D01*
G01Y529724D02*
X364943D01*
G01X369291Y528386D02*
X363958D01*
G01X363957Y569959D02*
X364912Y569961D01*
G01X364941Y568190D02*
X363957Y568189D01*
G01Y564959D02*
X364912Y564961D01*
G01X364941Y563190D02*
X363957Y563189D01*
G01Y559959D02*
X364912Y559961D01*
G01X364941Y558190D02*
X363957Y558189D01*
G01Y534959D02*
X364912Y534961D01*
G01X364941Y533190D02*
X363957Y533189D01*
G01Y529959D02*
X364912Y529961D01*
G01X364941Y528190D02*
X363957Y528189D01*
G01X350418Y555472D02*
X350530Y555464D01*
G01X350529Y546019D02*
X350418Y546024D01*
G01X350529Y539721D02*
X350418Y539724D01*
G01X363957Y527894D02*
X364941D01*
G01Y525256D02*
X363957D01*
G01X363958Y524764D02*
X369291D01*
G01Y524724D02*
X364943D01*
G01X369291Y523386D02*
X363958D01*
G01X363957Y522894D02*
X364941D01*
G01Y520256D02*
X363957D01*
G01X363958Y519764D02*
X369291D01*
G01Y519724D02*
X364943D01*
G01X369291Y518386D02*
X363958D01*
G01X363957Y517894D02*
X364941D01*
G01Y515256D02*
X363957D01*
G01X363958Y514764D02*
X369291D01*
G01Y514724D02*
X364943D01*
G01X369291Y513386D02*
X363958D01*
G01X363957Y512894D02*
X364941D01*
G01Y510256D02*
X363957D01*
G01X363958Y509764D02*
X369291D01*
G01Y509724D02*
X364943D01*
G01X369291Y508386D02*
X363958D01*
G01X363957Y507894D02*
X364941D01*
G01Y505256D02*
X363957D01*
G01X363958Y504764D02*
X369291D01*
G01Y504724D02*
X364943D01*
G01X369291Y503386D02*
X363958D01*
G01X363957Y502894D02*
X364941D01*
G01X360433Y500256D02*
X354921D01*
G01X361614Y499075D02*
X353740D01*
G01X366929Y497579D02*
X351969D01*
G01X363189Y496713D02*
X366339D01*
G01X355709D02*
X351969D01*
G01Y495335D02*
X366339D01*
G01X360630Y493366D02*
X358268D01*
G01X360630Y491673D02*
X358268D01*
G01X362008Y486988D02*
X356890D01*
G01X370276Y486949D02*
X348622D01*
G01X363386Y483996D02*
X355512D01*
G01Y482421D02*
X363386D01*
G01X360630Y481043D02*
X358268D01*
G01Y479075D02*
X360630D01*
G01X362795Y477303D02*
X356102D01*
G01X368307Y476516D02*
X350591D01*
G01X363957Y524959D02*
X364912Y524961D01*
G01X364941Y523190D02*
X363957Y523189D01*
G01Y519959D02*
X364912Y519961D01*
G01X364941Y518190D02*
X363957Y518189D01*
G01Y514959D02*
X364912Y514961D01*
G01X364941Y513190D02*
X363957Y513189D01*
G01Y509959D02*
X364912Y509961D01*
G01X364941Y508190D02*
X363957Y508189D01*
G01Y504959D02*
X364912Y504961D01*
G01X364941Y503190D02*
X363957Y503189D01*
G01X354921Y500256D02*
X353740Y499075D01*
G01X351969Y497579D02*
X348622Y494232D01*
G01X364370Y556437D02*
X365551Y557618D01*
G01X360433Y556437D02*
X361614Y557618D01*
G01X361933Y495335D02*
X360630Y493366D01*
G01X355957Y487444D02*
X358268Y491673D01*
G01X364370Y536713D02*
X365551Y535531D01*
G01X360433Y536713D02*
X361614Y535531D01*
G01X366929Y497579D02*
X370276Y494232D01*
G01X360433Y500256D02*
X361614Y499075D01*
G01X351515Y537679D02*
X351516Y537691D01*
G01X351515Y540829D02*
X351516Y540840D01*
G01X351515Y543978D02*
X351516Y543990D01*
G01X351515Y547128D02*
X351516Y547139D01*
G01X351515Y550278D02*
X351516Y550289D01*
G01X351515Y553427D02*
X351516Y553439D01*
G01X351515Y556577D02*
X351516Y556588D01*
G01X364941Y504738D02*
Y504746D01*
G01Y509738D02*
Y509746D01*
G01Y514738D02*
Y514746D01*
G01Y519738D02*
Y519746D01*
G01Y524738D02*
Y524746D01*
G01Y529738D02*
Y529746D01*
G01Y534738D02*
Y534746D01*
G01Y559738D02*
Y559746D01*
G01Y564738D02*
Y564746D01*
G01Y569738D02*
Y569746D01*
G01X370276Y478484D02*
Y494232D01*
G01X369291Y568386D02*
Y569764D01*
G01Y563386D02*
Y564764D01*
G01Y558386D02*
Y559764D01*
G01Y533386D02*
Y534764D01*
G01Y528386D02*
Y529764D01*
G01Y523386D02*
Y524764D01*
G01Y518386D02*
Y519764D01*
G01Y513386D02*
Y514764D01*
G01Y508386D02*
Y509764D01*
G01Y503386D02*
Y504764D01*
G01X366929Y635571D02*
Y497579D01*
G01X366339Y637815D02*
Y495335D01*
G01X366122Y504764D02*
Y503386D01*
G01Y509764D02*
Y508386D01*
G01Y514764D02*
Y513386D01*
G01Y519764D02*
Y518386D01*
G01Y524764D02*
Y523386D01*
G01Y529764D02*
Y528386D01*
G01Y534764D02*
Y533386D01*
G01Y559764D02*
Y558386D01*
G01Y564764D02*
Y563386D01*
G01Y569764D02*
Y568386D01*
G01X365551Y557618D02*
Y535531D01*
G01X364941Y504738D02*
Y504881D01*
G01Y514738D02*
Y514881D01*
G01Y509738D02*
Y509881D01*
G01Y524738D02*
Y524881D01*
G01Y519738D02*
Y519881D01*
G01Y534738D02*
Y534881D01*
G01Y529738D02*
Y529881D01*
G01Y564738D02*
Y564881D01*
G01Y559738D02*
Y559881D01*
G01Y567894D02*
Y570256D01*
G01Y562894D02*
Y565256D01*
G01Y557894D02*
Y560256D01*
G01Y532894D02*
Y535256D01*
G01Y527894D02*
Y530256D01*
G01Y522894D02*
Y525256D01*
G01Y517894D02*
Y520256D01*
G01Y512894D02*
Y515256D01*
G01Y507894D02*
Y510256D01*
G01Y502894D02*
Y505256D01*
G01X364370Y556437D02*
Y536713D01*
G01X363957Y505256D02*
Y502894D01*
G01Y510256D02*
Y507894D01*
G01Y515256D02*
Y512894D01*
G01Y520256D02*
Y517894D01*
G01Y525256D02*
Y522894D01*
G01Y530256D02*
Y527894D01*
G01Y535256D02*
Y532894D01*
G01Y560256D02*
Y557894D01*
G01Y565256D02*
Y562894D01*
G01Y570256D02*
Y567894D01*
G01X363386Y483996D02*
Y477894D01*
G01X363189Y496713D02*
Y488169D01*
G01X361614Y535531D02*
Y499075D01*
G01Y634075D02*
Y557618D01*
G01X360630Y493366D02*
Y491673D01*
G01X360433Y536713D02*
Y500256D01*
G01Y632894D02*
Y556437D01*
G01X358268Y491673D02*
Y493366D01*
G01X355709Y488169D02*
Y496713D01*
G01X355512Y483996D02*
Y477894D01*
G01X354921Y500256D02*
Y632894D01*
G01X353740Y499075D02*
Y634075D01*
G01X351969Y534370D02*
Y495335D01*
G01Y637815D02*
Y558780D01*
G01X351516Y555275D02*
Y556772D01*
G01Y552126D02*
Y553622D01*
G01Y548976D02*
Y550472D01*
G01Y545826D02*
Y547323D01*
G01Y542677D02*
Y544173D01*
G01Y539527D02*
Y541024D01*
G01Y536378D02*
Y537874D01*
G01X351476Y536524D02*
Y536377D01*
G01Y539674D02*
Y539527D01*
G01Y541024D02*
Y540877D01*
G01Y537874D02*
Y537728D01*
G01Y545973D02*
Y545826D01*
G01Y542823D02*
Y542676D01*
G01Y544174D02*
Y544027D01*
G01Y549122D02*
Y548976D01*
G01Y550473D02*
Y550326D01*
G01Y547323D02*
Y547176D01*
G01Y555422D02*
Y555275D01*
G01Y552272D02*
Y552125D01*
G01Y553622D02*
Y553476D01*
G01Y556772D02*
Y556625D01*
G01X350571D02*
Y556772D01*
G01Y555275D02*
Y555422D01*
G01Y552125D02*
Y552272D01*
G01Y553476D02*
Y553622D01*
G01Y548976D02*
Y549122D01*
G01Y550326D02*
Y550473D01*
G01Y547176D02*
Y547323D01*
G01Y545826D02*
Y545973D01*
G01Y542676D02*
Y542823D01*
G01Y544027D02*
Y544174D01*
G01Y539527D02*
Y539674D01*
G01Y540877D02*
Y541024D01*
G01Y537728D02*
Y537874D01*
G01Y536377D02*
Y536524D01*
G01X350531Y541024D02*
Y539528D01*
G01Y537874D02*
Y536378D01*
G01Y544173D02*
Y542677D01*
G01Y550472D02*
Y548976D01*
G01Y547323D02*
Y545827D01*
G01Y553622D02*
Y552126D01*
G01Y556772D02*
Y555276D01*
G01X349350Y537717D02*
Y536535D01*
G01Y540866D02*
Y539685D01*
G01Y547165D02*
Y545984D01*
G01Y544016D02*
Y542835D01*
G01Y550315D02*
Y549134D01*
G01Y556614D02*
Y555433D01*
G01Y553465D02*
Y552283D01*
G01X349016Y558780D02*
Y534370D01*
G01X348622D02*
Y558780D01*
G01Y494232D02*
Y478484D01*
G01X345591Y555433D02*
Y556614D01*
G01Y552283D02*
Y553465D01*
G01Y549134D02*
Y550315D01*
G01Y545984D02*
Y547165D01*
G01Y542835D02*
Y544016D01*
G01Y539685D02*
Y540866D01*
G01Y536535D02*
Y537717D01*
G01X351516Y555459D02*
X351515Y555470D01*
G01X351516Y552309D02*
X351515Y552320D01*
G01X351516Y549160D02*
X351515Y549170D01*
G01X351516Y546010D02*
X351515Y546021D01*
G01X351516Y542861D02*
X351515Y542871D01*
G01X351516Y539711D02*
X351515Y539722D01*
G01X351516Y536561D02*
X351515Y536572D01*
G01X351475Y552283D02*
X351478Y552272D01*
G01X360630Y491673D02*
X362940Y487444D01*
G01X358268Y493366D02*
X356964Y495335D01*
G01X364908Y574862D02*
X364912Y574961D01*
G01X364902Y574790D02*
X364908Y574862D01*
G01X364904Y574764D02*
X364902Y574790D01*
G01X364908Y579862D02*
X364912Y579961D01*
G01X364902Y579790D02*
X364908Y579862D01*
G01X364904Y579764D02*
X364902Y579790D01*
G01X364908Y584862D02*
X364912Y584961D01*
G01X364902Y584790D02*
X364908Y584862D01*
G01X364904Y584764D02*
X364902Y584790D01*
G01X364908Y589862D02*
X364912Y589961D01*
G01X364902Y589790D02*
X364908Y589862D01*
G01X364904Y589764D02*
X364902Y589790D01*
G01X364908Y594862D02*
X364912Y594961D01*
G01X364902Y594790D02*
X364908Y594862D01*
G01X364904Y594764D02*
X364902Y594790D01*
G01X364908Y599862D02*
X364912Y599961D01*
G01X364902Y599790D02*
X364908Y599862D01*
G01X364904Y599764D02*
X364902Y599790D01*
G01X364908Y604862D02*
X364912Y604961D01*
G01X364902Y604790D02*
X364908Y604862D01*
G01X364904Y604764D02*
X364902Y604790D01*
G01X364908Y609862D02*
X364912Y609961D01*
G01X364902Y609790D02*
X364908Y609862D01*
G01X364904Y609764D02*
X364902Y609790D01*
G01X364908Y614862D02*
X364912Y614961D01*
G01X364902Y614790D02*
X364908Y614862D01*
G01X364904Y614764D02*
X364902Y614790D01*
G01X364908Y619862D02*
X364912Y619961D01*
G01X364902Y619790D02*
X364908Y619862D01*
G01X364904Y619764D02*
X364902Y619790D01*
G01X364908Y624862D02*
X364912Y624961D01*
G01X364902Y624790D02*
X364908Y624862D01*
G01X364904Y624764D02*
X364902Y624790D01*
G01X364908Y629862D02*
X364912Y629961D01*
G01X364902Y629790D02*
X364908Y629862D01*
G01X364904Y629764D02*
X364902Y629790D01*
G01X363957Y628384D02*
X363958Y628386D01*
G01X363957Y628378D02*
Y628384D01*
G01Y628370D02*
Y628378D01*
G01Y623384D02*
X363958Y623386D01*
G01X363957Y623378D02*
Y623384D01*
G01Y623370D02*
Y623378D01*
G01Y618384D02*
X363958Y618386D01*
G01X363957Y618378D02*
Y618384D01*
G01Y618370D02*
Y618378D01*
G01Y613384D02*
X363958Y613386D01*
G01X363957Y613378D02*
Y613384D01*
G01Y613370D02*
Y613378D01*
G01Y608384D02*
X363958Y608386D01*
G01X363957Y608378D02*
Y608384D01*
G01Y608370D02*
Y608378D01*
G01Y603384D02*
X363958Y603386D01*
G01X363957Y603378D02*
Y603384D01*
G01Y603370D02*
Y603378D01*
G01Y598384D02*
X363958Y598386D01*
G01X363957Y598378D02*
Y598384D01*
G01Y598370D02*
Y598378D01*
G01Y593384D02*
X363958Y593386D01*
G01X363957Y593378D02*
Y593384D01*
G01Y593370D02*
Y593378D01*
G01Y588384D02*
X363958Y588386D01*
G01X363957Y588378D02*
Y588384D01*
G01Y588370D02*
Y588378D01*
G01Y583384D02*
X363958Y583386D01*
G01X363957Y583378D02*
Y583384D01*
G01Y583370D02*
Y583378D01*
G01Y578384D02*
X363958Y578386D01*
G01X363957Y578378D02*
Y578384D01*
G01Y578370D02*
Y578378D01*
G01Y573384D02*
X363958Y573386D01*
G01X363957Y573378D02*
Y573384D01*
G01Y573370D02*
Y573378D01*
G01X364941Y574731D02*
Y574738D01*
G01X364942Y574726D02*
X364941Y574731D01*
G01X364943Y574724D02*
X364942Y574726D01*
G01X364941Y579731D02*
Y579738D01*
G01X364942Y579726D02*
X364941Y579731D01*
G01X364943Y579724D02*
X364942Y579726D01*
G01X364941Y584731D02*
Y584738D01*
G01X364942Y584726D02*
X364941Y584731D01*
G01X364943Y584724D02*
X364942Y584726D01*
G01X364941Y589731D02*
Y589738D01*
G01X364942Y589726D02*
X364941Y589731D01*
G01X364943Y589724D02*
X364942Y589726D01*
G01X364941Y594731D02*
Y594738D01*
G01X364942Y594726D02*
X364941Y594731D01*
G01X364943Y594724D02*
X364942Y594726D01*
G01X364941Y599731D02*
Y599738D01*
G01X364942Y599726D02*
X364941Y599731D01*
G01X364943Y599724D02*
X364942Y599726D01*
G01X364941Y604731D02*
Y604738D01*
G01X364942Y604726D02*
X364941Y604731D01*
G01X364943Y604724D02*
X364942Y604726D01*
G01X364941Y609731D02*
Y609738D01*
G01X364942Y609726D02*
X364941Y609731D01*
G01X364943Y609724D02*
X364942Y609726D01*
G01X364941Y614731D02*
Y614738D01*
G01X364942Y614726D02*
X364941Y614731D01*
G01X364943Y614724D02*
X364942Y614726D01*
G01X364941Y619731D02*
Y619738D01*
G01X364942Y619726D02*
X364941Y619731D01*
G01X364943Y619724D02*
X364942Y619726D01*
G01X363957Y574771D02*
Y574780D01*
G01Y574765D02*
Y574771D01*
G01X363958Y574764D02*
X363957Y574765D01*
G01Y579771D02*
Y579780D01*
G01Y579765D02*
Y579771D01*
G01X363958Y579764D02*
X363957Y579765D01*
G01Y584771D02*
Y584780D01*
G01Y584765D02*
Y584771D01*
G01X363958Y584764D02*
X363957Y584765D01*
G01Y589771D02*
Y589780D01*
G01Y589765D02*
Y589771D01*
G01X363958Y589764D02*
X363957Y589765D01*
G01Y594771D02*
Y594780D01*
G01Y594765D02*
Y594771D01*
G01X363958Y594764D02*
X363957Y594765D01*
G01Y599771D02*
Y599780D01*
G01Y599765D02*
Y599771D01*
G01X363958Y599764D02*
X363957Y599765D01*
G01Y604771D02*
Y604780D01*
G01Y604765D02*
Y604771D01*
G01X363958Y604764D02*
X363957Y604765D01*
G01Y609771D02*
Y609780D01*
G01Y609765D02*
Y609771D01*
G01X363958Y609764D02*
X363957Y609765D01*
G01Y614771D02*
Y614780D01*
G01Y614765D02*
Y614771D01*
G01X363958Y614764D02*
X363957Y614765D01*
G01Y619771D02*
Y619780D01*
G01Y619765D02*
Y619771D01*
G01X363958Y619764D02*
X363957Y619765D01*
G01Y624771D02*
Y624780D01*
G01Y624765D02*
Y624771D01*
G01X363958Y624764D02*
X363957Y624765D01*
G01Y629771D02*
Y629780D01*
G01Y629765D02*
Y629771D01*
G01X363958Y629764D02*
X363957Y629765D01*
G01X364933Y574907D02*
X364941Y574881D01*
G01X364923Y574934D02*
X364933Y574907D01*
G01X364912Y574961D02*
X364923Y574934D01*
G01X364933Y579907D02*
X364941Y579881D01*
G01X364923Y579934D02*
X364933Y579907D01*
G01X364912Y579961D02*
X364923Y579934D01*
G01X364933Y584907D02*
X364941Y584881D01*
G01X364923Y584934D02*
X364933Y584907D01*
G01X364912Y584961D02*
X364923Y584934D01*
G01X364933Y589907D02*
X364941Y589881D01*
G01X364923Y589934D02*
X364933Y589907D01*
G01X364912Y589961D02*
X364923Y589934D01*
G01X364933Y594907D02*
X364941Y594881D01*
G01X364923Y594934D02*
X364933Y594907D01*
G01X364912Y594961D02*
X364923Y594934D01*
G01X364933Y599907D02*
X364941Y599881D01*
G01X364923Y599934D02*
X364933Y599907D01*
G01X364912Y599961D02*
X364923Y599934D01*
G01X364933Y604907D02*
X364941Y604881D01*
G01X364923Y604934D02*
X364933Y604907D01*
G01X364912Y604961D02*
X364923Y604934D01*
G01X364933Y609907D02*
X364941Y609881D01*
G01X364923Y609934D02*
X364933Y609907D01*
G01X364912Y609961D02*
X364923Y609934D01*
G01X364933Y614907D02*
X364941Y614881D01*
G01X364923Y614934D02*
X364933Y614907D01*
G01X364912Y614961D02*
X364923Y614934D01*
G01X364933Y619907D02*
X364941Y619881D01*
G01X364923Y619934D02*
X364933Y619907D01*
G01X364912Y619961D02*
X364923Y619934D01*
G01X364933Y624907D02*
X364941Y624881D01*
G01X364923Y624934D02*
X364933Y624907D01*
G01X364912Y624961D02*
X364923Y624934D01*
G01X364933Y629907D02*
X364941Y629881D01*
G01X364923Y629934D02*
X364933Y629907D01*
G01X364912Y629961D02*
X364923Y629934D01*
G01X364924Y574759D02*
X364904Y574764D01*
G01X364938Y574744D02*
X364924Y574759D01*
G01X364943Y574724D02*
X364938Y574744D01*
G01X364924Y579759D02*
X364904Y579764D01*
G01X364938Y579744D02*
X364924Y579759D01*
G01X364943Y579724D02*
X364938Y579744D01*
G01X364924Y584759D02*
X364904Y584764D01*
G01X364938Y584744D02*
X364924Y584759D01*
G01X364943Y584724D02*
X364938Y584744D01*
G01X364924Y589759D02*
X364904Y589764D01*
G01X364938Y589744D02*
X364924Y589759D01*
G01X364943Y589724D02*
X364938Y589744D01*
G01X364924Y594759D02*
X364904Y594764D01*
G01X364938Y594744D02*
X364924Y594759D01*
G01X364943Y594724D02*
X364938Y594744D01*
G01X364924Y599759D02*
X364904Y599764D01*
G01X364938Y599744D02*
X364924Y599759D01*
G01X364943Y599724D02*
X364938Y599744D01*
G01X364924Y604759D02*
X364904Y604764D01*
G01X364938Y604744D02*
X364924Y604759D01*
G01X364943Y604724D02*
X364938Y604744D01*
G01X364924Y609759D02*
X364904Y609764D01*
G01X364938Y609744D02*
X364924Y609759D01*
G01X364943Y609724D02*
X364938Y609744D01*
G01X364924Y614759D02*
X364904Y614764D01*
G01X364938Y614744D02*
X364924Y614759D01*
G01X364943Y614724D02*
X364938Y614744D01*
G01X364924Y619759D02*
X364904Y619764D01*
G01X364938Y619744D02*
X364924Y619759D01*
G01X364943Y619724D02*
X364938Y619744D01*
G01X364924Y624759D02*
X364904Y624764D01*
G01X364938Y624744D02*
X364924Y624759D01*
G01X364943Y624724D02*
X364938Y624744D01*
G01X364924Y629759D02*
X364904Y629764D01*
G01X364938Y629744D02*
X364924Y629759D01*
G01X364943Y629724D02*
X364938Y629744D01*
G01X364941Y624731D02*
Y624738D01*
G01X364942Y624726D02*
X364941Y624731D01*
G01X364943Y624724D02*
X364942Y624726D01*
G01X364941Y629731D02*
Y629738D01*
G01X364942Y629726D02*
X364941Y629731D01*
G01X364943Y629724D02*
X364942Y629726D01*
G01X364941Y628378D02*
Y628369D01*
G01X364942Y628384D02*
X364941Y628378D01*
G01X364944Y628386D02*
X364942Y628384D01*
G01X364941Y623378D02*
Y623369D01*
G01X364942Y623384D02*
X364941Y623378D01*
G01X364944Y623386D02*
X364942Y623384D01*
G01X364941Y618378D02*
Y618369D01*
G01X364942Y618384D02*
X364941Y618378D01*
G01X364944Y618386D02*
X364942Y618384D01*
G01X364941Y613378D02*
Y613369D01*
G01X364942Y613384D02*
X364941Y613378D01*
G01X364944Y613386D02*
X364942Y613384D01*
G01X364941Y608378D02*
Y608369D01*
G01X364942Y608384D02*
X364941Y608378D01*
G01X364944Y608386D02*
X364942Y608384D01*
G01X364941Y603378D02*
Y603369D01*
G01X364942Y603384D02*
X364941Y603378D01*
G01X364944Y603386D02*
X364942Y603384D01*
G01X364941Y598378D02*
Y598369D01*
G01X364942Y598384D02*
X364941Y598378D01*
G01X364944Y598386D02*
X364942Y598384D01*
G01X364941Y593378D02*
Y593369D01*
G01X364942Y593384D02*
X364941Y593378D01*
G01X364944Y593386D02*
X364942Y593384D01*
G01X364941Y588378D02*
Y588369D01*
G01X364942Y588384D02*
X364941Y588378D01*
G01X364944Y588386D02*
X364942Y588384D01*
G01X364941Y583378D02*
Y583369D01*
G01X364942Y583384D02*
X364941Y583378D01*
G01X364944Y583386D02*
X364942Y583384D01*
G01X364941Y578378D02*
Y578369D01*
G01X364942Y578384D02*
X364941Y578378D01*
G01X364944Y578386D02*
X364942Y578384D01*
G01X364941Y573378D02*
Y573369D01*
G01X364942Y573384D02*
X364941Y573378D01*
G01X364944Y573386D02*
X364942Y573384D01*
G01X364928Y574755D02*
X364939Y574740D01*
G01X364904Y574764D02*
X364928Y574755D01*
G01Y579755D02*
X364939Y579740D01*
G01X364904Y579764D02*
X364928Y579755D01*
G01Y584755D02*
X364939Y584740D01*
G01X364904Y584764D02*
X364928Y584755D01*
G01Y589755D02*
X364939Y589740D01*
G01X364904Y589764D02*
X364928Y589755D01*
G01Y594755D02*
X364939Y594740D01*
G01X364904Y594764D02*
X364928Y594755D01*
G01Y599755D02*
X364939Y599740D01*
G01X364904Y599764D02*
X364928Y599755D01*
G01Y604755D02*
X364939Y604740D01*
G01X364904Y604764D02*
X364928Y604755D01*
G01Y609755D02*
X364939Y609740D01*
G01X364904Y609764D02*
X364928Y609755D01*
G01Y614755D02*
X364939Y614740D01*
G01X364904Y614764D02*
X364928Y614755D01*
G01Y619755D02*
X364939Y619740D01*
G01X364904Y619764D02*
X364928Y619755D01*
G01Y624755D02*
X364939Y624740D01*
G01X364904Y624764D02*
X364928Y624755D01*
G01Y629755D02*
X364939Y629740D01*
G01X364904Y629764D02*
X364928Y629755D01*
G01X363386Y655256D02*
G03X362795Y655846I-590J0D01*
G01X356102D02*
G03X355512Y655256I0J-590D01*
G01X358268Y654075D02*
G03Y652106I0J-985D01*
G01X360630D02*
G03Y654075I0J984D01*
G01X356890Y646161D02*
G03X355709Y644980I0J-1181D01*
G01X363189D02*
G03X362008Y646161I-1181J0D01*
G01X361339Y640886D02*
G03I-1890J0D01*
G01X370276Y654665D02*
G03X368307Y656634I-1969J0D01*
G01X350591D02*
G03X348622Y654665I0J-1969D01*
G01X361811Y640886D02*
G03I-2362J0D01*
G01X368307Y656634D02*
X350591D01*
G01X362795Y655846D02*
X356102D01*
G01X360630Y654075D02*
X358268D01*
G01Y652106D02*
X360630D01*
G01X363386Y650728D02*
X355512D01*
G01Y649154D02*
X363386D01*
G01X370276Y646201D02*
X348622D01*
G01X356890Y646161D02*
X362008D01*
G01X358268Y641476D02*
X360630D01*
G01X358268Y639783D02*
X360630D01*
G01X351969Y637815D02*
X366339D01*
G01X351969Y636437D02*
X355709D01*
G01X366339D02*
X363189D01*
G01X351969Y635571D02*
X366929D01*
G01X353740Y634075D02*
X361614D01*
G01X354921Y632894D02*
X360433D01*
G01X364941Y630256D02*
X363957D01*
G01X363958Y629764D02*
X369291D01*
G01Y629724D02*
X364943D01*
G01X369291Y628386D02*
X363958D01*
G01X363957Y627894D02*
X364941D01*
G01Y625256D02*
X363957D01*
G01X363958Y624764D02*
X369291D01*
G01Y624724D02*
X364943D01*
G01X369291Y623386D02*
X363958D01*
G01X363957Y622894D02*
X364941D01*
G01Y620256D02*
X363957D01*
G01X363958Y619764D02*
X369291D01*
G01Y619724D02*
X364943D01*
G01X369291Y618386D02*
X363958D01*
G01X363957Y617894D02*
X364941D01*
G01Y615256D02*
X363957D01*
G01X363958Y614764D02*
X369291D01*
G01Y614724D02*
X364943D01*
G01X369291Y613386D02*
X363958D01*
G01X363957Y612894D02*
X364941D01*
G01Y610256D02*
X363957D01*
G01Y629959D02*
X364912Y629961D01*
G01X364941Y628190D02*
X363957Y628189D01*
G01Y624959D02*
X364912Y624961D01*
G01X364941Y623190D02*
X363957Y623189D01*
G01Y619959D02*
X364912Y619961D01*
G01X364941Y618190D02*
X363957Y618189D01*
G01Y614959D02*
X364912Y614961D01*
G01X364941Y613190D02*
X363957Y613189D01*
G01Y609959D02*
X364912Y609961D01*
G01X363958Y609764D02*
X369291D01*
G01Y609724D02*
X364943D01*
G01X369291Y608386D02*
X363958D01*
G01X363957Y607894D02*
X364941D01*
G01Y605256D02*
X363957D01*
G01X363958Y604764D02*
X369291D01*
G01Y604724D02*
X364943D01*
G01X369291Y603386D02*
X363958D01*
G01X363957Y602894D02*
X364941D01*
G01Y600256D02*
X363957D01*
G01X363958Y599764D02*
X369291D01*
G01Y599724D02*
X364943D01*
G01X369291Y598386D02*
X363958D01*
G01X363957Y597894D02*
X364941D01*
G01Y595256D02*
X363957D01*
G01X363958Y594764D02*
X369291D01*
G01Y594724D02*
X364943D01*
G01X369291Y593386D02*
X363958D01*
G01X363957Y592894D02*
X364941D01*
G01Y590256D02*
X363957D01*
G01X363958Y589764D02*
X369291D01*
G01Y589724D02*
X364943D01*
G01X369291Y588386D02*
X363958D01*
G01X363957Y587894D02*
X364941D01*
G01Y585256D02*
X363957D01*
G01X363958Y584764D02*
X369291D01*
G01Y584724D02*
X364943D01*
G01X369291Y583386D02*
X363958D01*
G01X363957Y582894D02*
X364941D01*
G01Y580256D02*
X363957D01*
G01X363958Y579764D02*
X369291D01*
G01Y579724D02*
X364943D01*
G01X369291Y578386D02*
X363958D01*
G01X363957Y577894D02*
X364941D01*
G01Y575256D02*
X363957D01*
G01X363958Y574764D02*
X369291D01*
G01Y574724D02*
X364943D01*
G01X369291Y573386D02*
X363958D01*
G01X363957Y572894D02*
X364941D01*
G01Y608190D02*
X363957Y608189D01*
G01Y604959D02*
X364912Y604961D01*
G01X364941Y603190D02*
X363957Y603189D01*
G01Y599959D02*
X364912Y599961D01*
G01X364941Y598190D02*
X363957Y598189D01*
G01Y594959D02*
X364912Y594961D01*
G01X364941Y593190D02*
X363957Y593189D01*
G01Y589959D02*
X364912Y589961D01*
G01X364941Y588190D02*
X363957Y588189D01*
G01Y584959D02*
X364912Y584961D01*
G01X364941Y583190D02*
X363957Y583189D01*
G01Y579959D02*
X364912Y579961D01*
G01X364941Y578190D02*
X363957Y578189D01*
G01Y574959D02*
X364912Y574961D01*
G01X364941Y573190D02*
X363957Y573189D01*
G01X370276Y638917D02*
X366929Y635571D01*
G01X360433Y632894D02*
X361614Y634075D01*
G01X356964Y637815D02*
X358268Y639783D01*
G01X362940Y645706D02*
X360630Y641476D01*
G01X353740Y634075D02*
X354921Y632894D01*
G01X348622Y638917D02*
X351969Y635571D01*
G01X358268Y641476D02*
X355957Y645706D01*
G01X360630Y639783D02*
X361933Y637815D01*
G01X364941Y574738D02*
Y574746D01*
G01Y579738D02*
Y579746D01*
G01Y584738D02*
Y584746D01*
G01Y589738D02*
Y589746D01*
G01Y594738D02*
Y594746D01*
G01Y599738D02*
Y599746D01*
G01Y604738D02*
Y604746D01*
G01Y609738D02*
Y609746D01*
G01Y614738D02*
Y614746D01*
G01Y619738D02*
Y619746D01*
G01Y624738D02*
Y624746D01*
G01Y629738D02*
Y629746D01*
G01X370276Y638917D02*
Y654665D01*
G01X369291Y628386D02*
Y629764D01*
G01Y623386D02*
Y624764D01*
G01Y618386D02*
Y619764D01*
G01Y613386D02*
Y614764D01*
G01Y608386D02*
Y609764D01*
G01Y603386D02*
Y604764D01*
G01Y598386D02*
Y599764D01*
G01Y593386D02*
Y594764D01*
G01Y588386D02*
Y589764D01*
G01Y583386D02*
Y584764D01*
G01Y578386D02*
Y579764D01*
G01Y573386D02*
Y574764D01*
G01X366122D02*
Y573386D01*
G01Y579764D02*
Y578386D01*
G01Y584764D02*
Y583386D01*
G01Y589764D02*
Y588386D01*
G01Y594764D02*
Y593386D01*
G01Y599764D02*
Y598386D01*
G01Y604764D02*
Y603386D01*
G01Y609764D02*
Y608386D01*
G01Y614764D02*
Y613386D01*
G01Y619764D02*
Y618386D01*
G01Y624764D02*
Y623386D01*
G01Y629764D02*
Y628386D01*
G01X364941Y627894D02*
Y630256D01*
G01Y622894D02*
Y625256D01*
G01Y617894D02*
Y620256D01*
G01Y612894D02*
Y615256D01*
G01Y607894D02*
Y610256D01*
G01Y602894D02*
Y605256D01*
G01Y597894D02*
Y600256D01*
G01Y592894D02*
Y595256D01*
G01Y587894D02*
Y590256D01*
G01Y582894D02*
Y585256D01*
G01Y577894D02*
Y580256D01*
G01Y572894D02*
Y575256D01*
G01X363957D02*
Y572894D01*
G01Y580256D02*
Y577894D01*
G01Y585256D02*
Y582894D01*
G01Y590256D02*
Y587894D01*
G01Y595256D02*
Y592894D01*
G01Y600256D02*
Y597894D01*
G01Y605256D02*
Y602894D01*
G01Y610256D02*
Y607894D01*
G01Y615256D02*
Y612894D01*
G01Y620256D02*
Y617894D01*
G01Y625256D02*
Y622894D01*
G01Y630256D02*
Y627894D01*
G01X363386Y649154D02*
Y655256D01*
G01X363189Y644980D02*
Y636437D01*
G01X360630Y641476D02*
Y639783D01*
G01X358268D02*
Y641476D01*
G01X355709Y636437D02*
Y644980D01*
G01X355512Y649154D02*
Y655256D01*
G01X348622Y654665D02*
Y638917D01*
G01X362327Y717468D02*
G03X396138I16905J-13531D01*
G01X389213Y730599D02*
G03X369252I-9981J-3040D01*
G01X362327Y717468D02*
G03X369252Y730599I-30737J24602D01*
G01X319488Y713386D02*
G03X320669I590J0D01*
G01Y707087D02*
G03X319488I-591J0D01*
G01X317520D02*
G03X316339I-590J0D01*
G01Y713386D02*
G03X317520I590J0D01*
G01X319488D02*
G03X320669I590J0D01*
G01Y707087D02*
G03X319488I-591J0D01*
G01X317520D02*
G03X316339I-590J0D01*
G01Y713386D02*
G03X317520I590J0D01*
G01X389213Y730599D02*
G03X369252I-9981J-3040D01*
G01X362327Y717468D02*
G03X396138I16905J-13531D01*
G01X362327D02*
G03X369252Y730599I-30737J24602D01*
G01X316339Y713386D02*
X315551D01*
G01X316339D02*
X315551D01*
G01X319488D02*
X317520D01*
G01X319488D02*
X317520D01*
G01X321457D02*
X320669D01*
G01X321457D02*
X320669D01*
G01X321457Y712402D02*
X315551D01*
G01Y712205D02*
X321457D01*
G01X315551Y708268D02*
X321457D01*
G01Y708071D02*
X315551D01*
G01X320669Y707087D02*
X321457D01*
G01X320669D02*
X321457D01*
G01X317520D02*
X319488D01*
G01X317520D02*
X319488D01*
G01X315551D02*
X316339D01*
G01X315551D02*
X316339D01*
G01X321457D02*
Y713386D01*
G01Y707087D02*
Y713386D01*
G01X315551Y707087D02*
Y713386D01*
G01D02*
Y707087D01*
G01X355512Y930650D02*
G03X356102Y930059I590J-1D01*
G01X362795D02*
G03X363386Y930650I0J591D01*
G01X360630Y931831D02*
G03Y933799I0J984D01*
G01X358268D02*
G03Y931831I0J-984D01*
G01X360551Y945020D02*
G03I-1102J0D01*
G01X362008Y939744D02*
G03X363189Y940925I0J1181D01*
G01X355709D02*
G03X356890Y939744I1181J0D01*
G01X361024Y945020D02*
G03I-1575J0D01*
G01X348622Y931240D02*
G03X350591Y929272I1968J0D01*
G01X368307D02*
G03X370276Y931240I1J1968D01*
G01X361614Y951831D02*
X353740D01*
G01X366929Y950335D02*
X351969D01*
G01X363189Y949469D02*
X366339D01*
G01X355709D02*
X351969D01*
G01Y948091D02*
X366339D01*
G01X360630Y946122D02*
X358268D01*
G01X360630Y944429D02*
X358268D01*
G01X362008Y939744D02*
X356890D01*
G01X370276Y939705D02*
X348622D01*
G01X363386Y936752D02*
X355512D01*
G01Y935177D02*
X363386D01*
G01X360630Y933799D02*
X358268D01*
G01Y931831D02*
X360630D01*
G01X362795Y930059D02*
X356102D01*
G01X368307Y929272D02*
X350591D01*
G01X366929Y950335D02*
X370276Y946988D01*
G01X360433Y953012D02*
X361614Y951831D01*
G01X360630Y944429D02*
X362940Y940200D01*
G01X358268Y946122D02*
X356964Y948091D01*
G01X354921Y953012D02*
X353740Y951831D01*
G01X351969Y950335D02*
X348622Y946988D01*
G01X361933Y948091D02*
X360630Y946122D01*
G01X355957Y940200D02*
X358268Y944429D01*
G01X370276Y931240D02*
Y946988D01*
G01X366929Y1088327D02*
Y950335D01*
G01X366339Y1090571D02*
Y948091D01*
G01X363386Y936752D02*
Y930650D01*
G01X363189Y949469D02*
Y940925D01*
G01X361614Y988287D02*
Y951831D01*
G01X360630Y946122D02*
Y944429D01*
G01X358268D02*
Y946122D01*
G01X355709Y940925D02*
Y949469D01*
G01X355512Y936752D02*
Y930650D01*
G01X353740Y951831D02*
Y1086831D01*
G01X351969Y987126D02*
Y948091D01*
G01X348622Y946988D02*
Y931240D01*
G01X350544Y1009361D02*
X350569Y1009370D01*
G01X350533Y1009347D02*
X350544Y1009361D01*
G01X350531Y1009340D02*
X350533Y1009347D01*
G01X350544Y1006212D02*
X350569Y1006220D01*
G01X350533Y1006197D02*
X350544Y1006212D01*
G01X350531Y1006191D02*
X350533Y1006197D01*
G01X350544Y1003062D02*
X350569Y1003071D01*
G01X350533Y1003048D02*
X350544Y1003062D01*
G01X350531Y1003041D02*
X350533Y1003048D01*
G01X350544Y999913D02*
X350569Y999921D01*
G01X350533Y999898D02*
X350544Y999913D01*
G01X350531Y999891D02*
X350533Y999898D01*
G01X350544Y996763D02*
X350569Y996772D01*
G01X350533Y996748D02*
X350544Y996763D01*
G01X350531Y996742D02*
X350533Y996748D01*
G01X350544Y993613D02*
X350569Y993622D01*
G01X350533Y993599D02*
X350544Y993613D01*
G01X350531Y993592D02*
X350533Y993599D01*
G01X350544Y990464D02*
X350569Y990472D01*
G01X350533Y990449D02*
X350544Y990464D01*
G01X350531Y990443D02*
X350533Y990449D01*
G01X351516Y1009337D02*
Y1009344D01*
G01X351515Y1009332D02*
X351516Y1009337D01*
G01X351515Y1009331D02*
Y1009332D01*
G01X351516Y1006187D02*
Y1006194D01*
G01X351515Y1006183D02*
X351516Y1006187D01*
G01X351515Y1006181D02*
Y1006183D01*
G01X351516Y1003038D02*
Y1003045D01*
G01X351515Y1003033D02*
X351516Y1003038D01*
G01X351515Y1003031D02*
Y1003033D01*
G01X351516Y999888D02*
Y999895D01*
G01X351515Y999883D02*
X351516Y999888D01*
G01X351515Y999882D02*
Y999883D01*
G01X351516Y996739D02*
Y996746D01*
G01X351515Y996734D02*
X351516Y996739D01*
G01X351515Y996732D02*
Y996734D01*
G01X351516Y993589D02*
Y993596D01*
G01X351515Y993584D02*
X351516Y993589D01*
G01X351515Y993583D02*
Y993584D01*
G01X351516Y990439D02*
Y990446D01*
G01X351515Y990435D02*
X351516Y990439D01*
G01X351515Y990433D02*
Y990435D01*
G01X350531Y998774D02*
Y998766D01*
G01X350530Y998778D02*
X350531Y998774D01*
G01X350529Y998775D02*
X350530Y998778D01*
G01X350531Y992474D02*
Y992467D01*
G01X350530Y992479D02*
X350531Y992474D01*
G01X350529Y992477D02*
X350530Y992479D01*
G01X351476Y1009375D02*
Y1009381D01*
G01Y1009371D02*
Y1009375D01*
G01X351475Y1009370D02*
X351476Y1009371D01*
G01Y1006226D02*
Y1006231D01*
G01Y1006222D02*
Y1006226D01*
G01X351475Y1006220D02*
X351476Y1006222D01*
G01Y1003076D02*
Y1003082D01*
G01Y1003072D02*
Y1003076D01*
G01X351475Y1003071D02*
X351476Y1003072D01*
G01X364941Y1046134D02*
Y1046125D01*
G01X364942Y1046140D02*
X364941Y1046134D01*
G01X364944Y1046142D02*
X364942Y1046140D01*
G01X364908Y957618D02*
X364912Y957717D01*
G01X364902Y957546D02*
X364908Y957618D01*
G01X364904Y957520D02*
X364902Y957546D01*
G01X364908Y962618D02*
X364912Y962717D01*
G01X364902Y962546D02*
X364908Y962618D01*
G01X364904Y962520D02*
X364902Y962546D01*
G01X364908Y967618D02*
X364912Y967717D01*
G01X364902Y967546D02*
X364908Y967618D01*
G01X364904Y967520D02*
X364902Y967546D01*
G01X364908Y972618D02*
X364912Y972717D01*
G01X364902Y972546D02*
X364908Y972618D01*
G01X364904Y972520D02*
X364902Y972546D01*
G01X364908Y977618D02*
X364912Y977717D01*
G01X364902Y977546D02*
X364908Y977618D01*
G01X364904Y977520D02*
X364902Y977546D01*
G01X364908Y982618D02*
X364912Y982717D01*
G01X364902Y982546D02*
X364908Y982618D01*
G01X364904Y982520D02*
X364902Y982546D01*
G01X364908Y987618D02*
X364912Y987717D01*
G01X364902Y987546D02*
X364908Y987618D01*
G01X364904Y987520D02*
X364902Y987546D01*
G01X364908Y1012618D02*
X364912Y1012717D01*
G01X364902Y1012546D02*
X364908Y1012618D01*
G01X364904Y1012520D02*
X364902Y1012546D01*
G01X364908Y1017618D02*
X364912Y1017717D01*
G01X364902Y1017546D02*
X364908Y1017618D01*
G01X364904Y1017520D02*
X364902Y1017546D01*
G01X364908Y1022618D02*
X364912Y1022717D01*
G01X364902Y1022546D02*
X364908Y1022618D01*
G01X364904Y1022520D02*
X364902Y1022546D01*
G01X364908Y1027618D02*
X364912Y1027717D01*
G01X364902Y1027546D02*
X364908Y1027618D01*
G01X364904Y1027520D02*
X364902Y1027546D01*
G01X364908Y1032618D02*
X364912Y1032717D01*
G01X364902Y1032546D02*
X364908Y1032618D01*
G01X364904Y1032520D02*
X364902Y1032546D01*
G01X364908Y1037618D02*
X364912Y1037717D01*
G01X364902Y1037546D02*
X364908Y1037618D01*
G01X364904Y1037520D02*
X364902Y1037546D01*
G01X364908Y1042618D02*
X364912Y1042717D01*
G01X364902Y1042546D02*
X364908Y1042618D01*
G01X364904Y1042520D02*
X364902Y1042546D01*
G01X350531Y1001923D02*
Y1001916D01*
G01X350530Y1001928D02*
X350531Y1001923D01*
G01Y1001918D02*
X350530Y1001928D01*
G01X350572Y1009554D02*
X350571Y1009567D01*
G01X350569Y1009541D02*
X350572Y1009554D01*
G01X350569Y1009528D02*
Y1009541D01*
G01X350572Y1006405D02*
X350571Y1006417D01*
G01X350569Y1006392D02*
X350572Y1006405D01*
G01X350569Y1006378D02*
Y1006392D01*
G01X350572Y1003255D02*
X350571Y1003268D01*
G01X350569Y1003242D02*
X350572Y1003255D01*
G01X350569Y1003228D02*
Y1003242D01*
G01X350572Y1000106D02*
X350571Y1000118D01*
G01X350569Y1000093D02*
X350572Y1000106D01*
G01X350569Y1000079D02*
Y1000093D01*
G01X350572Y996956D02*
X350571Y996969D01*
G01X350569Y996943D02*
X350572Y996956D01*
G01X350569Y996929D02*
Y996943D01*
G01X350572Y993806D02*
X350571Y993819D01*
G01X350569Y993793D02*
X350572Y993806D01*
G01X350569Y993780D02*
Y993793D01*
G01X350572Y990657D02*
X350571Y990669D01*
G01X350569Y990644D02*
X350572Y990657D01*
G01X350569Y990630D02*
Y990644D01*
G01X363957Y1046140D02*
X363958Y1046142D01*
G01X363957Y1046134D02*
Y1046140D01*
G01Y1046126D02*
Y1046134D01*
G01Y1041140D02*
X363958Y1041142D01*
G01X363957Y1041134D02*
Y1041140D01*
G01Y1041126D02*
Y1041134D01*
G01Y1036140D02*
X363958Y1036142D01*
G01X363957Y1036134D02*
Y1036140D01*
G01Y1036126D02*
Y1036134D01*
G01Y1031140D02*
X363958Y1031142D01*
G01X363957Y1031134D02*
Y1031140D01*
G01Y1031126D02*
Y1031134D01*
G01Y1026140D02*
X363958Y1026142D01*
G01X363957Y1026134D02*
Y1026140D01*
G01Y1026126D02*
Y1026134D01*
G01Y1021140D02*
X363958Y1021142D01*
G01X363957Y1021134D02*
Y1021140D01*
G01Y1021126D02*
Y1021134D01*
G01Y1016140D02*
X363958Y1016142D01*
G01X363957Y1016134D02*
Y1016140D01*
G01Y1016126D02*
Y1016134D01*
G01Y1011140D02*
X363958Y1011142D01*
G01X363957Y1011134D02*
Y1011140D01*
G01Y1011126D02*
Y1011134D01*
G01Y986140D02*
X363958Y986142D01*
G01X363957Y986134D02*
Y986140D01*
G01Y986126D02*
Y986134D01*
G01Y981140D02*
X363958Y981142D01*
G01X363957Y981134D02*
Y981140D01*
G01Y981126D02*
Y981134D01*
G01Y976140D02*
X363958Y976142D01*
G01X363957Y976134D02*
Y976140D01*
G01Y976126D02*
Y976134D01*
G01Y971140D02*
X363958Y971142D01*
G01X363957Y971134D02*
Y971140D01*
G01Y971126D02*
Y971134D01*
G01Y966140D02*
X363958Y966142D01*
G01X363957Y966134D02*
Y966140D01*
G01Y966126D02*
Y966134D01*
G01Y961140D02*
X363958Y961142D01*
G01X363957Y961134D02*
Y961140D01*
G01Y961126D02*
Y961134D01*
G01Y956140D02*
X363958Y956142D01*
G01X363957Y956134D02*
Y956140D01*
G01Y956126D02*
Y956134D01*
G01X350531Y1008222D02*
Y1008215D01*
G01X350530Y1008227D02*
X350531Y1008222D01*
G01X350530Y1008219D02*
Y1008227D01*
G01X350569Y1008017D02*
X350567Y1008031D01*
G01X350572Y1008005D02*
X350569Y1008017D01*
G01X350571Y1007992D02*
X350572Y1008005D01*
G01X350569Y1004868D02*
X350567Y1004881D01*
G01X350572Y1004855D02*
X350569Y1004868D01*
G01X350571Y1004843D02*
X350572Y1004855D01*
G01X350569Y1001718D02*
X350567Y1001732D01*
G01X350572Y1001706D02*
X350569Y1001718D01*
G01X350571Y1001693D02*
X350572Y1001706D01*
G01X350569Y998569D02*
X350567Y998582D01*
G01X350572Y998556D02*
X350569Y998569D01*
G01X350571Y998543D02*
X350572Y998556D01*
G01X350569Y995419D02*
X350567Y995433D01*
G01X350572Y995406D02*
X350569Y995419D01*
G01X350571Y995394D02*
X350572Y995406D01*
G01X350569Y992269D02*
X350567Y992283D01*
G01X350572Y992257D02*
X350569Y992269D01*
G01X350571Y992244D02*
X350572Y992257D01*
G01X350569Y989120D02*
X350567Y989133D01*
G01X350572Y989107D02*
X350569Y989120D01*
G01X350571Y989094D02*
X350572Y989107D01*
G01X351479Y1009541D02*
X351480Y1009528D01*
G01X351476Y1009554D02*
X351479Y1009541D01*
G01X351476Y1009567D02*
Y1009554D01*
G01X351479Y1006392D02*
X351480Y1006378D01*
G01X351476Y1006405D02*
X351479Y1006392D01*
G01X351476Y1006417D02*
Y1006405D01*
G01X351479Y1003242D02*
X351480Y1003228D01*
G01X351476Y1003255D02*
X351479Y1003242D01*
G01X351476Y1003268D02*
Y1003255D01*
G01X351479Y1000093D02*
X351480Y1000079D01*
G01X351476Y1000106D02*
X351479Y1000093D01*
G01X351476Y1000118D02*
Y1000106D01*
G01X351479Y996943D02*
X351480Y996929D01*
G01X351476Y996956D02*
X351479Y996943D01*
G01X351476Y996969D02*
Y996956D01*
G01X351479Y993793D02*
X351480Y993780D01*
G01X351476Y993806D02*
X351479Y993793D01*
G01X351476Y993819D02*
Y993806D01*
G01X351479Y990644D02*
X351480Y990630D01*
G01X351476Y990657D02*
X351479Y990644D01*
G01X351476Y990669D02*
Y990657D01*
G01X350531Y995624D02*
Y995617D01*
G01X350530Y995628D02*
X350531Y995624D01*
G01X350530Y995621D02*
Y995628D01*
G01X350531Y1005073D02*
Y1005065D01*
G01X350530Y1005077D02*
X350531Y1005073D01*
G01X350530Y1005070D02*
Y1005077D01*
G01X351476Y1008005D02*
Y1007992D01*
G01X351478Y1008017D02*
X351476Y1008005D01*
G01X351480Y1008031D02*
X351478Y1008017D01*
G01X351476Y1004855D02*
Y1004843D01*
G01X351478Y1004868D02*
X351476Y1004855D01*
G01X351480Y1004881D02*
X351478Y1004868D01*
G01X351476Y1001706D02*
Y1001693D01*
G01X351478Y1001718D02*
X351476Y1001706D01*
G01X351480Y1001732D02*
X351478Y1001718D01*
G01X351476Y998556D02*
Y998543D01*
G01X351478Y998569D02*
X351476Y998556D01*
G01X351480Y998582D02*
X351478Y998569D01*
G01X351476Y995406D02*
Y995394D01*
G01X351478Y995419D02*
X351476Y995406D01*
G01X351480Y995433D02*
X351478Y995419D01*
G01X351476Y992257D02*
Y992244D01*
G01X351478Y992269D02*
X351476Y992257D01*
G01X351480Y992283D02*
X351478Y992269D01*
G01X351476Y989107D02*
Y989094D01*
G01X351478Y989120D02*
X351476Y989107D01*
G01X351480Y989133D02*
X351478Y989120D01*
G01X350531Y989325D02*
Y989317D01*
G01X350530Y989329D02*
X350531Y989325D01*
G01X350530Y989323D02*
Y989329D01*
G01X351476Y999926D02*
Y999932D01*
G01Y999922D02*
Y999926D01*
G01X351475Y999921D02*
X351476Y999922D01*
G01Y996777D02*
Y996783D01*
G01Y996773D02*
Y996777D01*
G01X351475Y996772D02*
X351476Y996773D01*
G01Y993627D02*
Y993633D01*
G01Y993623D02*
Y993627D01*
G01X351475Y993622D02*
X351476Y993623D01*
G01Y990478D02*
Y990483D01*
G01Y990474D02*
Y990478D01*
G01X351475Y990472D02*
X351476Y990474D01*
G01X364941Y1041134D02*
Y1041125D01*
G01X364942Y1041140D02*
X364941Y1041134D01*
G01X364944Y1041142D02*
X364942Y1041140D01*
G01X364941Y1036134D02*
Y1036125D01*
G01X364942Y1036140D02*
X364941Y1036134D01*
G01X364944Y1036142D02*
X364942Y1036140D01*
G01X364941Y1031134D02*
Y1031125D01*
G01X364942Y1031140D02*
X364941Y1031134D01*
G01X364944Y1031142D02*
X364942Y1031140D01*
G01X364941Y1026134D02*
Y1026125D01*
G01X364942Y1026140D02*
X364941Y1026134D01*
G01X364944Y1026142D02*
X364942Y1026140D01*
G01X364941Y1021134D02*
Y1021125D01*
G01X364942Y1021140D02*
X364941Y1021134D01*
G01X364944Y1021142D02*
X364942Y1021140D01*
G01X364941Y1016134D02*
Y1016125D01*
G01X364942Y1016140D02*
X364941Y1016134D01*
G01X364944Y1016142D02*
X364942Y1016140D01*
G01X364941Y1011134D02*
Y1011125D01*
G01X364942Y1011140D02*
X364941Y1011134D01*
G01X364944Y1011142D02*
X364942Y1011140D01*
G01X364941Y986134D02*
Y986125D01*
G01X364942Y986140D02*
X364941Y986134D01*
G01X364944Y986142D02*
X364942Y986140D01*
G01X364941Y981134D02*
Y981125D01*
G01X364942Y981140D02*
X364941Y981134D01*
G01X364944Y981142D02*
X364942Y981140D01*
G01X364941Y976134D02*
Y976125D01*
G01X364942Y976140D02*
X364941Y976134D01*
G01X364944Y976142D02*
X364942Y976140D01*
G01X364941Y971134D02*
Y971125D01*
G01X364942Y971140D02*
X364941Y971134D01*
G01X364944Y971142D02*
X364942Y971140D01*
G01X364941Y966134D02*
Y966125D01*
G01X364942Y966140D02*
X364941Y966134D01*
G01X364944Y966142D02*
X364942Y966140D01*
G01X364941Y961134D02*
Y961125D01*
G01X364942Y961140D02*
X364941Y961134D01*
G01X364944Y961142D02*
X364942Y961140D01*
G01X364941Y956134D02*
Y956125D01*
G01X364942Y956140D02*
X364941Y956134D01*
G01X364944Y956142D02*
X364942Y956140D01*
G01X350531Y1009337D02*
Y1009344D01*
G01X350530Y1009332D02*
X350531Y1009337D01*
G01X350529Y1009331D02*
X350530Y1009332D01*
G01X350531Y1006187D02*
Y1006194D01*
G01X350530Y1006183D02*
X350531Y1006187D01*
G01X350529Y1006181D02*
X350530Y1006183D01*
G01X350531Y1003037D02*
Y1003045D01*
G01X350530Y1003033D02*
X350531Y1003037D01*
G01X350529Y1003031D02*
X350530Y1003033D01*
G01X350531Y999888D02*
Y999895D01*
G01X350530Y999883D02*
X350531Y999888D01*
G01X350529Y999882D02*
X350530Y999883D01*
G01X350531Y996738D02*
Y996746D01*
G01X350530Y996734D02*
X350531Y996738D01*
G01X350529Y996732D02*
X350530Y996734D01*
G01X350531Y993589D02*
Y993596D01*
G01X350530Y993584D02*
X350531Y993589D01*
G01X350529Y993583D02*
X350530Y993584D01*
G01X350531Y990439D02*
Y990446D01*
G01X350530Y990435D02*
X350531Y990439D01*
G01X350529Y990433D02*
X350530Y990435D01*
G01X351513Y1008202D02*
X351516Y1008215D01*
G01X351507Y1008191D02*
X351513Y1008202D01*
G01X351496Y1008183D02*
X351507Y1008191D01*
G01X351513Y1001903D02*
X351516Y1001915D01*
G01X351507Y1001892D02*
X351513Y1001903D01*
G01X351496Y1001884D02*
X351507Y1001892D01*
G01X351513Y998754D02*
X351516Y998766D01*
G01X351507Y998742D02*
X351513Y998754D01*
G01X351496Y998734D02*
X351507Y998742D01*
G01X351513Y995604D02*
X351516Y995616D01*
G01X351507Y995593D02*
X351513Y995604D01*
G01X351496Y995585D02*
X351507Y995593D01*
G01X351513Y992454D02*
X351516Y992467D01*
G01X351507Y992443D02*
X351513Y992454D01*
G01X351496Y992435D02*
X351507Y992443D01*
G01X351508Y996754D02*
X351501Y996762D01*
G01X351513Y996743D02*
X351508Y996754D01*
G01X351515Y996732D02*
X351513Y996743D01*
G01X351508Y990454D02*
X351501Y990463D01*
G01X351513Y990444D02*
X351508Y990454D01*
G01X351515Y990433D02*
X351513Y990444D01*
G01X351508Y993604D02*
X351501Y993612D01*
G01X351513Y993594D02*
X351508Y993604D01*
G01X351515Y993583D02*
X351513Y993594D01*
G01X351508Y999903D02*
X351501Y999911D01*
G01X351513Y999893D02*
X351508Y999903D01*
G01X351515Y999882D02*
X351513Y999893D01*
G01X351508Y1003053D02*
X351501Y1003061D01*
G01X351513Y1003043D02*
X351508Y1003053D01*
G01X351515Y1003031D02*
X351513Y1003043D01*
G01X351508Y1006202D02*
X351501Y1006211D01*
G01X351513Y1006192D02*
X351508Y1006202D01*
G01X351515Y1006181D02*
X351513Y1006192D01*
G01X351508Y1009352D02*
X351501Y1009360D01*
G01X351513Y1009342D02*
X351508Y1009352D01*
G01X351515Y1009331D02*
X351513Y1009342D01*
G01Y989305D02*
X351516Y989317D01*
G01X351507Y989293D02*
X351513Y989305D01*
G01X351496Y989285D02*
X351507Y989293D01*
G01X350570Y1009375D02*
Y1009381D01*
G01Y1009371D02*
Y1009375D01*
G01X350569Y1009370D02*
X350570Y1009371D01*
G01Y1006225D02*
Y1006231D01*
G01Y1006222D02*
Y1006225D01*
G01X350569Y1006220D02*
X350570Y1006222D01*
G01Y1003076D02*
Y1003082D01*
G01Y1003072D02*
Y1003076D01*
G01X350569Y1003071D02*
X350570Y1003072D01*
G01Y999926D02*
Y999932D01*
G01Y999922D02*
Y999926D01*
G01X350569Y999921D02*
X350570Y999922D01*
G01Y996776D02*
Y996783D01*
G01Y996773D02*
Y996776D01*
G01X350569Y996772D02*
X350570Y996773D01*
G01Y993627D02*
Y993633D01*
G01Y993623D02*
Y993627D01*
G01X350569Y993622D02*
X350570Y993623D01*
G01Y990477D02*
Y990483D01*
G01Y990474D02*
Y990477D01*
G01X350569Y990472D02*
X350570Y990474D01*
G01X350532Y1009350D02*
X350531Y1009344D01*
G01X350534Y1009357D02*
X350532Y1009350D01*
G01X350537Y1009363D02*
X350534Y1009357D01*
G01X350541Y1009368D02*
X350537Y1009363D01*
G01X350545Y1009372D02*
X350541Y1009368D01*
G01X350551Y1009376D02*
X350545Y1009372D01*
G01X350532Y1006201D02*
X350531Y1006194D01*
G01X350534Y1006207D02*
X350532Y1006201D01*
G01X350537Y1006213D02*
X350534Y1006207D01*
G01X350541Y1006218D02*
X350537Y1006213D01*
G01X350545Y1006223D02*
X350541Y1006218D01*
G01X350551Y1006226D02*
X350545Y1006223D01*
G01X350532Y1003051D02*
X350531Y1003045D01*
G01X350534Y1003057D02*
X350532Y1003051D01*
G01X350537Y1003063D02*
X350534Y1003057D01*
G01X350541Y1003069D02*
X350537Y1003063D01*
G01X350545Y1003073D02*
X350541Y1003069D01*
G01X350551Y1003077D02*
X350545Y1003073D01*
G01X350532Y999902D02*
X350531Y999895D01*
G01X350534Y999908D02*
X350532Y999902D01*
G01X350537Y999914D02*
X350534Y999908D01*
G01X350541Y999919D02*
X350537Y999914D01*
G01X350545Y999924D02*
X350541Y999919D01*
G01X350551Y999927D02*
X350545Y999924D01*
G01X350532Y996752D02*
X350531Y996746D01*
G01X350534Y996758D02*
X350532Y996752D01*
G01X350537Y996764D02*
X350534Y996758D01*
G01X350541Y996769D02*
X350537Y996764D01*
G01X350545Y996774D02*
X350541Y996769D01*
G01X350551Y996778D02*
X350545Y996774D01*
G01X350532Y993602D02*
X350531Y993596D01*
G01X350534Y993609D02*
X350532Y993602D01*
G01X350537Y993615D02*
X350534Y993609D01*
G01X350541Y993620D02*
X350537Y993615D01*
G01X350545Y993624D02*
X350541Y993620D01*
G01X350551Y993628D02*
X350545Y993624D01*
G01X350532Y990453D02*
X350531Y990446D01*
G01X350534Y990459D02*
X350532Y990453D01*
G01X350537Y990465D02*
X350534Y990459D01*
G01X350541Y990470D02*
X350537Y990465D01*
G01X350545Y990475D02*
X350541Y990470D01*
G01X350551Y990478D02*
X350545Y990475D01*
G01X351487Y1008191D02*
X351475Y1008189D01*
G01X351497Y1008196D02*
X351487Y1008191D01*
G01Y1005041D02*
X351475Y1005039D01*
G01X351497Y1005046D02*
X351487Y1005041D01*
G01Y1001892D02*
X351475Y1001890D01*
G01X351497Y1001896D02*
X351487Y1001892D01*
G01Y998742D02*
X351475Y998740D01*
G01X351497Y998747D02*
X351487Y998742D01*
G01X350549Y998745D02*
X350569Y998740D01*
G01X350536Y998757D02*
X350549Y998745D01*
G01X350529Y998775D02*
X350536Y998757D01*
G01X364924Y957515D02*
X364904Y957520D01*
G01X364938Y957500D02*
X364924Y957515D01*
G01X364943Y957480D02*
X364938Y957500D01*
G01X364924Y962515D02*
X364904Y962520D01*
G01X364938Y962500D02*
X364924Y962515D01*
G01X364943Y962480D02*
X364938Y962500D01*
G01X364924Y967515D02*
X364904Y967520D01*
G01X364938Y967500D02*
X364924Y967515D01*
G01X364943Y967480D02*
X364938Y967500D01*
G01X364924Y972515D02*
X364904Y972520D01*
G01X364938Y972500D02*
X364924Y972515D01*
G01X364943Y972480D02*
X364938Y972500D01*
G01X364924Y977515D02*
X364904Y977520D01*
G01X364938Y977500D02*
X364924Y977515D01*
G01X364943Y977480D02*
X364938Y977500D01*
G01X364924Y982515D02*
X364904Y982520D01*
G01X364938Y982500D02*
X364924Y982515D01*
G01X364943Y982480D02*
X364938Y982500D01*
G01X364924Y987515D02*
X364904Y987520D01*
G01X364938Y987500D02*
X364924Y987515D01*
G01X364943Y987480D02*
X364938Y987500D01*
G01X364924Y1012515D02*
X364904Y1012520D01*
G01X364938Y1012500D02*
X364924Y1012515D01*
G01X364943Y1012480D02*
X364938Y1012500D01*
G01X364924Y1017515D02*
X364904Y1017520D01*
G01X364938Y1017500D02*
X364924Y1017515D01*
G01X364943Y1017480D02*
X364938Y1017500D01*
G01X364924Y1022515D02*
X364904Y1022520D01*
G01X364938Y1022500D02*
X364924Y1022515D01*
G01X364943Y1022480D02*
X364938Y1022500D01*
G01X364924Y1027515D02*
X364904Y1027520D01*
G01X364938Y1027500D02*
X364924Y1027515D01*
G01X364943Y1027480D02*
X364938Y1027500D01*
G01X364924Y1032515D02*
X364904Y1032520D01*
G01X364938Y1032500D02*
X364924Y1032515D01*
G01X364943Y1032480D02*
X364938Y1032500D01*
G01X364924Y1037515D02*
X364904Y1037520D01*
G01X364938Y1037500D02*
X364924Y1037515D01*
G01X364943Y1037480D02*
X364938Y1037500D01*
G01X364924Y1042515D02*
X364904Y1042520D01*
G01X364938Y1042500D02*
X364924Y1042515D01*
G01X364943Y1042480D02*
X364938Y1042500D01*
G01X364924Y1047515D02*
X364904Y1047520D01*
G01X364938Y1047500D02*
X364924Y1047515D01*
G01X364943Y1047480D02*
X364938Y1047500D01*
G01X351487Y995593D02*
X351475Y995591D01*
G01X351497Y995597D02*
X351487Y995593D01*
G01Y992443D02*
X351475Y992441D01*
G01X351497Y992448D02*
X351487Y992443D01*
G01Y989293D02*
X351475Y989291D01*
G01X351497Y989298D02*
X351487Y989293D01*
G01X350554Y995593D02*
X350569Y995591D01*
G01X350542Y995601D02*
X350554Y995593D01*
G01X350530Y995621D02*
X350542Y995601D01*
G01X350554Y1005042D02*
X350569Y1005039D01*
G01X350542Y1005050D02*
X350554Y1005042D01*
G01X350530Y1005070D02*
X350542Y1005050D01*
G01X351516Y989325D02*
Y989317D01*
G01X351515Y989329D02*
X351516Y989325D01*
G01X351514Y989331D02*
X351515Y989329D01*
G01X351516Y992474D02*
Y992467D01*
G01X351515Y992479D02*
X351516Y992474D01*
G01X351514Y992480D02*
X351515Y992479D01*
G01X351516Y995624D02*
Y995616D01*
G01X351515Y995628D02*
X351516Y995624D01*
G01X351514Y995630D02*
X351515Y995628D01*
G01X351516Y998774D02*
Y998766D01*
G01X351515Y998778D02*
X351516Y998774D01*
G01X351514Y998780D02*
X351515Y998778D01*
G01X351516Y1001923D02*
Y1001915D01*
G01X351515Y1001928D02*
X351516Y1001923D01*
G01X351514Y1001929D02*
X351515Y1001928D01*
G01X351516Y1005073D02*
Y1005065D01*
G01X351515Y1005077D02*
X351516Y1005073D01*
G01X351514Y1005079D02*
X351515Y1005077D01*
G01X351516Y1008222D02*
Y1008215D01*
G01X351515Y1008227D02*
X351516Y1008222D01*
G01X351514Y1008228D02*
X351515Y1008227D01*
G01X350554Y1008192D02*
X350569Y1008189D01*
G01X350541Y1008200D02*
X350554Y1008192D01*
G01X350530Y1008220D02*
X350541Y1008200D01*
G01X350554Y989294D02*
X350569Y989291D01*
G01X350541Y989303D02*
X350554Y989294D01*
G01X350530Y989323D02*
X350541Y989303D01*
G01X351515Y990453D02*
X351516Y990446D01*
G01X351513Y990459D02*
X351515Y990453D01*
G01X351510Y990465D02*
X351513Y990459D01*
G01X351515Y993603D02*
X351516Y993596D01*
G01X351513Y993609D02*
X351515Y993603D01*
G01X351510Y993615D02*
X351513Y993609D01*
G01X351515Y996752D02*
X351516Y996746D01*
G01X351513Y996759D02*
X351515Y996752D01*
G01X351510Y996765D02*
X351513Y996759D01*
G01X351515Y999902D02*
X351516Y999895D01*
G01X351513Y999908D02*
X351515Y999902D01*
G01X351510Y999914D02*
X351513Y999908D01*
G01X351515Y1003052D02*
X351516Y1003045D01*
G01X351513Y1003058D02*
X351515Y1003052D01*
G01X351510Y1003064D02*
X351513Y1003058D01*
G01X351515Y1006201D02*
X351516Y1006194D01*
G01X351513Y1006207D02*
X351515Y1006201D01*
G01X351510Y1006213D02*
X351513Y1006207D01*
G01X351515Y1009351D02*
X351516Y1009344D01*
G01X351513Y1009357D02*
X351515Y1009351D01*
G01X351510Y1009363D02*
X351513Y1009357D01*
G01X351477Y989286D02*
Y989280D01*
G01X351476Y989290D02*
X351477Y989286D01*
G01X351475Y989291D02*
X351476Y989290D01*
G01X351477Y992436D02*
Y992430D01*
G01X351476Y992439D02*
X351477Y992436D01*
G01X351475Y992441D02*
X351476Y992439D01*
G01X351477Y995585D02*
Y995579D01*
G01X351476Y995589D02*
X351477Y995585D01*
G01X351475Y995591D02*
X351476Y995589D01*
G01X351477Y998735D02*
Y998729D01*
G01X351476Y998739D02*
X351477Y998735D01*
G01X351475Y998740D02*
X351476Y998739D01*
G01X351477Y1001885D02*
Y1001878D01*
G01X351476Y1001888D02*
X351477Y1001885D01*
G01X351475Y1001890D02*
X351476Y1001888D01*
G01X351477Y1008184D02*
Y1008178D01*
G01X351476Y1008187D02*
X351477Y1008184D01*
G01X351475Y1008189D02*
X351476Y1008187D01*
G01X363957Y957527D02*
Y957536D01*
G01Y957521D02*
Y957527D01*
G01X363958Y957520D02*
X363957Y957521D01*
G01Y962527D02*
Y962536D01*
G01Y962521D02*
Y962527D01*
G01X363958Y962520D02*
X363957Y962521D01*
G01Y967527D02*
Y967536D01*
G01Y967521D02*
Y967527D01*
G01X363958Y967520D02*
X363957Y967521D01*
G01Y972527D02*
Y972536D01*
G01Y972521D02*
Y972527D01*
G01X363958Y972520D02*
X363957Y972521D01*
G01Y977527D02*
Y977536D01*
G01Y977521D02*
Y977527D01*
G01X363958Y977520D02*
X363957Y977521D01*
G01Y982527D02*
Y982536D01*
G01Y982521D02*
Y982527D01*
G01X363958Y982520D02*
X363957Y982521D01*
G01Y987527D02*
Y987536D01*
G01Y987521D02*
Y987527D01*
G01X363958Y987520D02*
X363957Y987521D01*
G01Y1012527D02*
Y1012536D01*
G01Y1012521D02*
Y1012527D01*
G01X363958Y1012520D02*
X363957Y1012521D01*
G01Y1017527D02*
Y1017536D01*
G01Y1017521D02*
Y1017527D01*
G01X363958Y1017520D02*
X363957Y1017521D01*
G01Y1022527D02*
Y1022536D01*
G01Y1022521D02*
Y1022527D01*
G01X363958Y1022520D02*
X363957Y1022521D01*
G01Y1027527D02*
Y1027536D01*
G01Y1027521D02*
Y1027527D01*
G01X363958Y1027520D02*
X363957Y1027521D01*
G01Y1032527D02*
Y1032536D01*
G01Y1032521D02*
Y1032527D01*
G01X363958Y1032520D02*
X363957Y1032521D01*
G01Y1037527D02*
Y1037536D01*
G01Y1037521D02*
Y1037527D01*
G01X363958Y1037520D02*
X363957Y1037521D01*
G01Y1042527D02*
Y1042536D01*
G01Y1042521D02*
Y1042527D01*
G01X363958Y1042520D02*
X363957Y1042521D01*
G01X363958Y1047520D02*
X363957Y1047521D01*
G01X364933Y957663D02*
X364941Y957637D01*
G01X364923Y957690D02*
X364933Y957663D01*
G01X364912Y957717D02*
X364923Y957690D01*
G01X364933Y962663D02*
X364941Y962637D01*
G01X364923Y962690D02*
X364933Y962663D01*
G01X364912Y962717D02*
X364923Y962690D01*
G01X364933Y967663D02*
X364941Y967637D01*
G01X364923Y967690D02*
X364933Y967663D01*
G01X364912Y967717D02*
X364923Y967690D01*
G01X364933Y972663D02*
X364941Y972637D01*
G01X364923Y972690D02*
X364933Y972663D01*
G01X364912Y972717D02*
X364923Y972690D01*
G01X364933Y977663D02*
X364941Y977637D01*
G01X364923Y977690D02*
X364933Y977663D01*
G01X364912Y977717D02*
X364923Y977690D01*
G01X364933Y982663D02*
X364941Y982637D01*
G01X364923Y982690D02*
X364933Y982663D01*
G01X364912Y982717D02*
X364923Y982690D01*
G01X364933Y987663D02*
X364941Y987637D01*
G01X364923Y987690D02*
X364933Y987663D01*
G01X364912Y987717D02*
X364923Y987690D01*
G01X364933Y1012663D02*
X364941Y1012637D01*
G01X364923Y1012690D02*
X364933Y1012663D01*
G01X364912Y1012717D02*
X364923Y1012690D01*
G01X364933Y1017663D02*
X364941Y1017637D01*
G01X364923Y1017690D02*
X364933Y1017663D01*
G01X364912Y1017717D02*
X364923Y1017690D01*
G01X364933Y1022663D02*
X364941Y1022637D01*
G01X364923Y1022690D02*
X364933Y1022663D01*
G01X364912Y1022717D02*
X364923Y1022690D01*
G01X364933Y1027663D02*
X364941Y1027637D01*
G01X364923Y1027690D02*
X364933Y1027663D01*
G01X364912Y1027717D02*
X364923Y1027690D01*
G01X364933Y1032663D02*
X364941Y1032637D01*
G01X364923Y1032690D02*
X364933Y1032663D01*
G01X364912Y1032717D02*
X364923Y1032690D01*
G01X364933Y1037663D02*
X364941Y1037637D01*
G01X364923Y1037690D02*
X364933Y1037663D01*
G01X364912Y1037717D02*
X364923Y1037690D01*
G01X364933Y1042663D02*
X364941Y1042637D01*
G01X364923Y1042690D02*
X364933Y1042663D01*
G01X364912Y1042717D02*
X364923Y1042690D01*
G01X364941Y957487D02*
Y957494D01*
G01X364942Y957482D02*
X364941Y957487D01*
G01X364943Y957480D02*
X364942Y957482D01*
G01X364941Y962487D02*
Y962494D01*
G01X364942Y962482D02*
X364941Y962487D01*
G01X364943Y962480D02*
X364942Y962482D01*
G01X364941Y967487D02*
Y967494D01*
G01X364942Y967482D02*
X364941Y967487D01*
G01X364943Y967480D02*
X364942Y967482D01*
G01X364941Y972487D02*
Y972494D01*
G01X364942Y972482D02*
X364941Y972487D01*
G01X364943Y972480D02*
X364942Y972482D01*
G01X364941Y977487D02*
Y977494D01*
G01X364942Y977482D02*
X364941Y977487D01*
G01X364943Y977480D02*
X364942Y977482D01*
G01X364941Y982487D02*
Y982494D01*
G01X364942Y982482D02*
X364941Y982487D01*
G01X364943Y982480D02*
X364942Y982482D01*
G01X364941Y987487D02*
Y987494D01*
G01X364942Y987482D02*
X364941Y987487D01*
G01X364943Y987480D02*
X364942Y987482D01*
G01X364941Y1012487D02*
Y1012494D01*
G01X364942Y1012482D02*
X364941Y1012487D01*
G01X364943Y1012480D02*
X364942Y1012482D01*
G01X364941Y1017487D02*
Y1017494D01*
G01X364942Y1017482D02*
X364941Y1017487D01*
G01X364943Y1017480D02*
X364942Y1017482D01*
G01X364941Y1022487D02*
Y1022494D01*
G01X364942Y1022482D02*
X364941Y1022487D01*
G01X364943Y1022480D02*
X364942Y1022482D01*
G01X350554Y992443D02*
X350569Y992441D01*
G01X350543Y992450D02*
X350554Y992443D01*
G01X350531Y992469D02*
X350543Y992450D01*
G01X350554Y1001892D02*
X350569Y1001890D01*
G01X350543Y1001900D02*
X350554Y1001892D01*
G01X350531Y1001918D02*
X350543Y1001900D01*
G01X350570Y989286D02*
X350571Y989280D01*
G01X350570Y989290D02*
Y989286D01*
G01X350569Y989291D02*
X350570Y989290D01*
G01X364941Y1027487D02*
Y1027494D01*
G01X364942Y1027482D02*
X364941Y1027487D01*
G01X364943Y1027480D02*
X364942Y1027482D01*
G01X364941Y1032487D02*
Y1032494D01*
G01X364942Y1032482D02*
X364941Y1032487D01*
G01X364943Y1032480D02*
X364942Y1032482D01*
G01X364941Y1037487D02*
Y1037494D01*
G01X364942Y1037482D02*
X364941Y1037487D01*
G01X364943Y1037480D02*
X364942Y1037482D01*
G01X364941Y1042487D02*
Y1042494D01*
G01X364942Y1042482D02*
X364941Y1042487D01*
G01X364943Y1042480D02*
X364942Y1042482D01*
G01Y1047482D02*
X364941Y1047487D01*
G01X364943Y1047480D02*
X364942Y1047482D01*
G01X351484Y990471D02*
X351475Y990472D01*
G01X351493Y990468D02*
X351484Y990471D01*
G01X351501Y990463D02*
X351493Y990468D01*
G01X351484Y993621D02*
X351475Y993622D01*
G01X351493Y993618D02*
X351484Y993621D01*
G01X351501Y993612D02*
X351493Y993618D01*
G01X350570Y992436D02*
X350571Y992430D01*
G01X350570Y992440D02*
Y992436D01*
G01X350569Y992441D02*
X350570Y992440D01*
G01Y995585D02*
X350571Y995579D01*
G01X350570Y995589D02*
Y995585D01*
G01X350569Y995591D02*
X350570Y995589D01*
G01Y998735D02*
X350571Y998729D01*
G01X350570Y998739D02*
Y998735D01*
G01X350569Y998740D02*
X350570Y998739D01*
G01Y1001885D02*
X350571Y1001878D01*
G01X350570Y1001889D02*
Y1001885D01*
G01X350569Y1001890D02*
X350570Y1001889D01*
G01Y1005034D02*
X350571Y1005028D01*
G01X350570Y1005038D02*
Y1005034D01*
G01X350569Y1005039D02*
X350570Y1005038D01*
G01Y1008184D02*
X350571Y1008178D01*
G01X350570Y1008188D02*
Y1008184D01*
G01X350569Y1008189D02*
X350570Y1008188D01*
G01X351484Y996770D02*
X351475Y996772D01*
G01X351493Y996767D02*
X351484Y996770D01*
G01X351501Y996762D02*
X351493Y996767D01*
G01X351484Y999920D02*
X351475Y999921D01*
G01X351493Y999917D02*
X351484Y999920D01*
G01X351501Y999911D02*
X351493Y999917D01*
G01X351484Y1003070D02*
X351475Y1003071D01*
G01X351493Y1003067D02*
X351484Y1003070D01*
G01X351501Y1003061D02*
X351493Y1003067D01*
G01X351484Y1006219D02*
X351475Y1006220D01*
G01X351493Y1006216D02*
X351484Y1006219D01*
G01X351501Y1006211D02*
X351493Y1006216D01*
G01X351484Y1009369D02*
X351475Y1009370D01*
G01X351493Y1009366D02*
X351484Y1009369D01*
G01X351501Y1009360D02*
X351493Y1009366D01*
G01X364928Y957511D02*
X364939Y957496D01*
G01X364904Y957520D02*
X364928Y957511D01*
G01Y962511D02*
X364939Y962496D01*
G01X364904Y962520D02*
X364928Y962511D01*
G01Y967511D02*
X364939Y967496D01*
G01X364904Y967520D02*
X364928Y967511D01*
G01Y972511D02*
X364939Y972496D01*
G01X364904Y972520D02*
X364928Y972511D01*
G01Y977511D02*
X364939Y977496D01*
G01X364904Y977520D02*
X364928Y977511D01*
G01Y982511D02*
X364939Y982496D01*
G01X364904Y982520D02*
X364928Y982511D01*
G01X350531Y998770D02*
Y998766D01*
G01X350533Y998764D02*
X350531Y998770D01*
G01X350543Y998750D02*
X350533Y998764D01*
G01X350566Y998740D02*
X350543Y998750D01*
G01X350531Y992470D02*
Y992467D01*
G01X350533Y992464D02*
X350531Y992470D01*
G01X350545Y992449D02*
X350533Y992464D01*
G01X350570Y992441D02*
X350545Y992449D01*
G01X350531Y995620D02*
Y995616D01*
G01X350533Y995614D02*
X350531Y995620D01*
G01X350544Y995599D02*
X350533Y995614D01*
G01X350569Y995591D02*
X350544Y995599D01*
G01X350531Y1001919D02*
Y1001915D01*
G01X350533Y1001913D02*
X350531Y1001919D01*
G01X350544Y1001898D02*
X350533Y1001913D01*
G01X350569Y1001890D02*
X350544Y1001898D01*
G01X350531Y1005069D02*
Y1005065D01*
G01X350533Y1005063D02*
X350531Y1005069D01*
G01X350544Y1005048D02*
X350533Y1005063D01*
G01X350569Y1005039D02*
X350544Y1005048D01*
G01X350531Y989321D02*
Y989317D01*
G01X350533Y989315D02*
X350531Y989321D01*
G01X350544Y989300D02*
X350533Y989315D01*
G01X350569Y989291D02*
X350544Y989300D01*
G01X350531Y1008219D02*
Y1008215D01*
G01X350533Y1008213D02*
X350531Y1008219D01*
G01X350544Y1008197D02*
X350533Y1008213D01*
G01X350569Y1008189D02*
X350544Y1008197D01*
G01X364928Y987511D02*
X364939Y987496D01*
G01X364904Y987520D02*
X364928Y987511D01*
G01Y1012511D02*
X364939Y1012496D01*
G01X364904Y1012520D02*
X364928Y1012511D01*
G01Y1017511D02*
X364939Y1017496D01*
G01X364904Y1017520D02*
X364928Y1017511D01*
G01Y1022511D02*
X364939Y1022496D01*
G01X364904Y1022520D02*
X364928Y1022511D01*
G01Y1027511D02*
X364939Y1027496D01*
G01X364904Y1027520D02*
X364928Y1027511D01*
G01Y1032511D02*
X364939Y1032496D01*
G01X364904Y1032520D02*
X364928Y1032511D01*
G01Y1037511D02*
X364939Y1037496D01*
G01X364904Y1037520D02*
X364928Y1037511D01*
G01Y1042511D02*
X364939Y1042496D01*
G01X364904Y1042520D02*
X364928Y1042511D01*
G01Y1047511D02*
X364939Y1047496D01*
G01X364904Y1047520D02*
X364928Y1047511D01*
G01X350532Y989310D02*
X350531Y989317D01*
G01X350535Y989303D02*
X350532Y989310D01*
G01X350538Y989296D02*
X350535Y989303D01*
G01X350543Y989291D02*
X350538Y989296D01*
G01X350549Y989286D02*
X350543Y989291D01*
G01X350556Y989283D02*
X350549Y989286D01*
G01X350563Y989281D02*
X350556Y989283D01*
G01X350571Y989280D02*
X350563Y989281D01*
G01X350532Y992459D02*
X350531Y992467D01*
G01X350535Y992452D02*
X350532Y992459D01*
G01X350538Y992446D02*
X350535Y992452D01*
G01X350543Y992441D02*
X350538Y992446D01*
G01X350549Y992436D02*
X350543Y992441D01*
G01X350556Y992432D02*
X350549Y992436D01*
G01X350563Y992430D02*
X350556Y992432D01*
G01X350571Y992430D02*
X350563D01*
G01X350532Y995609D02*
X350531Y995616D01*
G01X350535Y995602D02*
X350532Y995609D01*
G01X350538Y995596D02*
X350535Y995602D01*
G01X350543Y995590D02*
X350538Y995596D01*
G01X350549Y995585D02*
X350543Y995590D01*
G01X350556Y995582D02*
X350549Y995585D01*
G01X350563Y995580D02*
X350556Y995582D01*
G01X350571Y995579D02*
X350563Y995580D01*
G01X351485Y990471D02*
X351495Y990467D01*
G01X351475Y990472D02*
X351485Y990471D01*
G01Y993620D02*
X351495Y993617D01*
G01X351475Y993622D02*
X351485Y993620D01*
G01Y996770D02*
X351495Y996766D01*
G01X351475Y996772D02*
X351485Y996770D01*
G01Y999920D02*
X351495Y999916D01*
G01X351475Y999921D02*
X351485Y999920D01*
G01Y1003069D02*
X351495Y1003065D01*
G01X351475Y1003071D02*
X351485Y1003069D01*
G01Y1006219D02*
X351495Y1006215D01*
G01X351475Y1006220D02*
X351485Y1006219D01*
G01Y1009369D02*
X351495Y1009365D01*
G01X351475Y1009370D02*
X351485Y1009369D01*
G01X351493Y989283D02*
X351496Y989285D01*
G01X351490Y989282D02*
X351493Y989283D01*
G01X351487Y989281D02*
X351490Y989282D01*
G01X351483Y989281D02*
X351487D01*
G01X351480Y989280D02*
X351483Y989281D01*
G01X351476Y989280D02*
X351480D01*
G01X350554Y990480D02*
X350551Y990478D01*
G01X350557Y990481D02*
X350554Y990480D01*
G01X350561Y990482D02*
X350557Y990481D01*
G01X350564Y990483D02*
X350561Y990482D01*
G01X350567Y990483D02*
X350564D01*
G01X350571D02*
X350567D01*
G01X351493Y992433D02*
X351496Y992435D01*
G01X351490Y992432D02*
X351493Y992433D01*
G01X351487Y992431D02*
X351490Y992432D01*
G01X351483Y992430D02*
X351487Y992431D01*
G01X351480Y992430D02*
X351483D01*
G01X351476D02*
X351480D01*
G01X350554Y993630D02*
X350551Y993628D01*
G01X350557Y993631D02*
X350554Y993630D01*
G01X350561Y993632D02*
X350557Y993631D01*
G01X350564Y993633D02*
X350561Y993632D01*
G01X350567Y993633D02*
X350564D01*
G01X350571D02*
X350567D01*
G01X351493Y995583D02*
X351496Y995585D01*
G01X351490Y995581D02*
X351493Y995583D01*
G01X351487Y995581D02*
X351490D01*
G01X351483Y995580D02*
X351487Y995581D01*
G01X351480Y995580D02*
X351483D01*
G01X351476Y995579D02*
X351480Y995580D01*
G01X349784Y992480D02*
X349350D01*
G01X350158D02*
X349784D01*
G01Y998780D02*
X349350D01*
G01X350158D02*
X349784D01*
G01Y1001929D02*
X349350D01*
G01X350158D02*
X349784D01*
G01X351506Y990471D02*
X351510Y990465D01*
G01X351502Y990475D02*
X351506Y990471D01*
G01X351496Y990479D02*
X351502Y990475D01*
G01X351490Y990481D02*
X351496Y990479D01*
G01X351483Y990483D02*
X351490Y990481D01*
G01X351476Y990483D02*
X351483D01*
G01X351506Y993620D02*
X351510Y993615D01*
G01X351502Y993625D02*
X351506Y993620D01*
G01X351496Y993628D02*
X351502Y993625D01*
G01X351490Y993631D02*
X351496Y993628D01*
G01X351483Y993633D02*
X351490Y993631D01*
G01X351476Y993633D02*
X351483D01*
G01X351506Y996770D02*
X351510Y996765D01*
G01X351502Y996774D02*
X351506Y996770D01*
G01X351496Y996778D02*
X351502Y996774D01*
G01X351490Y996781D02*
X351496Y996778D01*
G01X351483Y996782D02*
X351490Y996781D01*
G01X351476Y996783D02*
X351483Y996782D01*
G01X351506Y999920D02*
X351510Y999914D01*
G01X351502Y999924D02*
X351506Y999920D01*
G01X351496Y999928D02*
X351502Y999924D01*
G01X351490Y999930D02*
X351496Y999928D01*
G01X351483Y999932D02*
X351490Y999930D01*
G01X351476Y999932D02*
X351483D01*
G01X351506Y1003069D02*
X351510Y1003064D01*
G01X351502Y1003074D02*
X351506Y1003069D01*
G01X351496Y1003077D02*
X351502Y1003074D01*
G01X351490Y1003080D02*
X351496Y1003077D01*
G01X351483Y1003081D02*
X351490Y1003080D01*
G01X351476Y1003082D02*
X351483Y1003081D01*
G01X351506Y1006219D02*
X351510Y1006213D01*
G01X351502Y1006223D02*
X351506Y1006219D01*
G01X351496Y1006227D02*
X351502Y1006223D01*
G01X351490Y1006230D02*
X351496Y1006227D01*
G01X351483Y1006231D02*
X351490Y1006230D01*
G01X351476Y1006231D02*
X351483D01*
G01X351506Y1009369D02*
X351510Y1009363D01*
G01X351502Y1009373D02*
X351506Y1009369D01*
G01X351496Y1009376D02*
X351502Y1009373D01*
G01X351490Y1009379D02*
X351496Y1009376D01*
G01X351483Y1009381D02*
X351490Y1009379D01*
G01X351476Y1009381D02*
X351483D01*
G01X350532Y998759D02*
X350531Y998766D01*
G01X350535Y998752D02*
X350532Y998759D01*
G01X350538Y998745D02*
X350535Y998752D01*
G01X350543Y998740D02*
X350538Y998745D01*
G01X350549Y998735D02*
X350543Y998740D01*
G01X350556Y998731D02*
X350549Y998735D01*
G01X350563Y998730D02*
X350556Y998731D01*
G01X350571Y998729D02*
X350563Y998730D01*
G01X350532Y1001908D02*
X350531Y1001915D01*
G01X350535Y1001901D02*
X350532Y1001908D01*
G01X350538Y1001895D02*
X350535Y1001901D01*
G01X350543Y1001889D02*
X350538Y1001895D01*
G01X350549Y1001885D02*
X350543Y1001889D01*
G01X350556Y1001881D02*
X350549Y1001885D01*
G01X350563Y1001879D02*
X350556Y1001881D01*
G01X350571Y1001878D02*
X350563Y1001879D01*
G01X350532Y1005058D02*
X350531Y1005065D01*
G01X350535Y1005051D02*
X350532Y1005058D01*
G01X350538Y1005044D02*
X350535Y1005051D01*
G01X350543Y1005039D02*
X350538Y1005044D01*
G01X350549Y1005034D02*
X350543Y1005039D01*
G01X350556Y1005031D02*
X350549Y1005034D01*
G01X350563Y1005029D02*
X350556Y1005031D01*
G01X350571Y1005028D02*
X350563Y1005029D01*
G01X350532Y1008207D02*
X350531Y1008215D01*
G01X350535Y1008200D02*
X350532Y1008207D01*
G01X350538Y1008194D02*
X350535Y1008200D01*
G01X350543Y1008189D02*
X350538Y1008194D01*
G01X350549Y1008184D02*
X350543Y1008189D01*
G01X350556Y1008180D02*
X350549Y1008184D01*
G01X350563Y1008178D02*
X350556Y1008180D01*
G01X350571Y1008178D02*
X350563D01*
G01X351515Y1005058D02*
X351516Y1005065D01*
G01X351513Y1005051D02*
X351515Y1005058D01*
G01X351509Y1005044D02*
X351513Y1005051D01*
G01X351504Y1005039D02*
X351509Y1005044D01*
G01X351498Y1005034D02*
X351504Y1005039D01*
G01X351491Y1005031D02*
X351498Y1005034D01*
G01X351484Y1005029D02*
X351491Y1005031D01*
G01X351476Y1005028D02*
X351484Y1005029D01*
G01X350554Y996779D02*
X350551Y996778D01*
G01X350557Y996780D02*
X350554Y996779D01*
G01X350561Y996781D02*
X350557Y996780D01*
G01X350564Y996782D02*
X350561Y996781D01*
G01X350567Y996783D02*
X350564Y996782D01*
G01X350571Y996783D02*
X350567D01*
G01X351493Y998732D02*
X351496Y998734D01*
G01X351490Y998731D02*
X351493Y998732D01*
G01X351487Y998730D02*
X351490Y998731D01*
G01X351483Y998730D02*
X351487D01*
G01X351480Y998729D02*
X351483Y998730D01*
G01X351476Y998729D02*
X351480D01*
G01X350554Y999929D02*
X350551Y999927D01*
G01X350557Y999930D02*
X350554Y999929D01*
G01X350561Y999931D02*
X350557Y999930D01*
G01X350564Y999932D02*
X350561Y999931D01*
G01X350567Y999932D02*
X350564D01*
G01X350571D02*
X350567D01*
G01X351493Y1001882D02*
X351496Y1001884D01*
G01X351490Y1001881D02*
X351493Y1001882D01*
G01X351487Y1001880D02*
X351490Y1001881D01*
G01X351483Y1001879D02*
X351487Y1001880D01*
G01X351480Y1001879D02*
X351483D01*
G01X351476Y1001878D02*
X351480Y1001879D01*
G01X350554Y1003078D02*
X350551Y1003077D01*
G01X350557Y1003080D02*
X350554Y1003078D01*
G01X350561Y1003081D02*
X350557Y1003080D01*
G01X350564Y1003081D02*
X350561D01*
G01X350567Y1003082D02*
X350564Y1003081D01*
G01X350571Y1003082D02*
X350567D01*
G01X350554Y1006228D02*
X350551Y1006226D01*
G01X350557Y1006229D02*
X350554Y1006228D01*
G01X350561Y1006230D02*
X350557Y1006229D01*
G01X350564Y1006231D02*
X350561Y1006230D01*
G01X350567Y1006231D02*
X350564D01*
G01X350571D02*
X350567D01*
G01X351493Y1008181D02*
X351496Y1008183D01*
G01X351490Y1008180D02*
X351493Y1008181D01*
G01X351487Y1008179D02*
X351490Y1008180D01*
G01X351483Y1008178D02*
X351487Y1008179D01*
G01X351480Y1008178D02*
X351483D01*
G01X351476D02*
X351480D01*
G01X350554Y1009378D02*
X350551Y1009376D01*
G01X350557Y1009379D02*
X350554Y1009378D01*
G01X350561Y1009380D02*
X350557Y1009379D01*
G01X350564Y1009381D02*
X350561Y1009380D01*
G01X350567Y1009381D02*
X350564D01*
G01X350571D02*
X350567D01*
G01X350534Y990453D02*
X350529Y990433D01*
G01X350549Y990467D02*
X350534Y990453D01*
G01X350569Y990472D02*
X350549Y990467D01*
G01X350534Y993602D02*
X350529Y993583D01*
G01X350549Y993617D02*
X350534Y993602D01*
G01X350569Y993622D02*
X350549Y993617D01*
G01X350534Y996752D02*
X350529Y996732D01*
G01X350549Y996766D02*
X350534Y996752D01*
G01X350569Y996772D02*
X350549Y996766D01*
G01X350534Y999902D02*
X350529Y999882D01*
G01X350549Y999916D02*
X350534Y999902D01*
G01X350569Y999921D02*
X350549Y999916D01*
G01X350534Y1003051D02*
X350529Y1003031D01*
G01X350549Y1003065D02*
X350534Y1003051D01*
G01X350569Y1003071D02*
X350549Y1003065D01*
G01X350534Y1006201D02*
X350529Y1006181D01*
G01X350549Y1006215D02*
X350534Y1006201D01*
G01X350569Y1006220D02*
X350549Y1006215D01*
G01X350534Y1009350D02*
X350529Y1009331D01*
G01X350549Y1009365D02*
X350534Y1009350D01*
G01X350569Y1009370D02*
X350549Y1009365D01*
G01X351509Y989311D02*
X351514Y989331D01*
G01X351494Y989296D02*
X351509Y989311D01*
G01X351475Y989291D02*
X351494Y989296D01*
G01X351509Y992461D02*
X351514Y992480D01*
G01X351494Y992446D02*
X351509Y992461D01*
G01X351475Y992441D02*
X351494Y992446D01*
G01X351509Y995610D02*
X351514Y995630D01*
G01X351494Y995596D02*
X351509Y995610D01*
G01X351475Y995591D02*
X351494Y995596D01*
G01X351509Y998760D02*
X351514Y998780D01*
G01X351494Y998745D02*
X351509Y998760D01*
G01X351475Y998740D02*
X351494Y998745D01*
G01X351509Y1001909D02*
X351514Y1001929D01*
G01X351494Y1001895D02*
X351509Y1001909D01*
G01X351475Y1001890D02*
X351494Y1001895D01*
G01X351509Y1005059D02*
X351514Y1005079D01*
G01X351494Y1005044D02*
X351509Y1005059D01*
G01X351475Y1005039D02*
X351494Y1005044D01*
G01X351509Y1008209D02*
X351514Y1008228D01*
G01X351494Y1008194D02*
X351509Y1008209D01*
G01X351475Y1008189D02*
X351494Y1008194D01*
G01X369291Y1046142D02*
X363958D01*
G01X363957Y1045650D02*
X364941D01*
G01Y1043012D02*
X363957D01*
G01X363958Y1042520D02*
X369291D01*
G01Y1042480D02*
X364943D01*
G01X369291Y1041142D02*
X363958D01*
G01X363957Y1040650D02*
X364941D01*
G01Y1038012D02*
X363957D01*
G01X363958Y1037520D02*
X369291D01*
G01Y1037480D02*
X364943D01*
G01X369291Y1036142D02*
X363958D01*
G01X363957Y1035650D02*
X364941D01*
G01Y1033012D02*
X363957D01*
G01X363958Y1032520D02*
X369291D01*
G01Y1032480D02*
X364943D01*
G01X369291Y1031142D02*
X363958D01*
G01X363957Y1030650D02*
X364941D01*
G01Y1028012D02*
X363957D01*
G01X363958Y1027520D02*
X369291D01*
G01Y1027480D02*
X364943D01*
G01X369291Y1026142D02*
X363958D01*
G01X363957Y1025650D02*
X364941D01*
G01Y1023012D02*
X363957D01*
G01X363958Y1022520D02*
X369291D01*
G01Y1022480D02*
X364943D01*
G01X369291Y1021142D02*
X363958D01*
G01X364941Y1045946D02*
X363957Y1045945D01*
G01Y1042715D02*
X364912Y1042717D01*
G01X364941Y1040946D02*
X363957Y1040945D01*
G01Y1037715D02*
X364912Y1037717D01*
G01X364941Y1035946D02*
X363957Y1035945D01*
G01Y1032715D02*
X364912Y1032717D01*
G01X364941Y1030946D02*
X363957Y1030945D01*
G01Y1027715D02*
X364912Y1027717D01*
G01X364941Y1025946D02*
X363957Y1025945D01*
G01Y1022715D02*
X364912Y1022717D01*
G01X364941Y1020946D02*
X363957Y1020945D01*
G01X350418Y1008228D02*
X350530Y1008220D01*
G01X350529Y998775D02*
X350418Y998780D01*
G01X350529Y992477D02*
X350418Y992480D01*
G01X350529Y1001926D02*
X350418Y1001929D01*
G01X363957Y1020650D02*
X364941D01*
G01Y1018012D02*
X363957D01*
G01X363958Y1017520D02*
X369291D01*
G01Y1017480D02*
X364943D01*
G01X369291Y1016142D02*
X363958D01*
G01X363957Y1015650D02*
X364941D01*
G01Y1013012D02*
X363957D01*
G01X363958Y1012520D02*
X369291D01*
G01Y1012480D02*
X364943D01*
G01X351969Y1011535D02*
X348622D01*
G01X369291Y1011142D02*
X363958D01*
G01X363957Y1010650D02*
X364941D01*
G01X361614Y1010374D02*
X365551D01*
G01X351476Y1009567D02*
X350571D01*
G01X351516Y1009528D02*
X350531D01*
G01X351475Y1009370D02*
X345591D01*
G01Y1009331D02*
X351515D01*
G01X360433Y1009193D02*
X364370D01*
G01X351514Y1008228D02*
X345591D01*
G01X351475Y1008189D02*
X345591D01*
G01X350531Y1008031D02*
X351516D01*
G01X350571Y1007992D02*
X351476D01*
G01Y1006417D02*
X350571D01*
G01X351516Y1006378D02*
X350531D01*
G01X351475Y1006220D02*
X345591D01*
G01Y1006181D02*
X351515D01*
G01X351514Y1005079D02*
X345591D01*
G01X351475Y1005039D02*
X345591D01*
G01X350531Y1004882D02*
X351516D01*
G01X350571Y1004843D02*
X351476D01*
G01Y1003268D02*
X350571D01*
G01X351516Y1003228D02*
X350531D01*
G01X351475Y1003071D02*
X345591D01*
G01Y1003031D02*
X351515D01*
G01X351514Y1001929D02*
X345591D01*
G01X351475Y1001890D02*
X345591D01*
G01X350531Y1001732D02*
X351516D01*
G01X350571Y1001693D02*
X351476D01*
G01Y1000118D02*
X350571D01*
G01X351516Y1000079D02*
X350531D01*
G01X351475Y999921D02*
X345591D01*
G01Y999882D02*
X351515D01*
G01X351514Y998780D02*
X345591D01*
G01X351475Y998740D02*
X345591D01*
G01X350531Y998583D02*
X351516D01*
G01X350571Y998543D02*
X351476D01*
G01Y996969D02*
X350571D01*
G01X351516Y996929D02*
X350531D01*
G01X351475Y996772D02*
X345591D01*
G01Y996732D02*
X351515D01*
G01X351514Y995630D02*
X345591D01*
G01X351475Y995591D02*
X345591D01*
G01X350531Y995433D02*
X351516D01*
G01X350571Y995394D02*
X351476D01*
G01Y993819D02*
X350571D01*
G01X351516Y993780D02*
X350531D01*
G01X351475Y993622D02*
X345591D01*
G01Y993583D02*
X351515D01*
G01X351514Y992480D02*
X345591D01*
G01X351475Y992441D02*
X345591D01*
G01X350531Y992283D02*
X351516D01*
G01X350571Y992244D02*
X351476D01*
G01Y990669D02*
X350571D01*
G01X351516Y990630D02*
X350531D01*
G01X351475Y990472D02*
X345591D01*
G01Y990433D02*
X351515D01*
G01X364370Y989469D02*
X360433D01*
G01X351514Y989331D02*
X345591D01*
G01X351475Y989291D02*
X345591D01*
G01X350531Y989134D02*
X351516D01*
G01X350571Y989094D02*
X351476D01*
G01X365551Y988287D02*
X361614D01*
G01X364941Y988012D02*
X363957D01*
G01X363958Y987520D02*
X369291D01*
G01Y987480D02*
X364943D01*
G01X351969Y987126D02*
X348622D01*
G01X369291Y986142D02*
X363958D01*
G01X363957Y985650D02*
X364941D01*
G01Y983012D02*
X363957D01*
G01X363958Y982520D02*
X369291D01*
G01Y982480D02*
X364943D01*
G01X369291Y981142D02*
X363958D01*
G01X363957Y980650D02*
X364941D01*
G01Y978012D02*
X363957D01*
G01X363958Y977520D02*
X369291D01*
G01Y977480D02*
X364943D01*
G01X369291Y976142D02*
X363958D01*
G01X363957Y975650D02*
X364941D01*
G01Y973012D02*
X363957D01*
G01X363958Y972520D02*
X369291D01*
G01Y972480D02*
X364943D01*
G01X369291Y971142D02*
X363958D01*
G01X363957Y970650D02*
X364941D01*
G01Y968012D02*
X363957D01*
G01X363958Y967520D02*
X369291D01*
G01Y967480D02*
X364943D01*
G01X369291Y966142D02*
X363958D01*
G01X363957Y965650D02*
X364941D01*
G01Y963012D02*
X363957D01*
G01X363958Y962520D02*
X369291D01*
G01Y962480D02*
X364943D01*
G01X369291Y961142D02*
X363958D01*
G01X363957Y960650D02*
X364941D01*
G01Y958012D02*
X363957D01*
G01X363958Y957520D02*
X369291D01*
G01Y957480D02*
X364943D01*
G01X369291Y956142D02*
X363958D01*
G01X363957Y955650D02*
X364941D01*
G01X360433Y953012D02*
X354921D01*
G01X363957Y1017715D02*
X364912Y1017717D01*
G01X364941Y1015946D02*
X363957Y1015945D01*
G01Y1012715D02*
X364912Y1012717D01*
G01X364941Y1010946D02*
X363957Y1010945D01*
G01Y987715D02*
X364912Y987717D01*
G01X364941Y985946D02*
X363957Y985945D01*
G01Y982715D02*
X364912Y982717D01*
G01X364941Y980946D02*
X363957Y980945D01*
G01Y977715D02*
X364912Y977717D01*
G01X364941Y975946D02*
X363957Y975945D01*
G01Y972715D02*
X364912Y972717D01*
G01X364941Y970946D02*
X363957Y970945D01*
G01Y967715D02*
X364912Y967717D01*
G01X364941Y965946D02*
X363957Y965945D01*
G01Y962715D02*
X364912Y962717D01*
G01X364941Y960946D02*
X363957Y960945D01*
G01Y957715D02*
X364912Y957717D01*
G01X364941Y955946D02*
X363957Y955945D01*
G01X364370Y989469D02*
X365551Y988287D01*
G01X360433Y989469D02*
X361614Y988287D01*
G01X351475Y1005039D02*
X351478Y1005028D01*
G01X364370Y1009193D02*
X365551Y1010374D01*
G01X360433Y1009193D02*
X361614Y1010374D01*
G01X351515Y990435D02*
X351516Y990446D01*
G01X351515Y993585D02*
X351516Y993596D01*
G01X351515Y996734D02*
X351516Y996746D01*
G01X351515Y999884D02*
X351516Y999895D01*
G01X351515Y1003033D02*
X351516Y1003045D01*
G01X351515Y1006183D02*
X351516Y1006194D01*
G01X351515Y1009333D02*
X351516Y1009344D01*
G01X364941Y957494D02*
Y957502D01*
G01Y962494D02*
Y962502D01*
G01Y967494D02*
Y967502D01*
G01Y972494D02*
Y972502D01*
G01Y977494D02*
Y977502D01*
G01Y982494D02*
Y982502D01*
G01Y987494D02*
Y987502D01*
G01Y1012494D02*
Y1012502D01*
G01Y1017494D02*
Y1017502D01*
G01Y1022494D02*
Y1022502D01*
G01Y1027494D02*
Y1027502D01*
G01Y1032494D02*
Y1032502D01*
G01Y1037494D02*
Y1037502D01*
G01Y1042494D02*
Y1042502D01*
G01X369291Y1046142D02*
Y1047520D01*
G01Y1041142D02*
Y1042520D01*
G01Y1036142D02*
Y1037520D01*
G01Y1031142D02*
Y1032520D01*
G01Y1026142D02*
Y1027520D01*
G01Y1021142D02*
Y1022520D01*
G01Y1016142D02*
Y1017520D01*
G01Y1011142D02*
Y1012520D01*
G01Y986142D02*
Y987520D01*
G01Y981142D02*
Y982520D01*
G01Y976142D02*
Y977520D01*
G01Y971142D02*
Y972520D01*
G01Y966142D02*
Y967520D01*
G01Y961142D02*
Y962520D01*
G01Y956142D02*
Y957520D01*
G01X366122D02*
Y956142D01*
G01Y962520D02*
Y961142D01*
G01Y967520D02*
Y966142D01*
G01Y972520D02*
Y971142D01*
G01Y977520D02*
Y976142D01*
G01Y982520D02*
Y981142D01*
G01Y987520D02*
Y986142D01*
G01Y1012520D02*
Y1011142D01*
G01Y1017520D02*
Y1016142D01*
G01Y1022520D02*
Y1021142D01*
G01Y1027520D02*
Y1026142D01*
G01Y1032520D02*
Y1031142D01*
G01Y1037520D02*
Y1036142D01*
G01Y1042520D02*
Y1041142D01*
G01Y1047520D02*
Y1046142D01*
G01X365551Y1010374D02*
Y988287D01*
G01X364941Y1045650D02*
Y1048012D01*
G01Y1040650D02*
Y1043012D01*
G01Y1035650D02*
Y1038012D01*
G01Y1030650D02*
Y1033012D01*
G01Y1025650D02*
Y1028012D01*
G01Y1020650D02*
Y1023012D01*
G01Y1015650D02*
Y1018012D01*
G01Y1010650D02*
Y1013012D01*
G01Y985650D02*
Y988012D01*
G01Y980650D02*
Y983012D01*
G01Y975650D02*
Y978012D01*
G01Y970650D02*
Y973012D01*
G01Y965650D02*
Y968012D01*
G01Y960650D02*
Y963012D01*
G01Y955650D02*
Y958012D01*
G01Y962494D02*
Y962637D01*
G01Y957494D02*
Y957637D01*
G01Y972494D02*
Y972637D01*
G01Y967494D02*
Y967637D01*
G01Y982494D02*
Y982637D01*
G01Y977494D02*
Y977637D01*
G01Y987494D02*
Y987637D01*
G01Y1012494D02*
Y1012637D01*
G01Y1022494D02*
Y1022637D01*
G01Y1017494D02*
Y1017637D01*
G01Y1032494D02*
Y1032637D01*
G01Y1027494D02*
Y1027637D01*
G01Y1042494D02*
Y1042637D01*
G01Y1037494D02*
Y1037637D01*
G01X364370Y1009193D02*
Y989469D01*
G01X363957Y958012D02*
Y955650D01*
G01Y963012D02*
Y960650D01*
G01Y968012D02*
Y965650D01*
G01Y973012D02*
Y970650D01*
G01Y978012D02*
Y975650D01*
G01Y983012D02*
Y980650D01*
G01Y988012D02*
Y985650D01*
G01Y1013012D02*
Y1010650D01*
G01Y1018012D02*
Y1015650D01*
G01Y1023012D02*
Y1020650D01*
G01Y1028012D02*
Y1025650D01*
G01Y1033012D02*
Y1030650D01*
G01Y1038012D02*
Y1035650D01*
G01Y1043012D02*
Y1040650D01*
G01Y1048012D02*
Y1045650D01*
G01X361614Y1086831D02*
Y1010374D01*
G01X360433Y989469D02*
Y953012D01*
G01Y1085650D02*
Y1009193D01*
G01X354921Y953012D02*
Y1085650D01*
G01X351969Y1090571D02*
Y1011535D01*
G01X351516Y1008031D02*
Y1009528D01*
G01Y1004881D02*
Y1006378D01*
G01Y1001732D02*
Y1003228D01*
G01Y998582D02*
Y1000079D01*
G01Y995433D02*
Y996929D01*
G01Y992283D02*
Y993780D01*
G01Y989133D02*
Y990630D01*
G01X351476Y989280D02*
Y989133D01*
G01Y990630D02*
Y990483D01*
G01Y995579D02*
Y995432D01*
G01Y992430D02*
Y992283D01*
G01Y993780D02*
Y993633D01*
G01Y998729D02*
Y998582D01*
G01Y1000079D02*
Y999932D01*
G01Y996930D02*
Y996783D01*
G01Y1001878D02*
Y1001731D01*
G01Y1003229D02*
Y1003082D01*
G01Y1008178D02*
Y1008031D01*
G01Y1009528D02*
Y1009381D01*
G01Y1005028D02*
Y1004881D01*
G01Y1006378D02*
Y1006231D01*
G01X350571Y1008031D02*
Y1008178D01*
G01Y1009381D02*
Y1009528D01*
G01Y1004881D02*
Y1005028D01*
G01Y1006231D02*
Y1006378D01*
G01Y1001731D02*
Y1001878D01*
G01Y1003082D02*
Y1003229D01*
G01Y998582D02*
Y998729D01*
G01Y999932D02*
Y1000079D01*
G01Y996783D02*
Y996930D01*
G01Y995432D02*
Y995579D01*
G01Y992283D02*
Y992430D01*
G01Y993633D02*
Y993780D01*
G01Y989133D02*
Y989280D01*
G01Y990483D02*
Y990630D01*
G01X350531D02*
Y989134D01*
G01Y993780D02*
Y992283D01*
G01Y1000079D02*
Y998583D01*
G01Y996929D02*
Y995433D01*
G01Y1003228D02*
Y1001732D01*
G01Y1009528D02*
Y1008031D01*
G01Y1006378D02*
Y1004882D01*
G01X349350Y990472D02*
Y989291D01*
G01Y996772D02*
Y995591D01*
G01Y993622D02*
Y992441D01*
G01Y999921D02*
Y998740D01*
G01Y1003071D02*
Y1001890D01*
G01Y1009370D02*
Y1008189D01*
G01Y1006220D02*
Y1005039D01*
G01X349016Y1011535D02*
Y987126D01*
G01X348622D02*
Y1011535D01*
G01X345591Y1008189D02*
Y1009370D01*
G01Y1005039D02*
Y1006220D01*
G01Y1001890D02*
Y1003071D01*
G01Y998740D02*
Y999921D01*
G01Y995591D02*
Y996772D01*
G01Y992441D02*
Y993622D01*
G01Y989291D02*
Y990472D01*
G01X351516Y1008215D02*
X351515Y1008226D01*
G01X351516Y1005065D02*
X351515Y1005076D01*
G01X351516Y1001916D02*
X351515Y1001926D01*
G01X351516Y998766D02*
X351515Y998777D01*
G01X351516Y995617D02*
X351515Y995627D01*
G01X351516Y992467D02*
X351515Y992478D01*
G01X351516Y989317D02*
X351515Y989328D01*
G01X364941Y1081134D02*
Y1081125D01*
G01X364942Y1081140D02*
X364941Y1081134D01*
G01X364944Y1081142D02*
X364942Y1081140D01*
G01X364941Y1076134D02*
Y1076125D01*
G01X364942Y1076140D02*
X364941Y1076134D01*
G01X364944Y1076142D02*
X364942Y1076140D01*
G01X364941Y1071134D02*
Y1071125D01*
G01X364942Y1071140D02*
X364941Y1071134D01*
G01X364944Y1071142D02*
X364942Y1071140D01*
G01X364941Y1066134D02*
Y1066125D01*
G01X364942Y1066140D02*
X364941Y1066134D01*
G01X364944Y1066142D02*
X364942Y1066140D01*
G01X364941Y1061134D02*
Y1061125D01*
G01X364942Y1061140D02*
X364941Y1061134D01*
G01X364944Y1061142D02*
X364942Y1061140D01*
G01X364941Y1056134D02*
Y1056125D01*
G01X364942Y1056140D02*
X364941Y1056134D01*
G01X364944Y1056142D02*
X364942Y1056140D01*
G01X364941Y1051134D02*
Y1051125D01*
G01X364942Y1051140D02*
X364941Y1051134D01*
G01X364944Y1051142D02*
X364942Y1051140D01*
G01X364908Y1047618D02*
X364912Y1047717D01*
G01X364902Y1047546D02*
X364908Y1047618D01*
G01X364904Y1047520D02*
X364902Y1047546D01*
G01X364908Y1052618D02*
X364912Y1052717D01*
G01X364902Y1052546D02*
X364908Y1052618D01*
G01X364904Y1052520D02*
X364902Y1052546D01*
G01X364908Y1057618D02*
X364912Y1057717D01*
G01X364902Y1057546D02*
X364908Y1057618D01*
G01X364904Y1057520D02*
X364902Y1057546D01*
G01X364908Y1062618D02*
X364912Y1062717D01*
G01X364902Y1062546D02*
X364908Y1062618D01*
G01X364904Y1062520D02*
X364902Y1062546D01*
G01X364908Y1067618D02*
X364912Y1067717D01*
G01X364902Y1067546D02*
X364908Y1067618D01*
G01X364904Y1067520D02*
X364902Y1067546D01*
G01X364908Y1072618D02*
X364912Y1072717D01*
G01X364902Y1072546D02*
X364908Y1072618D01*
G01X364904Y1072520D02*
X364902Y1072546D01*
G01X364908Y1077618D02*
X364912Y1077717D01*
G01X364902Y1077546D02*
X364908Y1077618D01*
G01X364904Y1077520D02*
X364902Y1077546D01*
G01X364908Y1082618D02*
X364912Y1082717D01*
G01X364902Y1082546D02*
X364908Y1082618D01*
G01X364904Y1082520D02*
X364902Y1082546D01*
G01X363957Y1081140D02*
X363958Y1081142D01*
G01X363957Y1081134D02*
Y1081140D01*
G01Y1081126D02*
Y1081134D01*
G01Y1076140D02*
X363958Y1076142D01*
G01X363957Y1076134D02*
Y1076140D01*
G01Y1076126D02*
Y1076134D01*
G01Y1071140D02*
X363958Y1071142D01*
G01X363957Y1071134D02*
Y1071140D01*
G01Y1071126D02*
Y1071134D01*
G01Y1066140D02*
X363958Y1066142D01*
G01X363957Y1066134D02*
Y1066140D01*
G01Y1066126D02*
Y1066134D01*
G01Y1061140D02*
X363958Y1061142D01*
G01X363957Y1061134D02*
Y1061140D01*
G01Y1061126D02*
Y1061134D01*
G01Y1056140D02*
X363958Y1056142D01*
G01X363957Y1056134D02*
Y1056140D01*
G01Y1056126D02*
Y1056134D01*
G01Y1051140D02*
X363958Y1051142D01*
G01X363957Y1051134D02*
Y1051140D01*
G01Y1051126D02*
Y1051134D01*
G01X364924Y1052515D02*
X364904Y1052520D01*
G01X364938Y1052500D02*
X364924Y1052515D01*
G01X364943Y1052480D02*
X364938Y1052500D01*
G01X364924Y1057515D02*
X364904Y1057520D01*
G01X364938Y1057500D02*
X364924Y1057515D01*
G01X364943Y1057480D02*
X364938Y1057500D01*
G01X364924Y1062515D02*
X364904Y1062520D01*
G01X364938Y1062500D02*
X364924Y1062515D01*
G01X364943Y1062480D02*
X364938Y1062500D01*
G01X364924Y1067515D02*
X364904Y1067520D01*
G01X364938Y1067500D02*
X364924Y1067515D01*
G01X364943Y1067480D02*
X364938Y1067500D01*
G01X364924Y1072515D02*
X364904Y1072520D01*
G01X364938Y1072500D02*
X364924Y1072515D01*
G01X364943Y1072480D02*
X364938Y1072500D01*
G01X364924Y1077515D02*
X364904Y1077520D01*
G01X364938Y1077500D02*
X364924Y1077515D01*
G01X364943Y1077480D02*
X364938Y1077500D01*
G01X364924Y1082515D02*
X364904Y1082520D01*
G01X364938Y1082500D02*
X364924Y1082515D01*
G01X364943Y1082480D02*
X364938Y1082500D01*
G01X363957Y1047527D02*
Y1047536D01*
G01Y1047521D02*
Y1047527D01*
G01Y1052527D02*
Y1052536D01*
G01Y1052521D02*
Y1052527D01*
G01X363958Y1052520D02*
X363957Y1052521D01*
G01Y1057527D02*
Y1057536D01*
G01Y1057521D02*
Y1057527D01*
G01X363958Y1057520D02*
X363957Y1057521D01*
G01Y1062527D02*
Y1062536D01*
G01Y1062521D02*
Y1062527D01*
G01X363958Y1062520D02*
X363957Y1062521D01*
G01Y1067527D02*
Y1067536D01*
G01Y1067521D02*
Y1067527D01*
G01X363958Y1067520D02*
X363957Y1067521D01*
G01Y1072527D02*
Y1072536D01*
G01Y1072521D02*
Y1072527D01*
G01X363958Y1072520D02*
X363957Y1072521D01*
G01Y1077527D02*
Y1077536D01*
G01Y1077521D02*
Y1077527D01*
G01X363958Y1077520D02*
X363957Y1077521D01*
G01Y1082527D02*
Y1082536D01*
G01Y1082521D02*
Y1082527D01*
G01X363958Y1082520D02*
X363957Y1082521D01*
G01X364933Y1047663D02*
X364941Y1047637D01*
G01X364923Y1047690D02*
X364933Y1047663D01*
G01X364912Y1047717D02*
X364923Y1047690D01*
G01X364933Y1052663D02*
X364941Y1052637D01*
G01X364923Y1052690D02*
X364933Y1052663D01*
G01X364912Y1052717D02*
X364923Y1052690D01*
G01X364933Y1057663D02*
X364941Y1057637D01*
G01X364923Y1057690D02*
X364933Y1057663D01*
G01X364912Y1057717D02*
X364923Y1057690D01*
G01X364933Y1062663D02*
X364941Y1062637D01*
G01X364923Y1062690D02*
X364933Y1062663D01*
G01X364912Y1062717D02*
X364923Y1062690D01*
G01X364933Y1067663D02*
X364941Y1067637D01*
G01X364923Y1067690D02*
X364933Y1067663D01*
G01X364912Y1067717D02*
X364923Y1067690D01*
G01X364933Y1072663D02*
X364941Y1072637D01*
G01X364923Y1072690D02*
X364933Y1072663D01*
G01X364912Y1072717D02*
X364923Y1072690D01*
G01X364933Y1077663D02*
X364941Y1077637D01*
G01X364923Y1077690D02*
X364933Y1077663D01*
G01X364912Y1077717D02*
X364923Y1077690D01*
G01X364933Y1082663D02*
X364941Y1082637D01*
G01X364923Y1082690D02*
X364933Y1082663D01*
G01X364912Y1082717D02*
X364923Y1082690D01*
G01X364941Y1047487D02*
Y1047494D01*
G01Y1052487D02*
Y1052494D01*
G01X364942Y1052482D02*
X364941Y1052487D01*
G01X364943Y1052480D02*
X364942Y1052482D01*
G01X364941Y1057487D02*
Y1057494D01*
G01X364942Y1057482D02*
X364941Y1057487D01*
G01X364943Y1057480D02*
X364942Y1057482D01*
G01X364941Y1062487D02*
Y1062494D01*
G01X364942Y1062482D02*
X364941Y1062487D01*
G01X364943Y1062480D02*
X364942Y1062482D01*
G01X364941Y1067487D02*
Y1067494D01*
G01X364942Y1067482D02*
X364941Y1067487D01*
G01X364943Y1067480D02*
X364942Y1067482D01*
G01X364941Y1072487D02*
Y1072494D01*
G01X364942Y1072482D02*
X364941Y1072487D01*
G01X364943Y1072480D02*
X364942Y1072482D01*
G01X364941Y1077487D02*
Y1077494D01*
G01X364942Y1077482D02*
X364941Y1077487D01*
G01X364943Y1077480D02*
X364942Y1077482D01*
G01X364941Y1082487D02*
Y1082494D01*
G01X364942Y1082482D02*
X364941Y1082487D01*
G01X364943Y1082480D02*
X364942Y1082482D01*
G01X364928Y1052511D02*
X364939Y1052496D01*
G01X364904Y1052520D02*
X364928Y1052511D01*
G01Y1057511D02*
X364939Y1057496D01*
G01X364904Y1057520D02*
X364928Y1057511D01*
G01Y1062511D02*
X364939Y1062496D01*
G01X364904Y1062520D02*
X364928Y1062511D01*
G01Y1067511D02*
X364939Y1067496D01*
G01X364904Y1067520D02*
X364928Y1067511D01*
G01Y1072511D02*
X364939Y1072496D01*
G01X364904Y1072520D02*
X364928Y1072511D01*
G01Y1077511D02*
X364939Y1077496D01*
G01X364904Y1077520D02*
X364928Y1077511D01*
G01Y1082511D02*
X364939Y1082496D01*
G01X364904Y1082520D02*
X364928Y1082511D01*
G01X362327Y1170224D02*
G03X396138I16905J-13531D01*
G01X362327D02*
G03X396138I16905J-13531D01*
G01X363386Y1108012D02*
G03X362795Y1108602I-591J-1D01*
G01X356102D02*
G03X355512Y1108012I0J-590D01*
G01X358268Y1106831D02*
G03Y1104862I0J-985D01*
G01X360630D02*
G03Y1106831I0J984D01*
G01X356890Y1098917D02*
G03X355709Y1097736I0J-1181D01*
G01X363189D02*
G03X362008Y1098917I-1181J0D01*
G01X361339Y1093642D02*
G03I-1890J0D01*
G01X370276Y1107421D02*
G03X368307Y1109390I-1969J0D01*
G01X350591D02*
G03X348622Y1107421I0J-1969D01*
G01X361811Y1093642D02*
G03I-2362J0D01*
G01X368307Y1109390D02*
X350591D01*
G01X362795Y1108602D02*
X356102D01*
G01X360630Y1106831D02*
X358268D01*
G01Y1104862D02*
X360630D01*
G01X363386Y1103484D02*
X355512D01*
G01Y1101909D02*
X363386D01*
G01X370276Y1098957D02*
X348622D01*
G01X356890Y1098917D02*
X362008D01*
G01X358268Y1094232D02*
X360630D01*
G01X358268Y1092539D02*
X360630D01*
G01X351969Y1090571D02*
X366339D01*
G01X351969Y1089193D02*
X355709D01*
G01X366339D02*
X363189D01*
G01X351969Y1088327D02*
X366929D01*
G01X353740Y1086831D02*
X361614D01*
G01X354921Y1085650D02*
X360433D01*
G01X364941Y1083012D02*
X363957D01*
G01X363958Y1082520D02*
X369291D01*
G01Y1082480D02*
X364943D01*
G01X369291Y1081142D02*
X363958D01*
G01X363957Y1080650D02*
X364941D01*
G01Y1078012D02*
X363957D01*
G01X363958Y1077520D02*
X369291D01*
G01Y1077480D02*
X364943D01*
G01X369291Y1076142D02*
X363958D01*
G01X363957Y1075650D02*
X364941D01*
G01Y1073012D02*
X363957D01*
G01X363958Y1072520D02*
X369291D01*
G01Y1072480D02*
X364943D01*
G01X369291Y1071142D02*
X363958D01*
G01X363957Y1070650D02*
X364941D01*
G01Y1068012D02*
X363957D01*
G01X363958Y1067520D02*
X369291D01*
G01Y1067480D02*
X364943D01*
G01X369291Y1066142D02*
X363958D01*
G01X363957Y1065650D02*
X364941D01*
G01Y1063012D02*
X363957D01*
G01X363958Y1062520D02*
X369291D01*
G01Y1062480D02*
X364943D01*
G01X369291Y1061142D02*
X363958D01*
G01X363957Y1060650D02*
X364941D01*
G01Y1058012D02*
X363957D01*
G01X363958Y1057520D02*
X369291D01*
G01Y1057480D02*
X364943D01*
G01X369291Y1056142D02*
X363958D01*
G01X363957Y1055650D02*
X364941D01*
G01Y1053012D02*
X363957D01*
G01X363958Y1052520D02*
X369291D01*
G01Y1052480D02*
X364943D01*
G01X369291Y1051142D02*
X363958D01*
G01X363957Y1050650D02*
X364941D01*
G01Y1048012D02*
X363957D01*
G01X363958Y1047520D02*
X369291D01*
G01Y1047480D02*
X364943D01*
G01X363957Y1082715D02*
X364912Y1082717D01*
G01X364941Y1080946D02*
X363957Y1080945D01*
G01Y1077715D02*
X364912Y1077717D01*
G01X364941Y1075946D02*
X363957Y1075945D01*
G01Y1072715D02*
X364912Y1072717D01*
G01X364941Y1070946D02*
X363957Y1070945D01*
G01Y1067715D02*
X364912Y1067717D01*
G01X364941Y1065946D02*
X363957Y1065945D01*
G01Y1062715D02*
X364912Y1062717D01*
G01X364941Y1060946D02*
X363957Y1060945D01*
G01Y1057715D02*
X364912Y1057717D01*
G01X364941Y1055946D02*
X363957Y1055945D01*
G01Y1052715D02*
X364912Y1052717D01*
G01X364941Y1050946D02*
X363957Y1050945D01*
G01Y1047715D02*
X364912Y1047717D01*
G01X353740Y1086831D02*
X354921Y1085650D01*
G01X348622Y1091673D02*
X351969Y1088327D01*
G01X358268Y1094232D02*
X355957Y1098461D01*
G01X360630Y1092539D02*
X361933Y1090571D01*
G01X364941Y1047494D02*
Y1047502D01*
G01Y1052494D02*
Y1052502D01*
G01Y1057494D02*
Y1057502D01*
G01Y1062494D02*
Y1062502D01*
G01Y1067494D02*
Y1067502D01*
G01Y1072494D02*
Y1072502D01*
G01Y1077494D02*
Y1077502D01*
G01Y1082494D02*
Y1082502D01*
G01X370276Y1091673D02*
Y1107421D01*
G01X369291Y1081142D02*
Y1082520D01*
G01Y1076142D02*
Y1077520D01*
G01Y1071142D02*
Y1072520D01*
G01Y1066142D02*
Y1067520D01*
G01Y1061142D02*
Y1062520D01*
G01Y1056142D02*
Y1057520D01*
G01Y1051142D02*
Y1052520D01*
G01X366122D02*
Y1051142D01*
G01Y1057520D02*
Y1056142D01*
G01Y1062520D02*
Y1061142D01*
G01Y1067520D02*
Y1066142D01*
G01Y1072520D02*
Y1071142D01*
G01Y1077520D02*
Y1076142D01*
G01Y1082520D02*
Y1081142D01*
G01X364941Y1080650D02*
Y1083012D01*
G01Y1075650D02*
Y1078012D01*
G01Y1070650D02*
Y1073012D01*
G01Y1065650D02*
Y1068012D01*
G01Y1060650D02*
Y1063012D01*
G01Y1055650D02*
Y1058012D01*
G01Y1050650D02*
Y1053012D01*
G01Y1052494D02*
Y1052637D01*
G01Y1047494D02*
Y1047637D01*
G01Y1062494D02*
Y1062637D01*
G01Y1057494D02*
Y1057637D01*
G01Y1072494D02*
Y1072637D01*
G01Y1067494D02*
Y1067637D01*
G01Y1082494D02*
Y1082637D01*
G01Y1077494D02*
Y1077637D01*
G01X363957Y1053012D02*
Y1050650D01*
G01Y1058012D02*
Y1055650D01*
G01Y1063012D02*
Y1060650D01*
G01Y1068012D02*
Y1065650D01*
G01Y1073012D02*
Y1070650D01*
G01Y1078012D02*
Y1075650D01*
G01Y1083012D02*
Y1080650D01*
G01X363386Y1101909D02*
Y1108012D01*
G01X363189Y1097736D02*
Y1089193D01*
G01X360630Y1094232D02*
Y1092539D01*
G01X358268D02*
Y1094232D01*
G01X355709Y1089193D02*
Y1097736D01*
G01X355512Y1101909D02*
Y1108012D01*
G01X348622Y1107421D02*
Y1091673D01*
G01X370276D02*
X366929Y1088327D01*
G01X360433Y1085650D02*
X361614Y1086831D01*
G01X356964Y1090571D02*
X358268Y1092539D01*
G01X362940Y1098461D02*
X360630Y1094232D01*
G01X389213Y1183355D02*
G03X369252I-9981J-3040D01*
G01X362327Y1170224D02*
G03X369252Y1183355I-30737J24602D01*
G01X389213D02*
G03X369252I-9981J-3040D01*
G01X362327Y1170224D02*
G03X369252Y1183355I-30737J24602D01*
G01X291977Y1315803D02*
X291772Y1315761D01*
G01X302953Y1333028D02*
X304980D01*
G01X295118D02*
X293091D01*
G01X325118D02*
X323091D01*
G01X295059Y1332755D02*
X293091D01*
G01X304980D02*
X303012D01*
G01X325059D02*
X323091D01*
G01X295118Y1331059D02*
X293091D01*
G01X304980D02*
X302953D01*
G01X325118D02*
X323091D01*
G01Y1328070D02*
X325059D01*
G01X303012D02*
X304980D01*
G01X293091D02*
X295059D01*
G01X295118Y1323972D02*
X293091D01*
G01X304980D02*
X302953D01*
G01X325118D02*
X323091D01*
G01X295059Y1322794D02*
X293091D01*
G01X304980D02*
X303012D01*
G01X325059D02*
X323091D01*
G01Y1321790D02*
X325118D01*
G01X302953D02*
X304980D01*
G01X293091D02*
X295118D01*
G01X302953Y1319606D02*
X295118D01*
G01X332953D02*
X325118D01*
G01X323091Y1318109D02*
X325059D01*
G01X303012D02*
X304980D01*
G01X293091D02*
X295059D01*
G01X297144Y1316850D02*
X297390D01*
G01X295422D02*
X295668D01*
G01X293207D02*
X293576D01*
G01X294602D02*
X294848D01*
G01X292633D02*
X292879D01*
G01X290787D02*
X291772D01*
G01X291813Y1316641D02*
X291033D01*
G01Y1316013D02*
X291813D01*
G01X291772Y1315761D02*
X291033D01*
G01X295996Y1315091D02*
X296570D01*
G01X291033Y1314882D02*
X290787D01*
G01X296570D02*
X295996D01*
G01X295668D02*
X295422D01*
G01X293453D02*
X293207D01*
G01X294848D02*
X294478D01*
G01X292879D02*
X292633D01*
G01X297390D02*
X297144D01*
G01X319035Y1311456D02*
X339035D01*
G01X319035Y1310275D02*
X309035D01*
G01X291772Y1316850D02*
X291977Y1316808D01*
G01X291936Y1316599D02*
X291813Y1316641D01*
G01X291977Y1316808D02*
X292141Y1316683D01*
G01X292018Y1316515D02*
X291936Y1316599D01*
G01X292141Y1316683D02*
X292264Y1316515D01*
G01X294478Y1314882D02*
X293453Y1316599D01*
G01X293576Y1316850D02*
X294602Y1315175D01*
G01X292264Y1316515D02*
X292305Y1316390D01*
G01X292059D02*
X292018Y1316515D01*
G01X325118Y1357086D02*
Y1319606D01*
G01X325059Y1328070D02*
Y1332755D01*
G01Y1318109D02*
Y1322794D01*
G01X323091Y1333028D02*
Y1342716D01*
G01Y1318109D02*
Y1332755D01*
G01X319035Y1310275D02*
Y1311456D01*
G01X309035D02*
Y1310275D01*
G01X304980Y1333028D02*
Y1342716D01*
G01Y1318109D02*
Y1332755D01*
G01X303012Y1322794D02*
Y1318109D01*
G01Y1332755D02*
Y1328070D01*
G01X302953Y1319606D02*
Y1357086D01*
G01X297390Y1316850D02*
Y1314882D01*
G01X297144D02*
Y1316515D01*
G01X296898Y1316222D02*
Y1316557D01*
G01X296570Y1315091D02*
Y1314882D01*
G01X295996D02*
Y1315091D01*
G01X295668Y1316850D02*
Y1314882D01*
G01X295422D02*
Y1316515D01*
G01X295176Y1316222D02*
Y1316557D01*
G01X295118Y1357086D02*
Y1319606D01*
G01X295059Y1328070D02*
Y1332755D01*
G01Y1318109D02*
Y1322794D01*
G01X294848Y1316850D02*
Y1314882D01*
G01X294602Y1315175D02*
Y1316850D01*
G01X293453Y1316599D02*
Y1314882D01*
G01X293207D02*
Y1316850D01*
G01X293091Y1333028D02*
Y1342716D01*
G01Y1318109D02*
Y1332755D01*
G01X292879Y1316850D02*
Y1314882D01*
G01X292633D02*
Y1316850D01*
G01X292305Y1316390D02*
Y1316222D01*
G01X292059Y1316264D02*
Y1316390D01*
G01X291033Y1316641D02*
Y1316013D01*
G01Y1315761D02*
Y1314882D01*
G01X290787D02*
Y1316850D01*
G01X291813Y1316013D02*
X291936Y1316055D01*
G01X292141Y1315929D02*
X291977Y1315803D01*
G01X291936Y1316055D02*
X292018Y1316138D01*
G01X297144Y1316515D02*
X296898Y1316222D01*
G01Y1316557D02*
X297144Y1316850D01*
G01X295422Y1316515D02*
X295176Y1316222D01*
G01Y1316557D02*
X295422Y1316850D01*
G01X292264Y1316096D02*
X292141Y1315929D01*
G01X292305Y1316222D02*
X292264Y1316096D01*
G01X292018Y1316138D02*
X292059Y1316264D01*
G01X362953Y1333028D02*
X364980D01*
G01X332953D02*
X334980D01*
G01X355118D02*
X353091D01*
G01X385118D02*
X383091D01*
G01X334980Y1332755D02*
X333012D01*
G01X355059D02*
X353091D01*
G01X364980D02*
X363012D01*
G01X385059D02*
X383091D01*
G01X334980Y1331059D02*
X332953D01*
G01X355118D02*
X353091D01*
G01X364980D02*
X362953D01*
G01X385118D02*
X383091D01*
G01Y1328070D02*
X385059D01*
G01X363012D02*
X364980D01*
G01X353091D02*
X355059D01*
G01X333012D02*
X334980D01*
G01Y1323972D02*
X332953D01*
G01X355118D02*
X353091D01*
G01X364980D02*
X362953D01*
G01X385118D02*
X383091D01*
G01X334980Y1322794D02*
X333012D01*
G01X355059D02*
X353091D01*
G01X364980D02*
X363012D01*
G01X385059D02*
X383091D01*
G01Y1321790D02*
X385118D01*
G01X362953D02*
X364980D01*
G01X353091D02*
X355118D01*
G01X332953D02*
X334980D01*
G01X362953Y1319606D02*
X355118D01*
G01X392953D02*
X385118D01*
G01X383091Y1318109D02*
X385059D01*
G01X363012D02*
X364980D01*
G01X353091D02*
X355059D01*
G01X333012D02*
X334980D01*
G01X379035Y1311456D02*
X399035D01*
G01X349035D02*
X369035D01*
G01X349035Y1310275D02*
X339035D01*
G01X379035D02*
X369035D01*
G01X385118Y1357086D02*
Y1319606D01*
G01X385059Y1328070D02*
Y1332755D01*
G01Y1318109D02*
Y1322794D01*
G01X383091Y1333028D02*
Y1342716D01*
G01Y1318109D02*
Y1332755D01*
G01X379035Y1310275D02*
Y1311456D01*
G01X369035D02*
Y1310275D01*
G01X364980Y1333028D02*
Y1342716D01*
G01Y1318109D02*
Y1332755D01*
G01X363012Y1322794D02*
Y1318109D01*
G01Y1332755D02*
Y1328070D01*
G01X362953Y1319606D02*
Y1357086D01*
G01X355118D02*
Y1319606D01*
G01X355059Y1328070D02*
Y1332755D01*
G01Y1318109D02*
Y1322794D01*
G01X353091Y1333028D02*
Y1342716D01*
G01Y1318109D02*
Y1332755D01*
G01X349035Y1310275D02*
Y1311456D01*
G01X339035D02*
Y1310275D01*
G01X334980Y1333028D02*
Y1342716D01*
G01Y1318109D02*
Y1332755D01*
G01X333012Y1322794D02*
Y1318109D01*
G01Y1332755D02*
Y1328070D01*
G01X332953Y1319606D02*
Y1357086D01*
G01X319035Y1360669D02*
X309035D01*
G01X319035Y1360472D02*
X339035D01*
G01X325118Y1357086D02*
X332953D01*
G01X295118D02*
X302953D01*
G01X295059Y1352676D02*
X293091D01*
G01X304980D02*
X303012D01*
G01X325059D02*
X323091D01*
G01Y1352336D02*
X325118D01*
G01X302953D02*
X304980D01*
G01X293091D02*
X295118D01*
G01Y1350154D02*
X293091D01*
G01X304980D02*
X302953D01*
G01X325118D02*
X323091D01*
G01Y1347991D02*
X325059D01*
G01X303012D02*
X304980D01*
G01X293091D02*
X295059D01*
G01X302953Y1343028D02*
X304980D01*
G01X295118D02*
X293091D01*
G01X325118D02*
X323091D01*
G01X295059Y1342716D02*
X293091D01*
G01X304980D02*
X303012D01*
G01X325059D02*
X323091D01*
G01X295118Y1341059D02*
X293091D01*
G01X304980D02*
X302953D01*
G01X325118D02*
X323091D01*
G01Y1338031D02*
X325059D01*
G01X303012D02*
X304980D01*
G01X293091D02*
X295059D01*
G01X325059Y1347991D02*
Y1352676D01*
G01Y1338031D02*
Y1342716D01*
G01X323091Y1343028D02*
Y1352676D01*
G01X319035Y1360472D02*
Y1360669D01*
G01X309035D02*
Y1360472D01*
G01X304980Y1343028D02*
Y1352676D01*
G01X303012Y1342716D02*
Y1338031D01*
G01Y1352676D02*
Y1347991D01*
G01X295059D02*
Y1352676D01*
G01Y1338031D02*
Y1342716D01*
G01X293091Y1343028D02*
Y1352676D01*
G01X349035Y1360669D02*
X339035D01*
G01X379035D02*
X369035D01*
G01X379035Y1360472D02*
X399035D01*
G01X349035D02*
X369035D01*
G01X385118Y1357086D02*
X392953D01*
G01X355118D02*
X362953D01*
G01X334980Y1352676D02*
X333012D01*
G01X355059D02*
X353091D01*
G01X364980D02*
X363012D01*
G01X385059D02*
X383091D01*
G01Y1352336D02*
X385118D01*
G01X362953D02*
X364980D01*
G01X353091D02*
X355118D01*
G01X332953D02*
X334980D01*
G01Y1350154D02*
X332953D01*
G01X355118D02*
X353091D01*
G01X364980D02*
X362953D01*
G01X385118D02*
X383091D01*
G01Y1347991D02*
X385059D01*
G01X363012D02*
X364980D01*
G01X353091D02*
X355059D01*
G01X333012D02*
X334980D01*
G01X362953Y1343028D02*
X364980D01*
G01X332953D02*
X334980D01*
G01X355118D02*
X353091D01*
G01X385118D02*
X383091D01*
G01X334980Y1342716D02*
X333012D01*
G01X355059D02*
X353091D01*
G01X364980D02*
X363012D01*
G01X385059D02*
X383091D01*
G01X334980Y1341059D02*
X332953D01*
G01X355118D02*
X353091D01*
G01X364980D02*
X362953D01*
G01X385118D02*
X383091D01*
G01Y1338031D02*
X385059D01*
G01X363012D02*
X364980D01*
G01X353091D02*
X355059D01*
G01X333012D02*
X334980D01*
G01X385059Y1347991D02*
Y1352676D01*
G01Y1338031D02*
Y1342716D01*
G01X383091Y1343028D02*
Y1352676D01*
G01X379035Y1360472D02*
Y1360669D01*
G01X369035D02*
Y1360472D01*
G01X364980Y1343028D02*
Y1352676D01*
G01X363012Y1342716D02*
Y1338031D01*
G01Y1352676D02*
Y1347991D01*
G01X355059D02*
Y1352676D01*
G01Y1338031D02*
Y1342716D01*
G01X353091Y1343028D02*
Y1352676D01*
G01X349035Y1360472D02*
Y1360669D01*
G01X339035D02*
Y1360472D01*
G01X334980Y1343028D02*
Y1352676D01*
G01X333012Y1342716D02*
Y1338031D01*
G01Y1352676D02*
Y1347991D01*
G01X296457Y1519685D02*
G03X292520Y1515748I0J-3937D01*
G01X322441Y1503937D02*
G03Y1496063I0J-3937D01*
G01X304331D02*
G03Y1503937I0J3937D01*
G01X296457Y1519685D02*
X485433D01*
G01X304331Y1503937D02*
X292520D01*
G01X459449D02*
X322441D01*
G01X292520Y1515748D02*
Y1503937D01*
G01X459449D02*
X322441D01*
G01X304331D02*
X292520D01*
G01X296457Y1519685D02*
G03X292520Y1515748I0J-3937D01*
G01X322441Y1503937D02*
G03Y1496063I0J-3937D01*
G01X304331D02*
G03Y1503937I0J3937D01*
G01X292520Y1515748D02*
Y1503937D01*
G01X296457Y1519685D02*
X485433D01*
G01X478266Y-369410D02*
Y-388347D01*
G01X458849Y-369410D02*
X1640444D01*
G01X475697Y91259D02*
X475687Y91260D01*
G01X475706Y91256D02*
X475697Y91259D01*
G01X475713Y91250D02*
X475706Y91256D01*
G01X475697Y84959D02*
X475687Y84961D01*
G01X475706Y84956D02*
X475697Y84959D01*
G01X475713Y84951D02*
X475706Y84956D01*
G01X475697Y88109D02*
X475687Y88110D01*
G01X475706Y88106D02*
X475697Y88109D01*
G01X475713Y88100D02*
X475706Y88106D01*
G01X474783Y83774D02*
Y83768D01*
G01X474782Y83778D02*
X474783Y83774D01*
G01X474781Y83780D02*
X474782Y83778D01*
G01X474783Y86924D02*
Y86918D01*
G01X474782Y86928D02*
X474783Y86924D01*
G01X474781Y86929D02*
X474782Y86928D01*
G01X474783Y90074D02*
Y90067D01*
G01X474782Y90078D02*
X474783Y90074D01*
G01X474781Y90079D02*
X474782Y90078D01*
G01X474783Y93223D02*
Y93217D01*
G01X474782Y93227D02*
X474783Y93223D01*
G01X474781Y93228D02*
X474782Y93227D01*
G01X475698Y84959D02*
X475707Y84955D01*
G01X475687Y84961D02*
X475698Y84959D01*
G01Y88109D02*
X475707Y88105D01*
G01X475687Y88110D02*
X475698Y88109D01*
G01Y91258D02*
X475707Y91254D01*
G01X475687Y91260D02*
X475698Y91258D01*
G01X474744Y86959D02*
Y86955D01*
G01X474746Y86952D02*
X474744Y86959D01*
G01X474757Y86937D02*
X474746Y86952D01*
G01X474782Y86929D02*
X474757Y86937D01*
G01X474744Y90108D02*
Y90104D01*
G01X474746Y90102D02*
X474744Y90108D01*
G01X474757Y90087D02*
X474746Y90102D01*
G01X474781Y90079D02*
X474757Y90087D01*
G01X474744Y83809D02*
Y83806D01*
G01X474746Y83803D02*
X474744Y83809D01*
G01X474757Y83788D02*
X474746Y83803D01*
G01X474781Y83780D02*
X474757Y83788D01*
G01X474744Y93258D02*
Y93254D01*
G01X474746Y93252D02*
X474744Y93258D01*
G01X474756Y93238D02*
X474746Y93252D01*
G01X474779Y93228D02*
X474756Y93238D01*
G01X474767Y86931D02*
X474781Y86929D01*
G01X474756Y86939D02*
X474767Y86931D01*
G01X474743Y86957D02*
X474756Y86939D01*
G01X474767Y90081D02*
X474781Y90079D01*
G01X474754Y90089D02*
X474767Y90081D01*
G01X474743Y90109D02*
X474754Y90089D01*
G01X475728Y83813D02*
Y83805D01*
G01Y83817D02*
Y83813D01*
G01X475727Y83819D02*
X475728Y83817D01*
G01Y86963D02*
Y86955D01*
G01Y86967D02*
Y86963D01*
G01X475727Y86969D02*
X475728Y86967D01*
G01Y90112D02*
Y90104D01*
G01Y90117D02*
Y90112D01*
G01X475727Y90118D02*
X475728Y90117D01*
G01Y93262D02*
Y93254D01*
G01Y93266D02*
Y93262D01*
G01X475727Y93268D02*
X475728Y93266D01*
G01X474766Y83782D02*
X474781Y83780D01*
G01X474753Y83791D02*
X474766Y83782D01*
G01X474743Y83811D02*
X474753Y83791D01*
G01X475728Y84941D02*
Y84935D01*
G01X475726Y84948D02*
X475728Y84941D01*
G01X475723Y84954D02*
X475726Y84948D01*
G01X475728Y88091D02*
Y88084D01*
G01X475726Y88097D02*
X475728Y88091D01*
G01X475723Y88103D02*
X475726Y88097D01*
G01X475728Y91241D02*
Y91234D01*
G01X475726Y91247D02*
X475728Y91241D01*
G01X475723Y91253D02*
X475726Y91247D01*
G01X475689Y83774D02*
X475690Y83768D01*
G01X475688Y83778D02*
X475689Y83774D01*
G01X475687Y83780D02*
X475688Y83778D01*
G01X475689Y86924D02*
X475690Y86918D01*
G01X475688Y86928D02*
X475689Y86924D01*
G01X475687Y86929D02*
X475688Y86928D01*
G01X475689Y90074D02*
X475690Y90067D01*
G01X475688Y90077D02*
X475689Y90074D01*
G01X475687Y90079D02*
X475688Y90077D01*
G01X475689Y93223D02*
X475690Y93217D01*
G01X475688Y93227D02*
X475689Y93223D01*
G01X475687Y93228D02*
X475688Y93227D01*
G01X475706Y83772D02*
X475709Y83774D01*
G01X475703Y83770D02*
X475706Y83772D01*
G01X475700Y83770D02*
X475703D01*
G01X475696Y83769D02*
X475700Y83770D01*
G01X475693Y83769D02*
X475696D01*
G01X475689Y83768D02*
X475693Y83769D01*
G01X474767Y84968D02*
X474763Y84967D01*
G01X474770Y84969D02*
X474767Y84968D01*
G01X474773Y84970D02*
X474770Y84969D01*
G01X474776Y84971D02*
X474773Y84970D01*
G01X474780Y84972D02*
X474776Y84971D01*
G01X474783Y84972D02*
X474780D01*
G01X475706Y86921D02*
X475709Y86923D01*
G01X475703Y86920D02*
X475706Y86921D01*
G01X475700Y86919D02*
X475703Y86920D01*
G01X475696Y86919D02*
X475700D01*
G01X475693Y86918D02*
X475696Y86919D01*
G01X475689Y86918D02*
X475693D01*
G01X474767Y88118D02*
X474763Y88116D01*
G01X474770Y88119D02*
X474767Y88118D01*
G01X474773Y88120D02*
X474770Y88119D01*
G01X474776Y88121D02*
X474773Y88120D01*
G01X474780Y88121D02*
X474776D01*
G01X474783D02*
X474780D01*
G01X475706Y90071D02*
X475709Y90073D01*
G01X475703Y90070D02*
X475706Y90071D01*
G01X475700Y90069D02*
X475703Y90070D01*
G01X475696Y90068D02*
X475700Y90069D01*
G01X475693Y90068D02*
X475696D01*
G01X475689Y90067D02*
X475693Y90068D01*
G01X474767Y91267D02*
X474763Y91266D01*
G01X474770Y91269D02*
X474767Y91267D01*
G01X474773Y91270D02*
X474770Y91269D01*
G01X474776Y91270D02*
X474773D01*
G01X474780Y91271D02*
X474776Y91270D01*
G01X474783Y91271D02*
X474780D01*
G01X475706Y93220D02*
X475709Y93222D01*
G01X475703Y93219D02*
X475706Y93220D01*
G01X475700Y93219D02*
X475703D01*
G01X475696Y93218D02*
X475700Y93219D01*
G01X475693Y93217D02*
X475696Y93218D01*
G01X475689Y93217D02*
X475693D01*
G01X473997Y86969D02*
X473563D01*
G01X474370D02*
X473997D01*
G01Y93268D02*
X473563D01*
G01X474370D02*
X473997D01*
G01X475719Y84959D02*
X475723Y84954D01*
G01X475714Y84963D02*
X475719Y84959D01*
G01X475708Y84967D02*
X475714Y84963D01*
G01X475702Y84970D02*
X475708Y84967D01*
G01X475696Y84971D02*
X475702Y84970D01*
G01X475689Y84972D02*
X475696Y84971D01*
G01X475719Y88109D02*
X475723Y88103D01*
G01X475714Y88113D02*
X475719Y88109D01*
G01X475708Y88117D02*
X475714Y88113D01*
G01X475702Y88119D02*
X475708Y88117D01*
G01X475696Y88121D02*
X475702Y88119D01*
G01X475689Y88121D02*
X475696D01*
G01X475719Y91258D02*
X475723Y91253D01*
G01X475714Y91263D02*
X475719Y91258D01*
G01X475708Y91266D02*
X475714Y91263D01*
G01X475702Y91269D02*
X475708Y91266D01*
G01X475696Y91270D02*
X475702Y91269D01*
G01X475689Y91271D02*
X475696Y91270D01*
G01X474745Y83798D02*
X474744Y83805D01*
G01X474747Y83791D02*
X474745Y83798D01*
G01X474751Y83785D02*
X474747Y83791D01*
G01X474756Y83779D02*
X474751Y83785D01*
G01X474762Y83774D02*
X474756Y83779D01*
G01X474769Y83771D02*
X474762Y83774D01*
G01X474776Y83769D02*
X474769Y83771D01*
G01X474783Y83768D02*
X474776Y83769D01*
G01X474745Y86948D02*
X474744Y86955D01*
G01X474747Y86941D02*
X474745Y86948D01*
G01X474751Y86934D02*
X474747Y86941D01*
G01X474756Y86929D02*
X474751Y86934D01*
G01X474762Y86924D02*
X474756Y86929D01*
G01X474769Y86920D02*
X474762Y86924D01*
G01X474776Y86919D02*
X474769Y86920D01*
G01X474783Y86918D02*
X474776Y86919D01*
G01X474745Y90097D02*
X474744Y90104D01*
G01X474747Y90090D02*
X474745Y90097D01*
G01X474751Y90084D02*
X474747Y90090D01*
G01X474756Y90078D02*
X474751Y90084D01*
G01X474762Y90074D02*
X474756Y90078D01*
G01X474769Y90070D02*
X474762Y90074D01*
G01X474776Y90068D02*
X474769Y90070D01*
G01X474783Y90067D02*
X474776Y90068D01*
G01X474745Y93247D02*
X474744Y93254D01*
G01X474747Y93240D02*
X474745Y93247D01*
G01X474751Y93233D02*
X474747Y93240D01*
G01X474756Y93228D02*
X474751Y93233D01*
G01X474762Y93223D02*
X474756Y93228D01*
G01X474769Y93220D02*
X474762Y93223D01*
G01X474776Y93218D02*
X474769Y93220D01*
G01X474783Y93217D02*
X474776Y93218D01*
G01X474762Y93233D02*
X474781Y93228D01*
G01X474748Y93246D02*
X474762Y93233D01*
G01X474742Y93263D02*
X474748Y93246D01*
G01X475721Y91242D02*
X475713Y91250D01*
G01X475726Y91231D02*
X475721Y91242D01*
G01X475727Y91220D02*
X475726Y91231D01*
G01X475721Y84943D02*
X475713Y84951D01*
G01X475726Y84932D02*
X475721Y84943D01*
G01X475727Y84921D02*
X475726Y84932D01*
G01X475721Y88092D02*
X475713Y88100D01*
G01X475726Y88082D02*
X475721Y88092D01*
G01X475727Y88071D02*
X475726Y88082D01*
G01X474784Y91444D02*
X474783Y91457D01*
G01X474781Y91431D02*
X474784Y91444D01*
G01X474781Y91417D02*
Y91431D01*
G01X474784Y88294D02*
X474783Y88307D01*
G01X474781Y88281D02*
X474784Y88294D01*
G01X474781Y88268D02*
Y88281D01*
G01X474784Y85145D02*
X474783Y85157D01*
G01X474781Y85132D02*
X474784Y85145D01*
G01X474781Y85118D02*
Y85132D01*
G01X474747Y84941D02*
X474742Y84921D01*
G01X474761Y84955D02*
X474747Y84941D01*
G01X474781Y84961D02*
X474761Y84955D01*
G01X474747Y88091D02*
X474742Y88071D01*
G01X474761Y88105D02*
X474747Y88091D01*
G01X474781Y88110D02*
X474761Y88105D01*
G01X474747Y91240D02*
X474742Y91220D01*
G01X474761Y91254D02*
X474747Y91240D01*
G01X474781Y91260D02*
X474761Y91254D01*
G01X475722Y83799D02*
X475727Y83819D01*
G01X475707Y83785D02*
X475722Y83799D01*
G01X475687Y83780D02*
X475707Y83785D01*
G01X475722Y86949D02*
X475727Y86969D01*
G01X475707Y86934D02*
X475722Y86949D01*
G01X475687Y86929D02*
X475707Y86934D01*
G01X475722Y90098D02*
X475727Y90118D01*
G01X475707Y90084D02*
X475722Y90098D01*
G01X475687Y90079D02*
X475707Y90084D01*
G01X475722Y93248D02*
X475727Y93268D01*
G01X475707Y93233D02*
X475722Y93248D01*
G01X475687Y93228D02*
X475707Y93233D01*
G01X474781Y93057D02*
X474780Y93070D01*
G01X474784Y93044D02*
X474781Y93057D01*
G01X474783Y93031D02*
X474784Y93044D01*
G01X474781Y89907D02*
X474780Y89921D01*
G01X474784Y89894D02*
X474781Y89907D01*
G01X474783Y89882D02*
X474784Y89894D01*
G01X474781Y86757D02*
X474780Y86771D01*
G01X474784Y86745D02*
X474781Y86757D01*
G01X474783Y86732D02*
X474784Y86745D01*
G01X474781Y83608D02*
X474780Y83622D01*
G01X474784Y83595D02*
X474781Y83608D01*
G01X474783Y83583D02*
X474784Y83595D01*
G01X475691Y91431D02*
X475693Y91417D01*
G01X475688Y91444D02*
X475691Y91431D01*
G01X475689Y91457D02*
X475688Y91444D01*
G01X475691Y88281D02*
X475693Y88268D01*
G01X475688Y88294D02*
X475691Y88281D01*
G01X475689Y88307D02*
X475688Y88294D01*
G01X475691Y85132D02*
X475693Y85118D01*
G01X475688Y85145D02*
X475691Y85132D01*
G01X475689Y85157D02*
X475688Y85145D01*
G01X474744Y90112D02*
Y90105D01*
G01X474743Y90117D02*
X474744Y90112D01*
G01X474743Y90109D02*
Y90117D01*
G01X475688Y93044D02*
X475689Y93031D01*
G01X475691Y93057D02*
X475688Y93044D01*
G01X475692Y93070D02*
X475691Y93057D01*
G01X475688Y89894D02*
X475689Y89882D01*
G01X475691Y89907D02*
X475688Y89894D01*
G01X475692Y89921D02*
X475691Y89907D01*
G01X475688Y86745D02*
X475689Y86732D01*
G01X475691Y86757D02*
X475688Y86745D01*
G01X475692Y86771D02*
X475691Y86757D01*
G01X475688Y83595D02*
X475689Y83583D01*
G01X475691Y83608D02*
X475688Y83595D01*
G01X475692Y83622D02*
X475691Y83608D01*
G01X474744Y83813D02*
Y83806D01*
G01X474743Y83817D02*
X474744Y83813D01*
G01X474743Y83811D02*
Y83817D01*
G01X474757Y91251D02*
X474781Y91260D01*
G01X474746Y91237D02*
X474757Y91251D01*
G01X474744Y91230D02*
X474746Y91237D01*
G01X474757Y88102D02*
X474781Y88110D01*
G01X474746Y88087D02*
X474757Y88102D01*
G01X474744Y88080D02*
X474746Y88087D01*
G01X474757Y84952D02*
X474781Y84961D01*
G01X474746Y84937D02*
X474757Y84952D01*
G01X474744Y84931D02*
X474746Y84937D01*
G01X475728Y91227D02*
Y91234D01*
G01Y91222D02*
Y91227D01*
G01X475727Y91220D02*
X475728Y91222D01*
G01Y88077D02*
Y88084D01*
G01Y88072D02*
Y88077D01*
G01X475727Y88071D02*
X475728Y88072D01*
G01Y84928D02*
Y84935D01*
G01Y84923D02*
Y84928D01*
G01X475727Y84921D02*
X475728Y84923D01*
G01X474744Y93262D02*
Y93254D01*
G01X474743Y93266D02*
X474744Y93262D01*
G01X474742Y93263D02*
X474743Y93266D01*
G01X474744Y86963D02*
Y86955D01*
G01X474743Y86967D02*
X474744Y86963D01*
G01X474742Y86965D02*
X474743Y86967D01*
G01X475689Y91265D02*
Y91271D01*
G01X475688Y91261D02*
X475689Y91265D01*
G01X475687Y91260D02*
X475688Y91261D01*
G01X475689Y88115D02*
Y88121D01*
G01X475688Y88111D02*
X475689Y88115D01*
G01X475687Y88110D02*
X475688Y88111D01*
G01X475689Y84966D02*
Y84972D01*
G01X475688Y84962D02*
X475689Y84966D01*
G01X475687Y84961D02*
X475688Y84962D01*
G01X474744Y91226D02*
Y91234D01*
G01X474743Y91222D02*
X474744Y91226D01*
G01X474742Y91220D02*
X474743Y91222D01*
G01X474744Y88077D02*
Y88084D01*
G01X474743Y88072D02*
X474744Y88077D01*
G01X474742Y88071D02*
X474743Y88072D01*
G01X474744Y84927D02*
Y84935D01*
G01X474743Y84923D02*
X474744Y84927D01*
G01X474742Y84921D02*
X474743Y84923D01*
G01X475726Y93242D02*
X475728Y93254D01*
G01X475719Y93230D02*
X475726Y93242D01*
G01X475709Y93222D02*
X475719Y93230D01*
G01X475726Y90092D02*
X475728Y90104D01*
G01X475719Y90081D02*
X475726Y90092D01*
G01X475709Y90073D02*
X475719Y90081D01*
G01X475726Y86943D02*
X475728Y86955D01*
G01X475719Y86931D02*
X475726Y86943D01*
G01X475709Y86923D02*
X475719Y86931D01*
G01X475726Y83793D02*
X475728Y83805D01*
G01X475719Y83781D02*
X475726Y83793D01*
G01X475709Y83774D02*
X475719Y83781D01*
G01X474783Y91265D02*
Y91271D01*
G01Y91261D02*
Y91265D01*
G01X474781Y91260D02*
X474783Y91261D01*
G01Y88115D02*
Y88121D01*
G01Y88111D02*
Y88115D01*
G01X474781Y88110D02*
X474783Y88111D01*
G01Y84965D02*
Y84972D01*
G01Y84962D02*
Y84965D01*
G01X474781Y84961D02*
X474783Y84962D01*
G01X474745Y91240D02*
X474744Y91234D01*
G01X474746Y91246D02*
X474745Y91240D01*
G01X474749Y91252D02*
X474746Y91246D01*
G01X474753Y91257D02*
X474749Y91252D01*
G01X474758Y91262D02*
X474753Y91257D01*
G01X474763Y91266D02*
X474758Y91262D01*
G01X474745Y88091D02*
X474744Y88084D01*
G01X474746Y88097D02*
X474745Y88091D01*
G01X474749Y88103D02*
X474746Y88097D01*
G01X474753Y88108D02*
X474749Y88103D01*
G01X474758Y88113D02*
X474753Y88108D01*
G01X474763Y88116D02*
X474758Y88113D01*
G01X474745Y84941D02*
X474744Y84935D01*
G01X474746Y84947D02*
X474745Y84941D01*
G01X474749Y84953D02*
X474746Y84947D01*
G01X474753Y84958D02*
X474749Y84953D01*
G01X474758Y84963D02*
X474753Y84958D01*
G01X474763Y84967D02*
X474758Y84963D01*
G01X475700Y93230D02*
X475687Y93228D01*
G01X475710Y93235D02*
X475700Y93230D01*
G01Y90081D02*
X475687Y90079D01*
G01X475710Y90085D02*
X475700Y90081D01*
G01Y86931D02*
X475687Y86929D01*
G01X475710Y86936D02*
X475700Y86931D01*
G01Y83781D02*
X475687Y83780D01*
G01X475710Y83786D02*
X475700Y83781D01*
G01X414665Y94488D02*
G03X428642I6989J0D01*
G01D02*
G03I-6988J0D01*
G01X479724Y25138D02*
G03X480315Y24547I591J0D01*
G01X479921Y35413D02*
G03X481102Y34232I1181J0D01*
G01X472835Y25728D02*
G03X474803Y23760I1968J0D01*
G01X479134Y47500D02*
X477953Y46319D01*
G01X476181Y44823D02*
X472835Y41476D01*
G01X480170Y34688D02*
X482480Y38917D01*
G01X475728Y84923D02*
Y84935D01*
G01Y88073D02*
Y88084D01*
G01Y91222D02*
Y91234D01*
G01X479921Y35413D02*
Y43957D01*
G01X479724Y31240D02*
Y25138D01*
G01X479134Y47500D02*
Y180138D01*
G01X477953Y46319D02*
Y181319D01*
G01X476181Y81614D02*
Y42579D01*
G01X475728Y93070D02*
Y94567D01*
G01Y89921D02*
Y91417D01*
G01Y86771D02*
Y88268D01*
G01Y83622D02*
Y85118D01*
G01X475689Y86918D02*
Y86771D01*
G01Y83768D02*
Y83621D01*
G01Y85119D02*
Y84972D01*
G01Y90067D02*
Y89920D01*
G01Y91418D02*
Y91271D01*
G01Y88268D02*
Y88121D01*
G01Y93217D02*
Y93070D01*
G01X474783D02*
Y93217D01*
G01Y89920D02*
Y90067D01*
G01Y91271D02*
Y91418D01*
G01Y88121D02*
Y88268D01*
G01Y86771D02*
Y86918D01*
G01Y83621D02*
Y83768D01*
G01Y84972D02*
Y85119D01*
G01X474744Y85118D02*
Y83622D01*
G01Y91417D02*
Y89921D01*
G01Y88268D02*
Y86772D01*
G01Y94567D02*
Y93071D01*
G01X473563Y88110D02*
Y86929D01*
G01Y84961D02*
Y83780D01*
G01Y91260D02*
Y90079D01*
G01Y94409D02*
Y93228D01*
G01X473228Y106024D02*
Y81614D01*
G01X472835D02*
Y106024D01*
G01Y41476D02*
Y25728D01*
G01X469803Y93228D02*
Y94409D01*
G01Y90079D02*
Y91260D01*
G01Y86929D02*
Y88110D01*
G01Y83780D02*
Y84961D01*
G01X475728Y93254D02*
Y93265D01*
G01Y90105D02*
Y90115D01*
G01Y86955D02*
Y86966D01*
G01Y83806D02*
Y83816D01*
G01X474742Y93263D02*
X474631Y93268D01*
G01X474742Y86965D02*
X474631Y86969D01*
G01X475727Y93268D02*
X469803D01*
G01X475687Y93228D02*
X469803D01*
G01X474744Y93071D02*
X475728D01*
G01X474783Y93031D02*
X475689D01*
G01Y91457D02*
X474783D01*
G01X475728Y91417D02*
X474744D01*
G01X475687Y91260D02*
X469803D01*
G01Y91220D02*
X475727D01*
G01Y90118D02*
X469803D01*
G01X475687Y90079D02*
X469803D01*
G01X474744Y89921D02*
X475728D01*
G01X474783Y89882D02*
X475689D01*
G01Y88307D02*
X474783D01*
G01X475728Y88268D02*
X474744D01*
G01X475687Y88110D02*
X469803D01*
G01Y88071D02*
X475727D01*
G01Y86969D02*
X469803D01*
G01X475687Y86929D02*
X469803D01*
G01X474744Y86772D02*
X475728D01*
G01X474783Y86732D02*
X475689D01*
G01Y85157D02*
X474783D01*
G01X475728Y85118D02*
X474744D01*
G01X475687Y84961D02*
X469803D01*
G01Y84921D02*
X475727D01*
G01Y83819D02*
X469803D01*
G01X475687Y83780D02*
X469803D01*
G01X474744Y83622D02*
X475728D01*
G01X474783Y83583D02*
X475689D01*
G01X476181Y81614D02*
X472835D01*
G01X484646Y47500D02*
X479134D01*
G01X485827Y46319D02*
X477953D01*
G01X491142Y44823D02*
X476181D01*
G01X479921Y43957D02*
X476181D01*
G01Y42579D02*
X490551D01*
G01X482480Y40610D02*
X481177Y42579D01*
G01X486220Y34232D02*
X481102D01*
G01X494488Y34193D02*
X472835D01*
G01X487598Y31240D02*
X479724D01*
G01Y29665D02*
X487598D01*
G01X487008Y24547D02*
X480315D01*
G01X492520Y23760D02*
X474803D01*
G01X475697Y94408D02*
X475687Y94409D01*
G01X475706Y94405D02*
X475697Y94408D01*
G01X475713Y94400D02*
X475706Y94405D01*
G01X475697Y97558D02*
X475687Y97559D01*
G01X475706Y97555D02*
X475697Y97558D01*
G01X475713Y97549D02*
X475706Y97555D01*
G01X475697Y100707D02*
X475687Y100709D01*
G01X475706Y100704D02*
X475697Y100707D01*
G01X475713Y100699D02*
X475706Y100704D01*
G01X475697Y103857D02*
X475687Y103858D01*
G01X475706Y103854D02*
X475697Y103857D01*
G01X475713Y103848D02*
X475706Y103854D01*
G01X474783Y96373D02*
Y96367D01*
G01X474782Y96377D02*
X474783Y96373D01*
G01X474781Y96378D02*
X474782Y96377D01*
G01X474783Y99522D02*
Y99516D01*
G01X474782Y99526D02*
X474783Y99522D01*
G01X474781Y99528D02*
X474782Y99526D01*
G01X474783Y102672D02*
Y102666D01*
G01X474782Y102676D02*
X474783Y102672D01*
G01X474781Y102677D02*
X474782Y102676D01*
G01X475698Y94408D02*
X475707Y94404D01*
G01X475687Y94409D02*
X475698Y94408D01*
G01X474744Y96407D02*
Y96404D01*
G01X474746Y96401D02*
X474744Y96407D01*
G01X474757Y96386D02*
X474746Y96401D01*
G01X474781Y96378D02*
X474757Y96386D01*
G01X474744Y99557D02*
Y99553D01*
G01X474746Y99551D02*
X474744Y99557D01*
G01X474757Y99536D02*
X474746Y99551D01*
G01X474781Y99528D02*
X474757Y99536D01*
G01X474744Y102707D02*
Y102703D01*
G01X474746Y102701D02*
X474744Y102707D01*
G01X474757Y102685D02*
X474746Y102701D01*
G01X474781Y102677D02*
X474757Y102685D01*
G01X474767Y96380D02*
X474781Y96378D01*
G01X474755Y96388D02*
X474767Y96380D01*
G01X474743Y96406D02*
X474755Y96388D01*
G01X474767Y99530D02*
X474781Y99528D01*
G01X474754Y99538D02*
X474767Y99530D01*
G01X474743Y99558D02*
X474754Y99538D01*
G01X475728Y96411D02*
Y96404D01*
G01Y96416D02*
Y96411D01*
G01X475727Y96417D02*
X475728Y96416D01*
G01Y99561D02*
Y99553D01*
G01Y99565D02*
Y99561D01*
G01X475727Y99567D02*
X475728Y99565D01*
G01Y102711D02*
Y102703D01*
G01Y102715D02*
Y102711D01*
G01X475727Y102717D02*
X475728Y102715D01*
G01X474767Y102680D02*
X474781Y102677D01*
G01X474754Y102688D02*
X474767Y102680D01*
G01X474743Y102708D02*
X474754Y102688D01*
G01X475728Y94390D02*
Y94383D01*
G01X475726Y94396D02*
X475728Y94390D01*
G01X475723Y94402D02*
X475726Y94396D01*
G01X475728Y97540D02*
Y97533D01*
G01X475726Y97546D02*
X475728Y97540D01*
G01X475723Y97552D02*
X475726Y97546D01*
G01X475728Y100689D02*
Y100683D01*
G01X475726Y100696D02*
X475728Y100689D01*
G01X475723Y100702D02*
X475726Y100696D01*
G01X475728Y103839D02*
Y103832D01*
G01X475726Y103845D02*
X475728Y103839D01*
G01X475723Y103851D02*
X475726Y103845D01*
G01X474767Y94417D02*
X474763Y94415D01*
G01X474770Y94418D02*
X474767Y94417D01*
G01X474773Y94419D02*
X474770Y94418D01*
G01X474776Y94420D02*
X474773Y94419D01*
G01X474780Y94420D02*
X474776D01*
G01X474783D02*
X474780D01*
G01X475706Y96370D02*
X475709Y96372D01*
G01X475703Y96369D02*
X475706Y96370D01*
G01X475700Y96368D02*
X475703Y96369D01*
G01X475696Y96367D02*
X475700Y96368D01*
G01X475693Y96367D02*
X475696D01*
G01X475689D02*
X475693D01*
G01X473997Y96417D02*
X473563D01*
G01X474370D02*
X473997D01*
G01X475719Y94408D02*
X475723Y94402D01*
G01X475714Y94412D02*
X475719Y94408D01*
G01X475708Y94416D02*
X475714Y94412D01*
G01X475702Y94419D02*
X475708Y94416D01*
G01X475696Y94420D02*
X475702Y94419D01*
G01X475689Y94420D02*
X475696D01*
G01X475719Y97557D02*
X475723Y97552D01*
G01X475714Y97562D02*
X475719Y97557D01*
G01X475708Y97565D02*
X475714Y97562D01*
G01X475702Y97568D02*
X475708Y97565D01*
G01X475696Y97570D02*
X475702Y97568D01*
G01X475689Y97570D02*
X475696D01*
G01X475719Y100707D02*
X475723Y100702D01*
G01X475714Y100711D02*
X475719Y100707D01*
G01X475708Y100715D02*
X475714Y100711D01*
G01X475702Y100718D02*
X475708Y100715D01*
G01X475696Y100719D02*
X475702Y100718D01*
G01X475689Y100720D02*
X475696Y100719D01*
G01X475719Y103857D02*
X475723Y103851D01*
G01X475714Y103861D02*
X475719Y103857D01*
G01X475708Y103865D02*
X475714Y103861D01*
G01X475702Y103867D02*
X475708Y103865D01*
G01X475696Y103869D02*
X475702Y103867D01*
G01X475689Y103869D02*
X475696D01*
G01X474745Y96396D02*
X474744Y96404D01*
G01X474747Y96389D02*
X474745Y96396D01*
G01X474751Y96383D02*
X474747Y96389D01*
G01X474756Y96378D02*
X474751Y96383D01*
G01X474762Y96373D02*
X474756Y96378D01*
G01X474769Y96369D02*
X474762Y96373D01*
G01X474776Y96367D02*
X474769Y96369D01*
G01X474783Y96367D02*
X474776D01*
G01X474745Y99546D02*
X474744Y99553D01*
G01X474747Y99539D02*
X474745Y99546D01*
G01X474751Y99533D02*
X474747Y99539D01*
G01X474756Y99527D02*
X474751Y99533D01*
G01X474762Y99522D02*
X474756Y99527D01*
G01X474769Y99519D02*
X474762Y99522D01*
G01X474776Y99517D02*
X474769Y99519D01*
G01X474783Y99516D02*
X474776Y99517D01*
G01X474745Y102696D02*
X474744Y102703D01*
G01X474747Y102689D02*
X474745Y102696D01*
G01X474751Y102682D02*
X474747Y102689D01*
G01X474756Y102677D02*
X474751Y102682D01*
G01X474762Y102672D02*
X474756Y102677D01*
G01X474769Y102669D02*
X474762Y102672D01*
G01X474776Y102667D02*
X474769Y102669D01*
G01X474783Y102666D02*
X474776Y102667D01*
G01X475698Y97557D02*
X475707Y97554D01*
G01X475687Y97559D02*
X475698Y97557D01*
G01Y100707D02*
X475707Y100703D01*
G01X475687Y100709D02*
X475698Y100707D01*
G01Y103857D02*
X475707Y103853D01*
G01X475687Y103858D02*
X475698Y103857D01*
G01X475689Y96373D02*
X475690Y96367D01*
G01X475688Y96376D02*
X475689Y96373D01*
G01X475687Y96378D02*
X475688Y96376D01*
G01X475689Y102672D02*
X475690Y102666D01*
G01X475688Y102676D02*
X475689Y102672D01*
G01X475687Y102677D02*
X475688Y102676D01*
G01X475728Y99546D02*
Y99553D01*
G01X475725Y99539D02*
X475728Y99546D01*
G01X475722Y99533D02*
X475725Y99539D01*
G01X475717Y99527D02*
X475722Y99533D01*
G01X475711Y99522D02*
X475717Y99527D01*
G01X475704Y99519D02*
X475711Y99522D01*
G01X475697Y99517D02*
X475704Y99519D01*
G01X475689Y99516D02*
X475697Y99517D01*
G01X474767Y97567D02*
X474763Y97565D01*
G01X474770Y97568D02*
X474767Y97567D01*
G01X474773Y97569D02*
X474770Y97568D01*
G01X474776Y97570D02*
X474773Y97569D01*
G01X474780Y97570D02*
X474776D01*
G01X474783D02*
X474780D01*
G01X474767Y100716D02*
X474763Y100715D01*
G01X474770Y100717D02*
X474767Y100716D01*
G01X474773Y100719D02*
X474770Y100717D01*
G01X474776Y100719D02*
X474773D01*
G01X474780Y100720D02*
X474776Y100719D01*
G01X474783Y100720D02*
X474780D01*
G01X475706Y102669D02*
X475709Y102671D01*
G01X475703Y102668D02*
X475706Y102669D01*
G01X475700Y102667D02*
X475703Y102668D01*
G01X475696Y102667D02*
X475700D01*
G01X475693Y102666D02*
X475696Y102667D01*
G01X475689Y102666D02*
X475693D01*
G01X474767Y103866D02*
X474763Y103864D01*
G01X474770Y103867D02*
X474767Y103866D01*
G01X474773Y103868D02*
X474770Y103867D01*
G01X474776Y103869D02*
X474773Y103868D01*
G01X474780Y103869D02*
X474776D01*
G01X474783D02*
X474780D01*
G01X475721Y94391D02*
X475713Y94400D01*
G01X475726Y94381D02*
X475721Y94391D01*
G01X475727Y94370D02*
X475726Y94381D01*
G01X475721Y97541D02*
X475713Y97549D01*
G01X475726Y97531D02*
X475721Y97541D01*
G01X475727Y97520D02*
X475726Y97531D01*
G01X475721Y100691D02*
X475713Y100699D01*
G01X475726Y100680D02*
X475721Y100691D01*
G01X475727Y100669D02*
X475726Y100680D01*
G01X475721Y103840D02*
X475713Y103848D01*
G01X475726Y103830D02*
X475721Y103840D01*
G01X475727Y103819D02*
X475726Y103830D01*
G01X474744Y96411D02*
Y96404D01*
G01X474743Y96416D02*
X474744Y96411D01*
G01X474743Y96406D02*
Y96416D01*
G01X474784Y104043D02*
X474783Y104055D01*
G01X474781Y104030D02*
X474784Y104043D01*
G01X474781Y104016D02*
Y104030D01*
G01X474784Y100893D02*
X474783Y100906D01*
G01X474781Y100880D02*
X474784Y100893D01*
G01X474781Y100866D02*
Y100880D01*
G01X474784Y97743D02*
X474783Y97756D01*
G01X474781Y97730D02*
X474784Y97743D01*
G01X474781Y97717D02*
Y97730D01*
G01X474784Y94594D02*
X474783Y94606D01*
G01X474781Y94581D02*
X474784Y94594D01*
G01X474781Y94567D02*
Y94581D01*
G01X474747Y94390D02*
X474742Y94370D01*
G01X474761Y94404D02*
X474747Y94390D01*
G01X474781Y94409D02*
X474761Y94404D01*
G01X474747Y97539D02*
X474742Y97520D01*
G01X474761Y97554D02*
X474747Y97539D01*
G01X474781Y97559D02*
X474761Y97554D01*
G01X474747Y100689D02*
X474742Y100669D01*
G01X474761Y100703D02*
X474747Y100689D01*
G01X474781Y100709D02*
X474761Y100703D01*
G01X474747Y103839D02*
X474742Y103819D01*
G01X474761Y103853D02*
X474747Y103839D01*
G01X474781Y103858D02*
X474761Y103853D01*
G01X475722Y96398D02*
X475727Y96417D01*
G01X475707Y96383D02*
X475722Y96398D01*
G01X475687Y96378D02*
X475707Y96383D01*
G01X475722Y99547D02*
X475727Y99567D01*
G01X475707Y99533D02*
X475722Y99547D01*
G01X475687Y99528D02*
X475707Y99533D01*
G01X475722Y102697D02*
X475727Y102717D01*
G01X475707Y102682D02*
X475722Y102697D01*
G01X475687Y102677D02*
X475707Y102682D01*
G01X474744Y102711D02*
Y102703D01*
G01X474743Y102715D02*
X474744Y102711D01*
G01X474743Y102707D02*
Y102715D01*
G01X474781Y102506D02*
X474780Y102519D01*
G01X474784Y102493D02*
X474781Y102506D01*
G01X474783Y102480D02*
X474784Y102493D01*
G01X474781Y99356D02*
X474780Y99370D01*
G01X474784Y99343D02*
X474781Y99356D01*
G01X474783Y99331D02*
X474784Y99343D01*
G01X474781Y96206D02*
X474780Y96220D01*
G01X474784Y96194D02*
X474781Y96206D01*
G01X474783Y96181D02*
X474784Y96194D01*
G01X475691Y104030D02*
X475693Y104016D01*
G01X475688Y104043D02*
X475691Y104030D01*
G01X475689Y104055D02*
X475688Y104043D01*
G01X475691Y100880D02*
X475693Y100866D01*
G01X475688Y100893D02*
X475691Y100880D01*
G01X475689Y100906D02*
X475688Y100893D01*
G01X475691Y97730D02*
X475693Y97717D01*
G01X475688Y97743D02*
X475691Y97730D01*
G01X475689Y97756D02*
X475688Y97743D01*
G01X475691Y94581D02*
X475693Y94567D01*
G01X475688Y94594D02*
X475691Y94581D01*
G01X475689Y94606D02*
X475688Y94594D01*
G01X474744Y99561D02*
Y99554D01*
G01X474743Y99565D02*
X474744Y99561D01*
G01X474743Y99558D02*
Y99565D01*
G01X475688Y102493D02*
X475689Y102480D01*
G01X475691Y102506D02*
X475688Y102493D01*
G01X475692Y102519D02*
X475691Y102506D01*
G01X475688Y99343D02*
X475689Y99331D01*
G01X475691Y99356D02*
X475688Y99343D01*
G01X475692Y99370D02*
X475691Y99356D01*
G01X475688Y96194D02*
X475689Y96181D01*
G01X475691Y96206D02*
X475688Y96194D01*
G01X475692Y96220D02*
X475691Y96206D01*
G01X474757Y103850D02*
X474781Y103858D01*
G01X474746Y103835D02*
X474757Y103850D01*
G01X474744Y103828D02*
X474746Y103835D01*
G01X474757Y100700D02*
X474781Y100709D01*
G01X474746Y100685D02*
X474757Y100700D01*
G01X474744Y100679D02*
X474746Y100685D01*
G01X474757Y97550D02*
X474781Y97559D01*
G01X474746Y97536D02*
X474757Y97550D01*
G01X474744Y97529D02*
X474746Y97536D01*
G01X474757Y94401D02*
X474781Y94409D01*
G01X474746Y94386D02*
X474757Y94401D01*
G01X474744Y94380D02*
X474746Y94386D01*
G01X475728Y103825D02*
Y103832D01*
G01Y103820D02*
Y103825D01*
G01X475727Y103819D02*
X475728Y103820D01*
G01Y100676D02*
Y100683D01*
G01Y100671D02*
Y100676D01*
G01X475727Y100669D02*
X475728Y100671D01*
G01Y97526D02*
Y97533D01*
G01Y97521D02*
Y97526D01*
G01X475727Y97520D02*
X475728Y97521D01*
G01Y94376D02*
Y94383D01*
G01Y94372D02*
Y94376D01*
G01X475727Y94370D02*
X475728Y94372D01*
G01X475689Y103863D02*
Y103869D01*
G01X475688Y103859D02*
X475689Y103863D01*
G01X475687Y103858D02*
X475688Y103859D01*
G01X475689Y100714D02*
Y100720D01*
G01X475688Y100710D02*
X475689Y100714D01*
G01X475687Y100709D02*
X475688Y100710D01*
G01X475689Y97564D02*
Y97570D01*
G01X475688Y97560D02*
X475689Y97564D01*
G01X475687Y97559D02*
X475688Y97560D01*
G01X475689Y94415D02*
Y94420D01*
G01X475688Y94411D02*
X475689Y94415D01*
G01X475687Y94409D02*
X475688Y94411D01*
G01X474744Y103825D02*
Y103832D01*
G01X474743Y103820D02*
X474744Y103825D01*
G01X474742Y103819D02*
X474743Y103820D01*
G01X474744Y100675D02*
Y100683D01*
G01X474743Y100671D02*
X474744Y100675D01*
G01X474742Y100669D02*
X474743Y100671D01*
G01X474744Y97526D02*
Y97533D01*
G01X474743Y97521D02*
X474744Y97526D01*
G01X474742Y97520D02*
X474743Y97521D01*
G01X474744Y94376D02*
Y94383D01*
G01X474743Y94372D02*
X474744Y94376D01*
G01X474742Y94370D02*
X474743Y94372D01*
G01X475726Y102691D02*
X475728Y102703D01*
G01X475719Y102679D02*
X475726Y102691D01*
G01X475709Y102671D02*
X475719Y102679D01*
G01X475726Y96391D02*
X475728Y96404D01*
G01X475719Y96380D02*
X475726Y96391D01*
G01X475709Y96372D02*
X475719Y96380D01*
G01X474783Y103863D02*
Y103869D01*
G01Y103859D02*
Y103863D01*
G01X474781Y103858D02*
X474783Y103859D01*
G01Y100713D02*
Y100720D01*
G01Y100710D02*
Y100713D01*
G01X474781Y100709D02*
X474783Y100710D01*
G01Y97564D02*
Y97570D01*
G01Y97560D02*
Y97564D01*
G01X474781Y97559D02*
X474783Y97560D01*
G01Y94414D02*
Y94420D01*
G01Y94411D02*
Y94414D01*
G01X474781Y94409D02*
X474783Y94411D01*
G01X474745Y103839D02*
X474744Y103832D01*
G01X474746Y103845D02*
X474745Y103839D01*
G01X474749Y103851D02*
X474746Y103845D01*
G01X474753Y103856D02*
X474749Y103851D01*
G01X474758Y103861D02*
X474753Y103856D01*
G01X474763Y103864D02*
X474758Y103861D01*
G01X474745Y100689D02*
X474744Y100683D01*
G01X474746Y100695D02*
X474745Y100689D01*
G01X474749Y100701D02*
X474746Y100695D01*
G01X474753Y100706D02*
X474749Y100701D01*
G01X474758Y100711D02*
X474753Y100706D01*
G01X474763Y100715D02*
X474758Y100711D01*
G01X474745Y97539D02*
X474744Y97533D01*
G01X474746Y97546D02*
X474745Y97539D01*
G01X474749Y97552D02*
X474746Y97546D01*
G01X474753Y97557D02*
X474749Y97552D01*
G01X474758Y97561D02*
X474753Y97557D01*
G01X474763Y97565D02*
X474758Y97561D01*
G01X474745Y94390D02*
X474744Y94383D01*
G01X474746Y94396D02*
X474745Y94390D01*
G01X474749Y94402D02*
X474746Y94396D01*
G01X474753Y94407D02*
X474749Y94402D01*
G01X474758Y94412D02*
X474753Y94407D01*
G01X474763Y94415D02*
X474758Y94412D01*
G01X475700Y102679D02*
X475687Y102677D01*
G01X475710Y102684D02*
X475700Y102679D01*
G01Y99530D02*
X475687Y99528D01*
G01X475710Y99534D02*
X475700Y99530D01*
G01Y96380D02*
X475687Y96378D01*
G01X475710Y96385D02*
X475700Y96380D01*
G01X428642Y94488D02*
G03X414665I-6989J0D01*
G01X481177Y185059D02*
X482480Y187028D01*
G01X475728Y94372D02*
Y94383D01*
G01Y97522D02*
Y97533D01*
G01Y100671D02*
Y100683D01*
G01Y103821D02*
Y103832D01*
G01X479921Y183681D02*
Y192224D01*
G01X476181Y185059D02*
Y106024D01*
G01X475728Y102519D02*
Y104016D01*
G01Y99370D02*
Y100866D01*
G01Y96220D02*
Y97717D01*
G01X475689Y96367D02*
Y96220D01*
G01Y94567D02*
Y94420D01*
G01Y99516D02*
Y99369D01*
G01Y100867D02*
Y100720D01*
G01Y97717D02*
Y97570D01*
G01Y102666D02*
Y102519D01*
G01Y104016D02*
Y103869D01*
G01X474783Y102519D02*
Y102666D01*
G01Y103869D02*
Y104016D01*
G01Y99369D02*
Y99516D01*
G01Y100720D02*
Y100867D01*
G01Y97570D02*
Y97717D01*
G01Y96220D02*
Y96367D01*
G01Y94420D02*
Y94567D01*
G01X474744Y100866D02*
Y99370D01*
G01Y97717D02*
Y96220D01*
G01Y104016D02*
Y102520D01*
G01X473563Y97559D02*
Y96378D01*
G01Y100709D02*
Y99528D01*
G01Y103858D02*
Y102677D01*
G01X472835Y201909D02*
Y186161D01*
G01X469803Y102677D02*
Y103858D01*
G01Y99528D02*
Y100709D01*
G01Y96378D02*
Y97559D01*
G01X475728Y102703D02*
Y102714D01*
G01Y99554D02*
Y99564D01*
G01Y96404D02*
Y96415D01*
G01X476181Y185059D02*
X490551D01*
G01X476181Y183681D02*
X479921D01*
G01X476181Y182815D02*
X491142D01*
G01X477953Y181319D02*
X485827D01*
G01X479134Y180138D02*
X484646D01*
G01X475687Y99528D02*
X475691Y99516D01*
G01X474631Y102717D02*
X474743Y102708D01*
G01X474742Y96414D02*
X474631Y96417D01*
G01X476181Y106024D02*
X472835D01*
G01X475689Y104055D02*
X474783D01*
G01X475728Y104016D02*
X474744D01*
G01X475687Y103858D02*
X469803D01*
G01Y103819D02*
X475727D01*
G01Y102717D02*
X469803D01*
G01X475687Y102677D02*
X469803D01*
G01X474744Y102520D02*
X475728D01*
G01X474783Y102480D02*
X475689D01*
G01Y100906D02*
X474783D01*
G01X475728Y100866D02*
X474744D01*
G01X475687Y100709D02*
X469803D01*
G01Y100669D02*
X475727D01*
G01Y99567D02*
X469803D01*
G01X475687Y99528D02*
X469803D01*
G01X474744Y99370D02*
X475728D01*
G01X474783Y99331D02*
X475689D01*
G01Y97756D02*
X474783D01*
G01X475728Y97717D02*
X474744D01*
G01X475687Y97559D02*
X469803D01*
G01Y97520D02*
X475727D01*
G01Y96417D02*
X469803D01*
G01X475687Y96378D02*
X469803D01*
G01X474744Y96220D02*
X475728D01*
G01X474783Y96181D02*
X475689D01*
G01Y94606D02*
X474783D01*
G01X475728Y94567D02*
X474744D01*
G01X475687Y94409D02*
X469803D01*
G01Y94370D02*
X475727D01*
G01X477953Y181319D02*
X479134Y180138D01*
G01X472835Y186161D02*
X476181Y182815D01*
G01X389213Y277843D02*
G03X396138Y264712I37662J11471D01*
G01X443701Y260630D02*
G03X444882I591J0D01*
G01Y254331D02*
G03X443701I-590J0D01*
G01X441732D02*
G03X440551I-591J0D01*
G01Y260630D02*
G03X441732I590J0D01*
G01X443701D02*
G03X444882I591J0D01*
G01Y254331D02*
G03X443701I-590J0D01*
G01X441732D02*
G03X440551I-591J0D01*
G01Y260630D02*
G03X441732I590J0D01*
G01X389213Y277843D02*
G03X396138Y264712I37662J11470D01*
G01X480315Y203091D02*
G03X479724Y202500I0J-591D01*
G01X481102Y193406D02*
G03X479921Y192224I0J-1181D01*
G01X474803Y203878D02*
G03X472835Y201909I0J-1968D01*
G01X443701Y260630D02*
X441732D01*
G01X440551D02*
X439764D01*
G01X443701D02*
X441732D01*
G01X440551D02*
X439764D01*
G01X445669D02*
X444882D01*
G01X445669D02*
X444882D01*
G01X445669Y259646D02*
X439764D01*
G01Y259449D02*
X445669D01*
G01X439764Y255512D02*
X445669D01*
G01Y255315D02*
X439764D01*
G01X444882Y254331D02*
X445669D01*
G01X444882D02*
X445669D01*
G01X441732D02*
X443701D01*
G01X439764D02*
X440551D01*
G01X441732D02*
X443701D01*
G01X439764D02*
X440551D01*
G01X492520Y203878D02*
X474803D01*
G01X487008Y203091D02*
X480315D01*
G01X479724Y196398D02*
Y202500D01*
G01X445669Y254331D02*
Y260630D01*
G01Y254331D02*
Y260630D01*
G01X439764Y254331D02*
Y260630D01*
G01D02*
Y254331D01*
G01X487598Y197972D02*
X479724D01*
G01Y196398D02*
X487598D01*
G01X494488Y193445D02*
X472835D01*
G01X481102Y193406D02*
X486220D01*
G01X482480Y188720D02*
X480170Y192950D01*
G01X474744Y549167D02*
Y549160D01*
G01X474743Y549172D02*
X474744Y549167D01*
G01X474743Y549162D02*
Y549172D01*
G01X474784Y556798D02*
X474783Y556811D01*
G01X474781Y556785D02*
X474784Y556798D01*
G01X474781Y556772D02*
Y556785D01*
G01X474784Y553649D02*
X474783Y553661D01*
G01X474781Y553636D02*
X474784Y553649D01*
G01X474781Y553622D02*
Y553636D01*
G01X474784Y550499D02*
X474783Y550512D01*
G01X474781Y550486D02*
X474784Y550499D01*
G01X474781Y550472D02*
Y550486D01*
G01X474784Y547350D02*
X474783Y547362D01*
G01X474781Y547337D02*
X474784Y547350D01*
G01X474781Y547323D02*
Y547337D01*
G01X474784Y544200D02*
X474783Y544213D01*
G01X474781Y544187D02*
X474784Y544200D01*
G01X474781Y544173D02*
Y544187D01*
G01X474784Y541050D02*
X474783Y541063D01*
G01X474781Y541037D02*
X474784Y541050D01*
G01X474781Y541024D02*
Y541037D01*
G01X474784Y537901D02*
X474783Y537913D01*
G01X474781Y537888D02*
X474784Y537901D01*
G01X474781Y537874D02*
Y537888D01*
G01X474744Y555467D02*
Y555459D01*
G01X474743Y555471D02*
X474744Y555467D01*
G01X474743Y555463D02*
Y555471D01*
G01X474783Y536530D02*
Y536524D01*
G01X474782Y536534D02*
X474783Y536530D01*
G01X474781Y536535D02*
X474782Y536534D01*
G01X474783Y539680D02*
Y539674D01*
G01X474782Y539684D02*
X474783Y539680D01*
G01X474781Y539685D02*
X474782Y539684D01*
G01X474783Y542830D02*
Y542823D01*
G01X474782Y542833D02*
X474783Y542830D01*
G01X474781Y542835D02*
X474782Y542833D01*
G01X474783Y545979D02*
Y545973D01*
G01X474782Y545983D02*
X474783Y545979D01*
G01X474781Y545984D02*
X474782Y545983D01*
G01X474783Y549129D02*
Y549122D01*
G01X474782Y549133D02*
X474783Y549129D01*
G01X474781Y549134D02*
X474782Y549133D01*
G01X474783Y552278D02*
Y552272D01*
G01X474782Y552282D02*
X474783Y552278D01*
G01X474781Y552283D02*
X474782Y552282D01*
G01X474767Y539687D02*
X474781Y539685D01*
G01X474756Y539694D02*
X474767Y539687D01*
G01X474743Y539713D02*
X474756Y539694D01*
G01X474767Y549136D02*
X474781Y549134D01*
G01X474755Y549144D02*
X474767Y549136D01*
G01X474743Y549162D02*
X474755Y549144D01*
G01X474767Y542837D02*
X474781Y542835D01*
G01X474754Y542845D02*
X474767Y542837D01*
G01X474743Y542865D02*
X474754Y542845D01*
G01X474767Y552286D02*
X474781Y552283D01*
G01X474754Y552294D02*
X474767Y552286D01*
G01X474743Y552314D02*
X474754Y552294D01*
G01X475728Y536569D02*
Y536561D01*
G01Y536573D02*
Y536569D01*
G01X475727Y536575D02*
X475728Y536573D01*
G01Y539719D02*
Y539711D01*
G01Y539723D02*
Y539719D01*
G01X475727Y539724D02*
X475728Y539723D01*
G01Y542868D02*
Y542860D01*
G01Y542872D02*
Y542868D01*
G01X475727Y542874D02*
X475728Y542872D01*
G01Y546018D02*
Y546010D01*
G01Y546022D02*
Y546018D01*
G01X475727Y546024D02*
X475728Y546022D01*
G01Y549167D02*
Y549159D01*
G01Y549172D02*
Y549167D01*
G01X475727Y549173D02*
X475728Y549172D01*
G01Y552317D02*
Y552309D01*
G01Y552321D02*
Y552317D01*
G01X475727Y552323D02*
X475728Y552321D01*
G01Y555467D02*
Y555459D01*
G01Y555471D02*
Y555467D01*
G01X475727Y555472D02*
X475728Y555471D01*
G01X474767Y555436D02*
X474781Y555433D01*
G01X474754Y555444D02*
X474767Y555436D01*
G01X474743Y555464D02*
X474754Y555444D01*
G01X474766Y536538D02*
X474781Y536535D01*
G01X474753Y536547D02*
X474766Y536538D01*
G01X474743Y536567D02*
X474753Y536547D01*
G01X475728Y537697D02*
Y537691D01*
G01X475726Y537704D02*
X475728Y537697D01*
G01X475723Y537709D02*
X475726Y537704D01*
G01X475728Y540847D02*
Y540840D01*
G01X475726Y540853D02*
X475728Y540847D01*
G01X475723Y540859D02*
X475726Y540853D01*
G01X475728Y543996D02*
Y543990D01*
G01X475726Y544003D02*
X475728Y543996D01*
G01X475723Y544009D02*
X475726Y544003D01*
G01X475728Y547146D02*
Y547139D01*
G01X475726Y547152D02*
X475728Y547146D01*
G01X475723Y547158D02*
X475726Y547152D01*
G01X475728Y550296D02*
Y550289D01*
G01X475726Y550302D02*
X475728Y550296D01*
G01X475723Y550308D02*
X475726Y550302D01*
G01X475728Y553445D02*
Y553439D01*
G01X475726Y553452D02*
X475728Y553445D01*
G01X475723Y553457D02*
X475726Y553452D01*
G01X475728Y556595D02*
Y556588D01*
G01X475726Y556601D02*
X475728Y556595D01*
G01X475723Y556607D02*
X475726Y556601D01*
G01X475689Y536530D02*
X475690Y536524D01*
G01X475688Y536534D02*
X475689Y536530D01*
G01X475687Y536535D02*
X475688Y536534D01*
G01X475689Y539680D02*
X475690Y539674D01*
G01X475688Y539683D02*
X475689Y539680D01*
G01X475687Y539685D02*
X475688Y539683D01*
G01X475689Y542830D02*
X475690Y542823D01*
G01X475688Y542833D02*
X475689Y542830D01*
G01X475687Y542835D02*
X475688Y542833D01*
G01X475689Y545979D02*
X475690Y545973D01*
G01X475688Y545983D02*
X475689Y545979D01*
G01X475687Y545984D02*
X475688Y545983D01*
G01X475689Y549129D02*
X475690Y549122D01*
G01X475688Y549132D02*
X475689Y549129D01*
G01X475687Y549134D02*
X475688Y549132D01*
G01X475689Y555428D02*
X475690Y555422D01*
G01X475688Y555431D02*
X475689Y555428D01*
G01X475687Y555433D02*
X475688Y555431D01*
G01X474762Y545989D02*
X474781Y545984D01*
G01X474748Y546002D02*
X474762Y545989D01*
G01X474742Y546019D02*
X474748Y546002D01*
G01X475721Y543998D02*
X475713Y544006D01*
G01X475726Y543987D02*
X475721Y543998D01*
G01X475727Y543976D02*
X475726Y543987D01*
G01X475721Y537698D02*
X475713Y537707D01*
G01X475726Y537688D02*
X475721Y537698D01*
G01X475727Y537677D02*
X475726Y537688D01*
G01X475721Y540848D02*
X475713Y540856D01*
G01X475726Y540838D02*
X475721Y540848D01*
G01X475727Y540827D02*
X475726Y540838D01*
G01X475721Y547147D02*
X475713Y547156D01*
G01X475726Y547137D02*
X475721Y547147D01*
G01X475727Y547126D02*
X475726Y547137D01*
G01X475721Y550297D02*
X475713Y550305D01*
G01X475726Y550287D02*
X475721Y550297D01*
G01X475727Y550276D02*
X475726Y550287D01*
G01X475721Y553446D02*
X475713Y553455D01*
G01X475726Y553436D02*
X475721Y553446D01*
G01X475727Y553425D02*
X475726Y553436D01*
G01X475721Y556596D02*
X475713Y556604D01*
G01X475726Y556586D02*
X475721Y556596D01*
G01X475727Y556575D02*
X475726Y556586D01*
G01X474781Y555261D02*
X474780Y555275D01*
G01X474784Y555249D02*
X474781Y555261D01*
G01X474783Y555236D02*
X474784Y555249D01*
G01X474781Y552112D02*
X474780Y552126D01*
G01X474784Y552099D02*
X474781Y552112D01*
G01X474783Y552087D02*
X474784Y552099D01*
G01X474781Y548962D02*
X474780Y548976D01*
G01X474784Y548950D02*
X474781Y548962D01*
G01X474783Y548937D02*
X474784Y548950D01*
G01X474781Y545813D02*
X474780Y545826D01*
G01X474784Y545800D02*
X474781Y545813D01*
G01X474783Y545787D02*
X474784Y545800D01*
G01X474781Y542663D02*
X474780Y542677D01*
G01X474784Y542650D02*
X474781Y542663D01*
G01X474783Y542638D02*
X474784Y542650D01*
G01X474781Y539513D02*
X474780Y539527D01*
G01X474784Y539501D02*
X474781Y539513D01*
G01X474783Y539488D02*
X474784Y539501D01*
G01X474781Y536364D02*
X474780Y536378D01*
G01X474784Y536351D02*
X474781Y536364D01*
G01X474783Y536339D02*
X474784Y536351D01*
G01X475691Y556785D02*
X475693Y556772D01*
G01X475688Y556798D02*
X475691Y556785D01*
G01X475689Y556811D02*
X475688Y556798D01*
G01X475691Y553636D02*
X475693Y553622D01*
G01X475688Y553649D02*
X475691Y553636D01*
G01X475689Y553661D02*
X475688Y553649D01*
G01X475691Y550486D02*
X475693Y550472D01*
G01X475688Y550499D02*
X475691Y550486D01*
G01X475689Y550512D02*
X475688Y550499D01*
G01X475691Y547337D02*
X475693Y547323D01*
G01X475688Y547350D02*
X475691Y547337D01*
G01X475689Y547362D02*
X475688Y547350D01*
G01X475691Y544187D02*
X475693Y544173D01*
G01X475688Y544200D02*
X475691Y544187D01*
G01X475689Y544213D02*
X475688Y544200D01*
G01X475691Y541037D02*
X475693Y541024D01*
G01X475688Y541050D02*
X475691Y541037D01*
G01X475689Y541063D02*
X475688Y541050D01*
G01X475691Y537888D02*
X475693Y537874D01*
G01X475688Y537901D02*
X475691Y537888D01*
G01X475689Y537913D02*
X475688Y537901D01*
G01X474744Y542868D02*
Y542861D01*
G01X474743Y542872D02*
X474744Y542868D01*
G01X474743Y542865D02*
Y542872D01*
G01X474744Y552317D02*
Y552309D01*
G01X474743Y552321D02*
X474744Y552317D01*
G01X474743Y552314D02*
Y552321D01*
G01X475688Y555249D02*
X475689Y555236D01*
G01X475691Y555261D02*
X475688Y555249D01*
G01X475692Y555275D02*
X475691Y555261D01*
G01X475688Y552099D02*
X475689Y552087D01*
G01X475691Y552112D02*
X475688Y552099D01*
G01X475692Y552126D02*
X475691Y552112D01*
G01X475688Y548950D02*
X475689Y548937D01*
G01X475691Y548962D02*
X475688Y548950D01*
G01X475692Y548976D02*
X475691Y548962D01*
G01X475688Y545800D02*
X475689Y545787D01*
G01X475691Y545813D02*
X475688Y545800D01*
G01X475692Y545826D02*
X475691Y545813D01*
G01X475688Y542650D02*
X475689Y542638D01*
G01X475691Y542663D02*
X475688Y542650D01*
G01X475692Y542677D02*
X475691Y542663D01*
G01X475688Y539501D02*
X475689Y539488D01*
G01X475691Y539513D02*
X475688Y539501D01*
G01X475692Y539527D02*
X475691Y539513D01*
G01X475688Y536351D02*
X475689Y536339D01*
G01X475691Y536364D02*
X475688Y536351D01*
G01X475692Y536378D02*
X475691Y536364D01*
G01X474744Y536569D02*
Y536561D01*
G01X474743Y536573D02*
X474744Y536569D01*
G01X474743Y536567D02*
Y536573D01*
G01X474757Y556606D02*
X474781Y556614D01*
G01X474746Y556591D02*
X474757Y556606D01*
G01X474744Y556584D02*
X474746Y556591D01*
G01X474757Y553456D02*
X474781Y553465D01*
G01X474746Y553441D02*
X474757Y553456D01*
G01X474744Y553435D02*
X474746Y553441D01*
G01X474757Y550306D02*
X474781Y550315D01*
G01X474746Y550292D02*
X474757Y550306D01*
G01X474744Y550285D02*
X474746Y550292D01*
G01X474757Y547157D02*
X474781Y547165D01*
G01X474746Y547142D02*
X474757Y547157D01*
G01X474744Y547135D02*
X474746Y547142D01*
G01X474757Y544007D02*
X474781Y544016D01*
G01X474746Y543993D02*
X474757Y544007D01*
G01X474744Y543986D02*
X474746Y543993D01*
G01X474757Y540857D02*
X474781Y540866D01*
G01X474746Y540843D02*
X474757Y540857D01*
G01X474744Y540836D02*
X474746Y540843D01*
G01X474757Y537708D02*
X474781Y537717D01*
G01X474746Y537693D02*
X474757Y537708D01*
G01X474744Y537687D02*
X474746Y537693D01*
G01X475697Y544015D02*
X475687Y544016D01*
G01X475706Y544011D02*
X475697Y544015D01*
G01X475713Y544006D02*
X475706Y544011D01*
G01X475697Y537715D02*
X475687Y537717D01*
G01X475706Y537712D02*
X475697Y537715D01*
G01X475713Y537707D02*
X475706Y537712D01*
G01X475697Y540865D02*
X475687Y540866D01*
G01X475706Y540862D02*
X475697Y540865D01*
G01X475713Y540856D02*
X475706Y540862D01*
G01X475697Y547164D02*
X475687Y547165D01*
G01X475706Y547161D02*
X475697Y547164D01*
G01X475713Y547156D02*
X475706Y547161D01*
G01X475697Y550314D02*
X475687Y550315D01*
G01X475706Y550311D02*
X475697Y550314D01*
G01X475713Y550305D02*
X475706Y550311D01*
G01X475697Y553463D02*
X475687Y553465D01*
G01X475706Y553460D02*
X475697Y553463D01*
G01X475713Y553455D02*
X475706Y553460D01*
G01X475697Y556613D02*
X475687Y556614D01*
G01X475706Y556610D02*
X475697Y556613D01*
G01X475713Y556604D02*
X475706Y556610D01*
G01X474783Y555428D02*
Y555422D01*
G01X474782Y555432D02*
X474783Y555428D01*
G01X474781Y555433D02*
X474782Y555432D01*
G01X475728Y556581D02*
Y556588D01*
G01Y556576D02*
Y556581D01*
G01X475727Y556575D02*
X475728Y556576D01*
G01Y553431D02*
Y553439D01*
G01Y553427D02*
Y553431D01*
G01X475727Y553425D02*
X475728Y553427D01*
G01Y550282D02*
Y550289D01*
G01Y550277D02*
Y550282D01*
G01X475727Y550276D02*
X475728Y550277D01*
G01Y547132D02*
Y547139D01*
G01Y547128D02*
Y547132D01*
G01X475727Y547126D02*
X475728Y547128D01*
G01Y543983D02*
Y543990D01*
G01Y543978D02*
Y543983D01*
G01X475727Y543976D02*
X475728Y543978D01*
G01Y540833D02*
Y540840D01*
G01Y540828D02*
Y540833D01*
G01X475727Y540827D02*
X475728Y540828D01*
G01Y537683D02*
Y537691D01*
G01Y537679D02*
Y537683D01*
G01X475727Y537677D02*
X475728Y537679D01*
G01X474744Y546018D02*
Y546010D01*
G01X474743Y546022D02*
X474744Y546018D01*
G01X474742Y546019D02*
X474743Y546022D01*
G01X474744Y539715D02*
Y539711D01*
G01X474746Y539708D02*
X474744Y539715D01*
G01X474757Y539693D02*
X474746Y539708D01*
G01X474782Y539685D02*
X474757Y539693D01*
G01X474744Y542864D02*
Y542860D01*
G01X474746Y542858D02*
X474744Y542864D01*
G01X474757Y542843D02*
X474746Y542858D01*
G01X474781Y542835D02*
X474757Y542843D01*
G01X474744Y549163D02*
Y549159D01*
G01X474746Y549157D02*
X474744Y549163D01*
G01X474757Y549142D02*
X474746Y549157D01*
G01X474781Y549134D02*
X474757Y549142D01*
G01X474744Y552313D02*
Y552309D01*
G01X474746Y552307D02*
X474744Y552313D01*
G01X474757Y552292D02*
X474746Y552307D01*
G01X474781Y552283D02*
X474757Y552292D01*
G01X474744Y536565D02*
Y536561D01*
G01X474746Y536559D02*
X474744Y536565D01*
G01X474757Y536544D02*
X474746Y536559D01*
G01X474781Y536535D02*
X474757Y536544D01*
G01X474744Y555463D02*
Y555459D01*
G01X474746Y555457D02*
X474744Y555463D01*
G01X474757Y555441D02*
X474746Y555457D01*
G01X474781Y555433D02*
X474757Y555441D01*
G01X474744Y546014D02*
Y546010D01*
G01X474746Y546008D02*
X474744Y546014D01*
G01X474756Y545994D02*
X474746Y546008D01*
G01X474779Y545984D02*
X474756Y545994D01*
G01X474744Y539719D02*
Y539711D01*
G01X474743Y539723D02*
X474744Y539719D01*
G01X474742Y539721D02*
X474743Y539723D01*
G01X475689Y556619D02*
Y556625D01*
G01X475688Y556615D02*
X475689Y556619D01*
G01X475687Y556614D02*
X475688Y556615D01*
G01X475689Y553470D02*
Y553476D01*
G01X475688Y553466D02*
X475689Y553470D01*
G01X475687Y553465D02*
X475688Y553466D01*
G01X475689Y550320D02*
Y550326D01*
G01X475688Y550316D02*
X475689Y550320D01*
G01X475687Y550315D02*
X475688Y550316D01*
G01X475689Y547170D02*
Y547176D01*
G01X475688Y547167D02*
X475689Y547170D01*
G01X475687Y547165D02*
X475688Y547167D01*
G01X475689Y544021D02*
Y544027D01*
G01X475688Y544017D02*
X475689Y544021D01*
G01X475687Y544016D02*
X475688Y544017D01*
G01X475689Y540871D02*
Y540877D01*
G01X475688Y540867D02*
X475689Y540871D01*
G01X475687Y540866D02*
X475688Y540867D01*
G01X475689Y537722D02*
Y537728D01*
G01X475688Y537718D02*
X475689Y537722D01*
G01X475687Y537717D02*
X475688Y537718D01*
G01X475719Y537715D02*
X475723Y537709D01*
G01X475714Y537719D02*
X475719Y537715D01*
G01X475708Y537723D02*
X475714Y537719D01*
G01X475702Y537726D02*
X475708Y537723D01*
G01X475696Y537727D02*
X475702Y537726D01*
G01X475689Y537728D02*
X475696Y537727D01*
G01X475719Y540865D02*
X475723Y540859D01*
G01X475714Y540869D02*
X475719Y540865D01*
G01X475708Y540872D02*
X475714Y540869D01*
G01X475702Y540875D02*
X475708Y540872D01*
G01X475696Y540877D02*
X475702Y540875D01*
G01X475689Y540877D02*
X475696D01*
G01X475719Y544014D02*
X475723Y544009D01*
G01X475714Y544019D02*
X475719Y544014D01*
G01X475708Y544022D02*
X475714Y544019D01*
G01X475702Y544025D02*
X475708Y544022D01*
G01X475696Y544026D02*
X475702Y544025D01*
G01X475689Y544027D02*
X475696Y544026D01*
G01X475719Y547164D02*
X475723Y547158D01*
G01X475714Y547168D02*
X475719Y547164D01*
G01X475708Y547172D02*
X475714Y547168D01*
G01X475702Y547174D02*
X475708Y547172D01*
G01X475696Y547176D02*
X475702Y547174D01*
G01X475689Y547176D02*
X475696D01*
G01X475719Y550313D02*
X475723Y550308D01*
G01X475714Y550318D02*
X475719Y550313D01*
G01X475708Y550321D02*
X475714Y550318D01*
G01X475702Y550324D02*
X475708Y550321D01*
G01X475696Y550326D02*
X475702Y550324D01*
G01X475689Y550326D02*
X475696D01*
G01X475719Y553463D02*
X475723Y553457D01*
G01X475714Y553467D02*
X475719Y553463D01*
G01X475708Y553471D02*
X475714Y553467D01*
G01X475702Y553474D02*
X475708Y553471D01*
G01X475696Y553475D02*
X475702Y553474D01*
G01X475689Y553476D02*
X475696Y553475D01*
G01X475719Y556613D02*
X475723Y556607D01*
G01X475714Y556617D02*
X475719Y556613D01*
G01X475708Y556620D02*
X475714Y556617D01*
G01X475702Y556623D02*
X475708Y556620D01*
G01X475696Y556625D02*
X475702Y556623D01*
G01X475689Y556625D02*
X475696D01*
G01X474745Y536554D02*
X474744Y536561D01*
G01X474747Y536547D02*
X474745Y536554D01*
G01X474751Y536541D02*
X474747Y536547D01*
G01X474756Y536535D02*
X474751Y536541D01*
G01X474762Y536530D02*
X474756Y536535D01*
G01X474769Y536527D02*
X474762Y536530D01*
G01X474776Y536525D02*
X474769Y536527D01*
G01X474783Y536524D02*
X474776Y536525D01*
G01X474745Y539704D02*
X474744Y539711D01*
G01X474747Y539696D02*
X474745Y539704D01*
G01X474751Y539690D02*
X474747Y539696D01*
G01X474756Y539685D02*
X474751Y539690D01*
G01X474762Y539680D02*
X474756Y539685D01*
G01X474769Y539676D02*
X474762Y539680D01*
G01X474776Y539674D02*
X474769Y539676D01*
G01X474783Y539674D02*
X474776D01*
G01X474745Y542853D02*
X474744Y542860D01*
G01X474747Y542846D02*
X474745Y542853D01*
G01X474751Y542840D02*
X474747Y542846D01*
G01X474756Y542834D02*
X474751Y542840D01*
G01X474762Y542830D02*
X474756Y542834D01*
G01X474769Y542826D02*
X474762Y542830D01*
G01X474776Y542824D02*
X474769Y542826D01*
G01X474783Y542823D02*
X474776Y542824D01*
G01X474745Y546003D02*
X474744Y546010D01*
G01X474747Y545996D02*
X474745Y546003D01*
G01X474751Y545989D02*
X474747Y545996D01*
G01X474756Y545984D02*
X474751Y545989D01*
G01X474762Y545979D02*
X474756Y545984D01*
G01X474769Y545976D02*
X474762Y545979D01*
G01X474776Y545974D02*
X474769Y545976D01*
G01X474783Y545973D02*
X474776Y545974D01*
G01X474745Y549152D02*
X474744Y549159D01*
G01X474747Y549145D02*
X474745Y549152D01*
G01X474751Y549139D02*
X474747Y549145D01*
G01X474756Y549133D02*
X474751Y549139D01*
G01X474762Y549129D02*
X474756Y549133D01*
G01X474769Y549125D02*
X474762Y549129D01*
G01X474776Y549123D02*
X474769Y549125D01*
G01X474783Y549122D02*
X474776Y549123D01*
G01X474745Y552302D02*
X474744Y552309D01*
G01X474747Y552295D02*
X474745Y552302D01*
G01X474751Y552289D02*
X474747Y552295D01*
G01X474756Y552283D02*
X474751Y552289D01*
G01X474762Y552278D02*
X474756Y552283D01*
G01X474769Y552275D02*
X474762Y552278D01*
G01X474776Y552273D02*
X474769Y552275D01*
G01X474783Y552272D02*
X474776Y552273D01*
G01X474745Y555452D02*
X474744Y555459D01*
G01X474747Y555444D02*
X474745Y555452D01*
G01X474751Y555438D02*
X474747Y555444D01*
G01X474756Y555433D02*
X474751Y555438D01*
G01X474762Y555428D02*
X474756Y555433D01*
G01X474769Y555424D02*
X474762Y555428D01*
G01X474776Y555422D02*
X474769Y555424D01*
G01X474783Y555422D02*
X474776D01*
G01X475698Y537715D02*
X475707Y537711D01*
G01X475687Y537717D02*
X475698Y537715D01*
G01Y540865D02*
X475707Y540861D01*
G01X475687Y540866D02*
X475698Y540865D01*
G01Y544014D02*
X475707Y544010D01*
G01X475687Y544016D02*
X475698Y544014D01*
G01Y547164D02*
X475707Y547160D01*
G01X475687Y547165D02*
X475698Y547164D01*
G01Y550313D02*
X475707Y550309D01*
G01X475687Y550315D02*
X475698Y550313D01*
G01Y553463D02*
X475707Y553459D01*
G01X475687Y553465D02*
X475698Y553463D01*
G01Y556613D02*
X475707Y556609D01*
G01X475687Y556614D02*
X475698Y556613D01*
G01X474744Y556581D02*
Y556588D01*
G01X474743Y556576D02*
X474744Y556581D01*
G01X474742Y556575D02*
X474743Y556576D01*
G01X474744Y553431D02*
Y553439D01*
G01X474743Y553427D02*
X474744Y553431D01*
G01X474742Y553425D02*
X474743Y553427D01*
G01X474744Y550281D02*
Y550289D01*
G01X474743Y550277D02*
X474744Y550281D01*
G01X474742Y550276D02*
X474743Y550277D01*
G01X474744Y547132D02*
Y547139D01*
G01X474743Y547128D02*
X474744Y547132D01*
G01X474742Y547126D02*
X474743Y547128D01*
G01X474744Y543982D02*
Y543990D01*
G01X474743Y543978D02*
X474744Y543982D01*
G01X474742Y543976D02*
X474743Y543978D01*
G01X474744Y540833D02*
Y540840D01*
G01X474743Y540828D02*
X474744Y540833D01*
G01X474742Y540827D02*
X474743Y540828D01*
G01X474744Y537683D02*
Y537691D01*
G01X474743Y537679D02*
X474744Y537683D01*
G01X474742Y537677D02*
X474743Y537679D01*
G01X475728Y552302D02*
Y552309D01*
G01X475725Y552295D02*
X475728Y552302D01*
G01X475722Y552289D02*
X475725Y552295D01*
G01X475717Y552283D02*
X475722Y552289D01*
G01X475711Y552278D02*
X475717Y552283D01*
G01X475704Y552275D02*
X475711Y552278D01*
G01X475697Y552273D02*
X475704Y552275D01*
G01X475689Y552272D02*
X475697Y552273D01*
G01X475706Y536528D02*
X475709Y536530D01*
G01X475703Y536526D02*
X475706Y536528D01*
G01X475700Y536526D02*
X475703D01*
G01X475696Y536525D02*
X475700Y536526D01*
G01X475693Y536524D02*
X475696Y536525D01*
G01X475689Y536524D02*
X475693D01*
G01X474767Y537724D02*
X474763Y537722D01*
G01X474770Y537725D02*
X474767Y537724D01*
G01X474773Y537726D02*
X474770Y537725D01*
G01X474776Y537727D02*
X474773Y537726D01*
G01X474780Y537728D02*
X474776Y537727D01*
G01X474783Y537728D02*
X474780D01*
G01X475706Y539677D02*
X475709Y539679D01*
G01X475703Y539676D02*
X475706Y539677D01*
G01X475700Y539675D02*
X475703Y539676D01*
G01X475696Y539674D02*
X475700Y539675D01*
G01X475693Y539674D02*
X475696D01*
G01X475689D02*
X475693D01*
G01X474767Y540874D02*
X474763Y540872D01*
G01X474770Y540875D02*
X474767Y540874D01*
G01X474773Y540876D02*
X474770Y540875D01*
G01X474776Y540877D02*
X474773Y540876D01*
G01X474780Y540877D02*
X474776D01*
G01X474783D02*
X474780D01*
G01X475706Y542827D02*
X475709Y542829D01*
G01X475703Y542826D02*
X475706Y542827D01*
G01X475700Y542825D02*
X475703Y542826D01*
G01X475696Y542824D02*
X475700Y542825D01*
G01X475693Y542824D02*
X475696D01*
G01X475689Y542823D02*
X475693Y542824D01*
G01X474767Y544023D02*
X474763Y544022D01*
G01X474770Y544024D02*
X474767Y544023D01*
G01X474773Y544026D02*
X474770Y544024D01*
G01X474776Y544026D02*
X474773D01*
G01X474780Y544027D02*
X474776Y544026D01*
G01X474783Y544027D02*
X474780D01*
G01X475706Y545976D02*
X475709Y545978D01*
G01X475703Y545975D02*
X475706Y545976D01*
G01X475700Y545974D02*
X475703Y545975D01*
G01X475696Y545974D02*
X475700D01*
G01X475693Y545973D02*
X475696Y545974D01*
G01X475689Y545973D02*
X475693D01*
G01X474767Y547173D02*
X474763Y547171D01*
G01X474770Y547174D02*
X474767Y547173D01*
G01X474773Y547175D02*
X474770Y547174D01*
G01X474776Y547176D02*
X474773Y547175D01*
G01X474780Y547176D02*
X474776D01*
G01X474783D02*
X474780D01*
G01X475706Y549126D02*
X475709Y549128D01*
G01X475703Y549125D02*
X475706Y549126D01*
G01X475700Y549124D02*
X475703Y549125D01*
G01X475696Y549123D02*
X475700Y549124D01*
G01X475693Y549123D02*
X475696D01*
G01X475689Y549122D02*
X475693Y549123D01*
G01X474767Y550322D02*
X474763Y550321D01*
G01X474770Y550324D02*
X474767Y550322D01*
G01X474773Y550325D02*
X474770Y550324D01*
G01X474776Y550326D02*
X474773Y550325D01*
G01X474780Y550326D02*
X474776D01*
G01X474783D02*
X474780D01*
G01X474767Y553472D02*
X474763Y553470D01*
G01X474770Y553473D02*
X474767Y553472D01*
G01X474773Y553474D02*
X474770Y553473D01*
G01X474776Y553475D02*
X474773Y553474D01*
G01X474780Y553476D02*
X474776Y553475D01*
G01X474783Y553476D02*
X474780D01*
G01X475706Y555425D02*
X475709Y555427D01*
G01X475703Y555424D02*
X475706Y555425D01*
G01X475700Y555423D02*
X475703Y555424D01*
G01X475696Y555422D02*
X475700Y555423D01*
G01X475693Y555422D02*
X475696D01*
G01X475689D02*
X475693D01*
G01X474767Y556622D02*
X474763Y556620D01*
G01X474770Y556623D02*
X474767Y556622D01*
G01X474773Y556624D02*
X474770Y556623D01*
G01X474776Y556625D02*
X474773Y556624D01*
G01X474780Y556625D02*
X474776D01*
G01X474783D02*
X474780D01*
G01X473997Y539724D02*
X473563D01*
G01X474370D02*
X473997D01*
G01Y546024D02*
X473563D01*
G01X474370D02*
X473997D01*
G01Y549173D02*
X473563D01*
G01X474370D02*
X473997D01*
G01X475726Y555446D02*
X475728Y555459D01*
G01X475719Y555435D02*
X475726Y555446D01*
G01X475709Y555427D02*
X475719Y555435D01*
G01X475726Y549147D02*
X475728Y549159D01*
G01X475719Y549136D02*
X475726Y549147D01*
G01X475709Y549128D02*
X475719Y549136D01*
G01X475726Y545998D02*
X475728Y546010D01*
G01X475719Y545986D02*
X475726Y545998D01*
G01X475709Y545978D02*
X475719Y545986D01*
G01X475726Y542848D02*
X475728Y542860D01*
G01X475719Y542837D02*
X475726Y542848D01*
G01X475709Y542829D02*
X475719Y542837D01*
G01X475726Y539698D02*
X475728Y539711D01*
G01X475719Y539687D02*
X475726Y539698D01*
G01X475709Y539679D02*
X475719Y539687D01*
G01X475726Y536549D02*
X475728Y536561D01*
G01X475719Y536537D02*
X475726Y536549D01*
G01X475709Y536530D02*
X475719Y536537D01*
G01X474783Y556619D02*
Y556625D01*
G01Y556615D02*
Y556619D01*
G01X474781Y556614D02*
X474783Y556615D01*
G01Y553469D02*
Y553476D01*
G01Y553466D02*
Y553469D01*
G01X474781Y553465D02*
X474783Y553466D01*
G01Y550320D02*
Y550326D01*
G01Y550316D02*
Y550320D01*
G01X474781Y550315D02*
X474783Y550316D01*
G01Y547170D02*
Y547176D01*
G01Y547167D02*
Y547170D01*
G01X474781Y547165D02*
X474783Y547167D01*
G01Y544020D02*
Y544027D01*
G01Y544017D02*
Y544020D01*
G01X474781Y544016D02*
X474783Y544017D01*
G01Y540871D02*
Y540877D01*
G01Y540867D02*
Y540871D01*
G01X474781Y540866D02*
X474783Y540867D01*
G01Y537721D02*
Y537728D01*
G01Y537718D02*
Y537721D01*
G01X474781Y537717D02*
X474783Y537718D01*
G01X474745Y556594D02*
X474744Y556588D01*
G01X474746Y556601D02*
X474745Y556594D01*
G01X474749Y556607D02*
X474746Y556601D01*
G01X474753Y556612D02*
X474749Y556607D01*
G01X474758Y556617D02*
X474753Y556612D01*
G01X474763Y556620D02*
X474758Y556617D01*
G01X474745Y553445D02*
X474744Y553439D01*
G01X474746Y553451D02*
X474745Y553445D01*
G01X474749Y553457D02*
X474746Y553451D01*
G01X474753Y553462D02*
X474749Y553457D01*
G01X474758Y553467D02*
X474753Y553462D01*
G01X474763Y553470D02*
X474758Y553467D01*
G01X474745Y550295D02*
X474744Y550289D01*
G01X474746Y550302D02*
X474745Y550295D01*
G01X474749Y550307D02*
X474746Y550302D01*
G01X474753Y550313D02*
X474749Y550307D01*
G01X474758Y550317D02*
X474753Y550313D01*
G01X474763Y550321D02*
X474758Y550317D01*
G01X474745Y547146D02*
X474744Y547139D01*
G01X474746Y547152D02*
X474745Y547146D01*
G01X474749Y547158D02*
X474746Y547152D01*
G01X474753Y547163D02*
X474749Y547158D01*
G01X474758Y547168D02*
X474753Y547163D01*
G01X474763Y547171D02*
X474758Y547168D01*
G01X474745Y543996D02*
X474744Y543990D01*
G01X474746Y544002D02*
X474745Y543996D01*
G01X474749Y544008D02*
X474746Y544002D01*
G01X474753Y544013D02*
X474749Y544008D01*
G01X474758Y544018D02*
X474753Y544013D01*
G01X474763Y544022D02*
X474758Y544018D01*
G01X474745Y540846D02*
X474744Y540840D01*
G01X474746Y540853D02*
X474745Y540846D01*
G01X474749Y540859D02*
X474746Y540853D01*
G01X474753Y540864D02*
X474749Y540859D01*
G01X474758Y540869D02*
X474753Y540864D01*
G01X474763Y540872D02*
X474758Y540869D01*
G01X474745Y537697D02*
X474744Y537691D01*
G01X474746Y537703D02*
X474745Y537697D01*
G01X474749Y537709D02*
X474746Y537703D01*
G01X474753Y537714D02*
X474749Y537709D01*
G01X474758Y537719D02*
X474753Y537714D01*
G01X474763Y537722D02*
X474758Y537719D01*
G01X474747Y537697D02*
X474742Y537677D01*
G01X474761Y537711D02*
X474747Y537697D01*
G01X474781Y537717D02*
X474761Y537711D01*
G01X474747Y540846D02*
X474742Y540827D01*
G01X474761Y540861D02*
X474747Y540846D01*
G01X474781Y540866D02*
X474761Y540861D01*
G01X474747Y543996D02*
X474742Y543976D01*
G01X474761Y544010D02*
X474747Y543996D01*
G01X474781Y544016D02*
X474761Y544010D01*
G01X474747Y547146D02*
X474742Y547126D01*
G01X474761Y547160D02*
X474747Y547146D01*
G01X474781Y547165D02*
X474761Y547160D01*
G01X474747Y550295D02*
X474742Y550276D01*
G01X474761Y550309D02*
X474747Y550295D01*
G01X474781Y550315D02*
X474761Y550309D01*
G01X474747Y553445D02*
X474742Y553425D01*
G01X474761Y553459D02*
X474747Y553445D01*
G01X474781Y553465D02*
X474761Y553459D01*
G01X474747Y556594D02*
X474742Y556575D01*
G01X474761Y556609D02*
X474747Y556594D01*
G01X474781Y556614D02*
X474761Y556609D01*
G01X475722Y536555D02*
X475727Y536575D01*
G01X475707Y536541D02*
X475722Y536555D01*
G01X475687Y536535D02*
X475707Y536541D01*
G01X475722Y539705D02*
X475727Y539724D01*
G01X475707Y539690D02*
X475722Y539705D01*
G01X475687Y539685D02*
X475707Y539690D01*
G01X475722Y542854D02*
X475727Y542874D01*
G01X475707Y542840D02*
X475722Y542854D01*
G01X475687Y542835D02*
X475707Y542840D01*
G01X475722Y546004D02*
X475727Y546024D01*
G01X475707Y545989D02*
X475722Y546004D01*
G01X475687Y545984D02*
X475707Y545989D01*
G01X475722Y549154D02*
X475727Y549173D01*
G01X475707Y549139D02*
X475722Y549154D01*
G01X475687Y549134D02*
X475707Y549139D01*
G01X475722Y552303D02*
X475727Y552323D01*
G01X475707Y552289D02*
X475722Y552303D01*
G01X475687Y552283D02*
X475707Y552289D01*
G01X475722Y555453D02*
X475727Y555472D01*
G01X475707Y555438D02*
X475722Y555453D01*
G01X475687Y555433D02*
X475707Y555438D01*
G01X475700Y555435D02*
X475687Y555433D01*
G01X475710Y555440D02*
X475700Y555435D01*
G01Y552285D02*
X475687Y552283D01*
G01X475710Y552290D02*
X475700Y552285D01*
G01Y549136D02*
X475687Y549134D01*
G01X475710Y549141D02*
X475700Y549136D01*
G01Y545986D02*
X475687Y545984D01*
G01X475710Y545991D02*
X475700Y545986D01*
G01Y542837D02*
X475687Y542835D01*
G01X475710Y542841D02*
X475700Y542837D01*
G01Y539687D02*
X475687Y539685D01*
G01X475710Y539692D02*
X475700Y539687D01*
G01Y536537D02*
X475687Y536535D01*
G01X475710Y536542D02*
X475700Y536537D01*
G01X479724Y477894D02*
G03X480315Y477303I591J0D01*
G01X479921Y488169D02*
G03X481102Y486988I1181J0D01*
G01X472835Y478484D02*
G03X474803Y476516I1968J0D01*
G01X474742Y546019D02*
X474631Y546024D01*
G01X474742Y549170D02*
X474631Y549173D01*
G01X476181Y558780D02*
X472835D01*
G01X475689Y556811D02*
X474783D01*
G01X475728Y556772D02*
X474744D01*
G01X475687Y556614D02*
X469803D01*
G01Y556575D02*
X475727D01*
G01Y555472D02*
X469803D01*
G01X475687Y555433D02*
X469803D01*
G01X474744Y555276D02*
X475728D01*
G01X474783Y555236D02*
X475689D01*
G01Y553661D02*
X474783D01*
G01X475728Y553622D02*
X474744D01*
G01X475687Y553465D02*
X469803D01*
G01Y553425D02*
X475727D01*
G01Y552323D02*
X469803D01*
G01X475687Y552283D02*
X469803D01*
G01X474744Y552126D02*
X475728D01*
G01X474783Y552087D02*
X475689D01*
G01Y550512D02*
X474783D01*
G01X475728Y550472D02*
X474744D01*
G01X475687Y550315D02*
X469803D01*
G01Y550276D02*
X475727D01*
G01Y549173D02*
X469803D01*
G01X475687Y549134D02*
X469803D01*
G01X474744Y548976D02*
X475728D01*
G01X474783Y548937D02*
X475689D01*
G01Y547362D02*
X474783D01*
G01X475728Y547323D02*
X474744D01*
G01X475687Y547165D02*
X469803D01*
G01Y547126D02*
X475727D01*
G01Y546024D02*
X469803D01*
G01X475687Y545984D02*
X469803D01*
G01X474744Y545827D02*
X475728D01*
G01X474783Y545787D02*
X475689D01*
G01Y544213D02*
X474783D01*
G01X475728Y544173D02*
X474744D01*
G01X475687Y544016D02*
X469803D01*
G01Y543976D02*
X475727D01*
G01Y542874D02*
X469803D01*
G01X475687Y542835D02*
X469803D01*
G01X474744Y542677D02*
X475728D01*
G01X474783Y542638D02*
X475689D01*
G01Y541063D02*
X474783D01*
G01X475728Y541024D02*
X474744D01*
G01X475687Y540866D02*
X469803D01*
G01Y540827D02*
X475727D01*
G01Y539724D02*
X469803D01*
G01X475687Y539685D02*
X469803D01*
G01X474744Y539528D02*
X475728D01*
G01X474783Y539488D02*
X475689D01*
G01Y537913D02*
X474783D01*
G01X475728Y537874D02*
X474744D01*
G01X475687Y537717D02*
X469803D01*
G01Y537677D02*
X475727D01*
G01Y536575D02*
X469803D01*
G01X475687Y536535D02*
X469803D01*
G01X474744Y536378D02*
X475728D01*
G01X474783Y536339D02*
X475689D01*
G01X476181Y534370D02*
X472835D01*
G01X479134Y500256D02*
X477953Y499075D01*
G01X476181Y497579D02*
X472835Y494232D01*
G01X474631Y555472D02*
X474743Y555464D01*
G01X474742Y539721D02*
X474631Y539724D01*
G01X484646Y500256D02*
X479134D01*
G01X485827Y499075D02*
X477953D01*
G01X491142Y497579D02*
X476181D01*
G01X479921Y496713D02*
X476181D01*
G01Y495335D02*
X490551D01*
G01X486220Y486988D02*
X481102D01*
G01X494488Y486949D02*
X472835D01*
G01X487598Y483996D02*
X479724D01*
G01Y482421D02*
X487598D01*
G01X487008Y477303D02*
X480315D01*
G01X492520Y476516D02*
X474803D01*
G01X480170Y487444D02*
X482480Y491673D01*
G01X475687Y552283D02*
X475691Y552272D01*
G01X482480Y493366D02*
X481177Y495335D01*
G01X475728Y537679D02*
Y537691D01*
G01Y540829D02*
Y540840D01*
G01Y543978D02*
Y543990D01*
G01Y547128D02*
Y547139D01*
G01Y550278D02*
Y550289D01*
G01Y553427D02*
Y553439D01*
G01Y556577D02*
Y556588D01*
G01X479921Y488169D02*
Y496713D01*
G01X479724Y483996D02*
Y477894D01*
G01X479134Y500256D02*
Y632894D01*
G01X477953Y499075D02*
Y634075D01*
G01X476181Y534370D02*
Y495335D01*
G01Y637815D02*
Y558780D01*
G01X475728Y555275D02*
Y556772D01*
G01Y552126D02*
Y553622D01*
G01Y548976D02*
Y550472D01*
G01Y545826D02*
Y547323D01*
G01Y542677D02*
Y544173D01*
G01Y539527D02*
Y541024D01*
G01Y536378D02*
Y537874D01*
G01X475689Y536524D02*
Y536377D01*
G01Y539674D02*
Y539527D01*
G01Y541024D02*
Y540877D01*
G01Y537874D02*
Y537728D01*
G01Y545973D02*
Y545826D01*
G01Y542823D02*
Y542676D01*
G01Y544174D02*
Y544027D01*
G01Y549122D02*
Y548976D01*
G01Y550473D02*
Y550326D01*
G01Y547323D02*
Y547176D01*
G01Y555422D02*
Y555275D01*
G01Y552272D02*
Y552125D01*
G01Y553622D02*
Y553476D01*
G01Y556772D02*
Y556625D01*
G01X474783D02*
Y556772D01*
G01Y555275D02*
Y555422D01*
G01Y552125D02*
Y552272D01*
G01Y553476D02*
Y553622D01*
G01Y548976D02*
Y549122D01*
G01Y550326D02*
Y550473D01*
G01Y547176D02*
Y547323D01*
G01Y545826D02*
Y545973D01*
G01Y542676D02*
Y542823D01*
G01Y544027D02*
Y544174D01*
G01Y539527D02*
Y539674D01*
G01Y540877D02*
Y541024D01*
G01Y537728D02*
Y537874D01*
G01Y536377D02*
Y536524D01*
G01X474744Y541024D02*
Y539528D01*
G01Y537874D02*
Y536378D01*
G01Y544173D02*
Y542677D01*
G01Y550472D02*
Y548976D01*
G01Y547323D02*
Y545827D01*
G01Y553622D02*
Y552126D01*
G01Y556772D02*
Y555276D01*
G01X473563Y537717D02*
Y536535D01*
G01Y540866D02*
Y539685D01*
G01Y547165D02*
Y545984D01*
G01Y544016D02*
Y542835D01*
G01Y550315D02*
Y549134D01*
G01Y556614D02*
Y555433D01*
G01Y553465D02*
Y552283D01*
G01X473228Y558780D02*
Y534370D01*
G01X472835D02*
Y558780D01*
G01Y494232D02*
Y478484D01*
G01X469803Y555433D02*
Y556614D01*
G01Y552283D02*
Y553465D01*
G01Y549134D02*
Y550315D01*
G01Y545984D02*
Y547165D01*
G01Y542835D02*
Y544016D01*
G01Y539685D02*
Y540866D01*
G01Y536535D02*
Y537717D01*
G01X475728Y555459D02*
Y555470D01*
G01Y552309D02*
Y552320D01*
G01Y549160D02*
Y549170D01*
G01Y546010D02*
Y546021D01*
G01Y542861D02*
Y542871D01*
G01Y539711D02*
Y539722D01*
G01Y536561D02*
Y536572D01*
G01X480315Y655846D02*
G03X479724Y655256I0J-591D01*
G01X481102Y646161D02*
G03X479921Y644980I0J-1181D01*
G01X474803Y656634D02*
G03X472835Y654665I0J-1968D01*
G01X492520Y656634D02*
X474803D01*
G01X487008Y655846D02*
X480315D01*
G01X487598Y650728D02*
X479724D01*
G01Y649154D02*
X487598D01*
G01X494488Y646201D02*
X472835D01*
G01X481102Y646161D02*
X486220D01*
G01X476181Y637815D02*
X490551D01*
G01X476181Y636437D02*
X479921D01*
G01X476181Y635571D02*
X491142D01*
G01X477953Y634075D02*
X485827D01*
G01X479134Y632894D02*
X484646D01*
G01X481177Y637815D02*
X482480Y639783D01*
G01X477953Y634075D02*
X479134Y632894D01*
G01X472835Y638917D02*
X476181Y635571D01*
G01X482480Y641476D02*
X480170Y645706D01*
G01X479921Y636437D02*
Y644980D01*
G01X479724Y649154D02*
Y655256D01*
G01X472835Y654665D02*
Y638917D01*
G01X389213Y730599D02*
G03X396138Y717468I37662J11471D01*
G01X443701Y713386D02*
G03X444882I591J0D01*
G01Y707087D02*
G03X443701I-590J0D01*
G01X441732D02*
G03X440551I-591J0D01*
G01Y713386D02*
G03X441732I590J0D01*
G01X443701D02*
G03X444882I591J0D01*
G01Y707087D02*
G03X443701I-590J0D01*
G01X441732D02*
G03X440551I-591J0D01*
G01Y713386D02*
G03X441732I590J0D01*
G01X389213Y730599D02*
G03X396138Y717468I37662J11470D01*
G01X443701Y713386D02*
X441732D01*
G01X440551D02*
X439764D01*
G01X443701D02*
X441732D01*
G01X440551D02*
X439764D01*
G01X445669D02*
X444882D01*
G01X445669D02*
X444882D01*
G01X445669Y712402D02*
X439764D01*
G01Y712205D02*
X445669D01*
G01X439764Y708268D02*
X445669D01*
G01Y708071D02*
X439764D01*
G01X444882Y707087D02*
X445669D01*
G01X444882D02*
X445669D01*
G01X441732D02*
X443701D01*
G01X439764D02*
X440551D01*
G01X441732D02*
X443701D01*
G01X439764D02*
X440551D01*
G01X445669D02*
Y713386D01*
G01Y707087D02*
Y713386D01*
G01X439764Y707087D02*
Y713386D01*
G01D02*
Y707087D01*
G01X479724Y930650D02*
G03X480315Y930059I591J0D01*
G01X479921Y940925D02*
G03X481102Y939744I1181J0D01*
G01X472835Y931240D02*
G03X474803Y929272I1968J0D01*
G01X485827Y951831D02*
X477953D01*
G01X491142Y950335D02*
X476181D01*
G01X479921Y949469D02*
X476181D01*
G01Y948091D02*
X490551D01*
G01X486220Y939744D02*
X481102D01*
G01X494488Y939705D02*
X472835D01*
G01X487598Y936752D02*
X479724D01*
G01Y935177D02*
X487598D01*
G01X487008Y930059D02*
X480315D01*
G01X492520Y929272D02*
X474803D01*
G01X482480Y946122D02*
X481177Y948091D01*
G01X479134Y953012D02*
X477953Y951831D01*
G01X476181Y950335D02*
X472835Y946988D01*
G01X480170Y940200D02*
X482480Y944429D01*
G01X479921Y940925D02*
Y949469D01*
G01X479724Y936752D02*
Y930650D01*
G01X477953Y951831D02*
Y1086831D01*
G01X476181Y987126D02*
Y948091D01*
G01X472835Y946988D02*
Y931240D01*
G01X474744Y1001923D02*
Y1001916D01*
G01X474743Y1001928D02*
X474744Y1001923D01*
G01X474743Y1001918D02*
Y1001928D01*
G01X474784Y1009554D02*
X474783Y1009567D01*
G01X474781Y1009541D02*
X474784Y1009554D01*
G01X474781Y1009528D02*
Y1009541D01*
G01X474784Y1006405D02*
X474783Y1006417D01*
G01X474781Y1006392D02*
X474784Y1006405D01*
G01X474781Y1006378D02*
Y1006392D01*
G01X474784Y1003255D02*
X474783Y1003268D01*
G01X474781Y1003242D02*
X474784Y1003255D01*
G01X474781Y1003228D02*
Y1003242D01*
G01X474784Y1000106D02*
X474783Y1000118D01*
G01X474781Y1000093D02*
X474784Y1000106D01*
G01X474781Y1000079D02*
Y1000093D01*
G01X474784Y996956D02*
X474783Y996969D01*
G01X474781Y996943D02*
X474784Y996956D01*
G01X474781Y996929D02*
Y996943D01*
G01X474784Y993806D02*
X474783Y993819D01*
G01X474781Y993793D02*
X474784Y993806D01*
G01X474781Y993780D02*
Y993793D01*
G01X474784Y990657D02*
X474783Y990669D01*
G01X474781Y990644D02*
X474784Y990657D01*
G01X474781Y990630D02*
Y990644D01*
G01X474744Y1008222D02*
Y1008215D01*
G01X474743Y1008227D02*
X474744Y1008222D01*
G01X474743Y1008219D02*
Y1008227D01*
G01X474781Y1008017D02*
X474780Y1008031D01*
G01X474784Y1008005D02*
X474781Y1008017D01*
G01X474783Y1007992D02*
X474784Y1008005D01*
G01X474781Y1004868D02*
X474780Y1004881D01*
G01X474784Y1004855D02*
X474781Y1004868D01*
G01X474783Y1004843D02*
X474784Y1004855D01*
G01X474781Y1001718D02*
X474780Y1001732D01*
G01X474784Y1001706D02*
X474781Y1001718D01*
G01X474783Y1001693D02*
X474784Y1001706D01*
G01X474781Y998569D02*
X474780Y998582D01*
G01X474784Y998556D02*
X474781Y998569D01*
G01X474783Y998543D02*
X474784Y998556D01*
G01X474781Y995419D02*
X474780Y995433D01*
G01X474784Y995406D02*
X474781Y995419D01*
G01X474783Y995394D02*
X474784Y995406D01*
G01X474781Y992269D02*
X474780Y992283D01*
G01X474784Y992257D02*
X474781Y992269D01*
G01X474783Y992244D02*
X474784Y992257D01*
G01X474781Y989120D02*
X474780Y989133D01*
G01X474784Y989107D02*
X474781Y989120D01*
G01X474783Y989094D02*
X474784Y989107D01*
G01X475691Y1009541D02*
X475693Y1009528D01*
G01X475688Y1009554D02*
X475691Y1009541D01*
G01X475689Y1009567D02*
X475688Y1009554D01*
G01X475691Y1006392D02*
X475693Y1006378D01*
G01X475688Y1006405D02*
X475691Y1006392D01*
G01X475689Y1006417D02*
X475688Y1006405D01*
G01X475691Y1003242D02*
X475693Y1003228D01*
G01X475688Y1003255D02*
X475691Y1003242D01*
G01X475689Y1003268D02*
X475688Y1003255D01*
G01X475691Y1000093D02*
X475693Y1000079D01*
G01X475688Y1000106D02*
X475691Y1000093D01*
G01X475689Y1000118D02*
X475688Y1000106D01*
G01X475691Y996943D02*
X475693Y996929D01*
G01X475688Y996956D02*
X475691Y996943D01*
G01X475689Y996969D02*
X475688Y996956D01*
G01X475691Y993793D02*
X475693Y993780D01*
G01X475688Y993806D02*
X475691Y993793D01*
G01X475689Y993819D02*
X475688Y993806D01*
G01X475691Y990644D02*
X475693Y990630D01*
G01X475688Y990657D02*
X475691Y990644D01*
G01X475689Y990669D02*
X475688Y990657D01*
G01X474744Y995624D02*
Y995617D01*
G01X474743Y995628D02*
X474744Y995624D01*
G01X474743Y995621D02*
Y995628D01*
G01X474744Y1005073D02*
Y1005065D01*
G01X474743Y1005077D02*
X474744Y1005073D01*
G01X474743Y1005070D02*
Y1005077D01*
G01X475688Y1008005D02*
X475689Y1007992D01*
G01X475691Y1008017D02*
X475688Y1008005D01*
G01X475692Y1008031D02*
X475691Y1008017D01*
G01X475688Y1004855D02*
X475689Y1004843D01*
G01X475691Y1004868D02*
X475688Y1004855D01*
G01X475692Y1004881D02*
X475691Y1004868D01*
G01X475688Y1001706D02*
X475689Y1001693D01*
G01X475691Y1001718D02*
X475688Y1001706D01*
G01X475692Y1001732D02*
X475691Y1001718D01*
G01X475688Y998556D02*
X475689Y998543D01*
G01X475691Y998569D02*
X475688Y998556D01*
G01X475692Y998582D02*
X475691Y998569D01*
G01X475688Y995406D02*
X475689Y995394D01*
G01X475691Y995419D02*
X475688Y995406D01*
G01X475692Y995433D02*
X475691Y995419D01*
G01X475688Y992257D02*
X475689Y992244D01*
G01X475691Y992269D02*
X475688Y992257D01*
G01X475692Y992283D02*
X475691Y992269D01*
G01X475688Y989107D02*
X475689Y989094D01*
G01X475691Y989120D02*
X475688Y989107D01*
G01X475692Y989133D02*
X475691Y989120D01*
G01X474744Y989325D02*
Y989317D01*
G01X474743Y989329D02*
X474744Y989325D01*
G01X474743Y989323D02*
Y989329D01*
G01X474757Y1009361D02*
X474781Y1009370D01*
G01X474746Y1009347D02*
X474757Y1009361D01*
G01X474744Y1009340D02*
X474746Y1009347D01*
G01X474757Y1006212D02*
X474781Y1006220D01*
G01X474746Y1006197D02*
X474757Y1006212D01*
G01X474744Y1006191D02*
X474746Y1006197D01*
G01X474757Y1003062D02*
X474781Y1003071D01*
G01X474746Y1003048D02*
X474757Y1003062D01*
G01X474744Y1003041D02*
X474746Y1003048D01*
G01X474757Y999913D02*
X474781Y999921D01*
G01X474746Y999898D02*
X474757Y999913D01*
G01X474744Y999891D02*
X474746Y999898D01*
G01X474757Y996763D02*
X474781Y996772D01*
G01X474746Y996748D02*
X474757Y996763D01*
G01X474744Y996742D02*
X474746Y996748D01*
G01X474757Y993613D02*
X474781Y993622D01*
G01X474746Y993599D02*
X474757Y993613D01*
G01X474744Y993592D02*
X474746Y993599D01*
G01X474757Y990464D02*
X474781Y990472D01*
G01X474746Y990449D02*
X474757Y990464D01*
G01X474744Y990443D02*
X474746Y990449D01*
G01X475728Y1009337D02*
Y1009344D01*
G01Y1009332D02*
Y1009337D01*
G01X475727Y1009331D02*
X475728Y1009332D01*
G01Y1006187D02*
Y1006194D01*
G01Y1006183D02*
Y1006187D01*
G01X475727Y1006181D02*
X475728Y1006183D01*
G01Y1003038D02*
Y1003045D01*
G01Y1003033D02*
Y1003038D01*
G01X475727Y1003031D02*
X475728Y1003033D01*
G01Y999888D02*
Y999895D01*
G01Y999883D02*
Y999888D01*
G01X475727Y999882D02*
X475728Y999883D01*
G01Y996739D02*
Y996746D01*
G01Y996734D02*
Y996739D01*
G01X475727Y996732D02*
X475728Y996734D01*
G01Y993589D02*
Y993596D01*
G01Y993584D02*
Y993589D01*
G01X475727Y993583D02*
X475728Y993584D01*
G01Y990439D02*
Y990446D01*
G01Y990435D02*
Y990439D01*
G01X475727Y990433D02*
X475728Y990435D01*
G01X474744Y998774D02*
Y998766D01*
G01X474743Y998778D02*
X474744Y998774D01*
G01X474742Y998775D02*
X474743Y998778D01*
G01X474744Y992474D02*
Y992467D01*
G01X474743Y992479D02*
X474744Y992474D01*
G01X474742Y992477D02*
X474743Y992479D01*
G01X475689Y1009375D02*
Y1009381D01*
G01X475688Y1009371D02*
X475689Y1009375D01*
G01X475687Y1009370D02*
X475688Y1009371D01*
G01X475689Y1006226D02*
Y1006231D01*
G01X475688Y1006222D02*
X475689Y1006226D01*
G01X475687Y1006220D02*
X475688Y1006222D01*
G01X475689Y1003076D02*
Y1003082D01*
G01X475688Y1003072D02*
X475689Y1003076D01*
G01X475687Y1003071D02*
X475688Y1003072D01*
G01X475689Y999926D02*
Y999932D01*
G01X475688Y999922D02*
X475689Y999926D01*
G01X475687Y999921D02*
X475688Y999922D01*
G01X475689Y996777D02*
Y996783D01*
G01X475688Y996773D02*
X475689Y996777D01*
G01X475687Y996772D02*
X475688Y996773D01*
G01X475689Y993627D02*
Y993633D01*
G01X475688Y993623D02*
X475689Y993627D01*
G01X475687Y993622D02*
X475688Y993623D01*
G01X475689Y990478D02*
Y990483D01*
G01X475688Y990474D02*
X475689Y990478D01*
G01X475687Y990472D02*
X475688Y990474D01*
G01X474744Y1009337D02*
Y1009344D01*
G01X474743Y1009332D02*
X474744Y1009337D01*
G01X474742Y1009331D02*
X474743Y1009332D01*
G01X474744Y1006187D02*
Y1006194D01*
G01X474743Y1006183D02*
X474744Y1006187D01*
G01X474742Y1006181D02*
X474743Y1006183D01*
G01X474744Y1003037D02*
Y1003045D01*
G01X474743Y1003033D02*
X474744Y1003037D01*
G01X474742Y1003031D02*
X474743Y1003033D01*
G01X474744Y999888D02*
Y999895D01*
G01X474743Y999883D02*
X474744Y999888D01*
G01X474742Y999882D02*
X474743Y999883D01*
G01X474744Y996738D02*
Y996746D01*
G01X474743Y996734D02*
X474744Y996738D01*
G01X474742Y996732D02*
X474743Y996734D01*
G01X474744Y993589D02*
Y993596D01*
G01X474743Y993584D02*
X474744Y993589D01*
G01X474742Y993583D02*
X474743Y993584D01*
G01X474744Y990439D02*
Y990446D01*
G01X474743Y990435D02*
X474744Y990439D01*
G01X474742Y990433D02*
X474743Y990435D01*
G01X475726Y1008202D02*
X475728Y1008215D01*
G01X475719Y1008191D02*
X475726Y1008202D01*
G01X475709Y1008183D02*
X475719Y1008191D01*
G01X475726Y1001903D02*
X475728Y1001915D01*
G01X475719Y1001892D02*
X475726Y1001903D01*
G01X475709Y1001884D02*
X475719Y1001892D01*
G01X475726Y998754D02*
X475728Y998766D01*
G01X475719Y998742D02*
X475726Y998754D01*
G01X475709Y998734D02*
X475719Y998742D01*
G01X475726Y995604D02*
X475728Y995616D01*
G01X475719Y995593D02*
X475726Y995604D01*
G01X475709Y995585D02*
X475719Y995593D01*
G01X475726Y992454D02*
X475728Y992467D01*
G01X475719Y992443D02*
X475726Y992454D01*
G01X475709Y992435D02*
X475719Y992443D01*
G01X475726Y989305D02*
X475728Y989317D01*
G01X475719Y989293D02*
X475726Y989305D01*
G01X475709Y989285D02*
X475719Y989293D01*
G01X474783Y1009375D02*
Y1009381D01*
G01Y1009371D02*
Y1009375D01*
G01X474781Y1009370D02*
X474783Y1009371D01*
G01Y1006225D02*
Y1006231D01*
G01Y1006222D02*
Y1006225D01*
G01X474781Y1006220D02*
X474783Y1006222D01*
G01Y1003076D02*
Y1003082D01*
G01Y1003072D02*
Y1003076D01*
G01X474781Y1003071D02*
X474783Y1003072D01*
G01Y999926D02*
Y999932D01*
G01Y999922D02*
Y999926D01*
G01X474781Y999921D02*
X474783Y999922D01*
G01Y996776D02*
Y996783D01*
G01Y996773D02*
Y996776D01*
G01X474781Y996772D02*
X474783Y996773D01*
G01Y993627D02*
Y993633D01*
G01Y993623D02*
Y993627D01*
G01X474781Y993622D02*
X474783Y993623D01*
G01Y990477D02*
Y990483D01*
G01Y990474D02*
Y990477D01*
G01X474781Y990472D02*
X474783Y990474D01*
G01X474745Y1009350D02*
X474744Y1009344D01*
G01X474746Y1009357D02*
X474745Y1009350D01*
G01X474749Y1009363D02*
X474746Y1009357D01*
G01X474753Y1009368D02*
X474749Y1009363D01*
G01X474758Y1009372D02*
X474753Y1009368D01*
G01X474763Y1009376D02*
X474758Y1009372D01*
G01X474745Y1006201D02*
X474744Y1006194D01*
G01X474746Y1006207D02*
X474745Y1006201D01*
G01X474749Y1006213D02*
X474746Y1006207D01*
G01X474753Y1006218D02*
X474749Y1006213D01*
G01X474758Y1006223D02*
X474753Y1006218D01*
G01X474763Y1006226D02*
X474758Y1006223D01*
G01X474745Y1003051D02*
X474744Y1003045D01*
G01X474746Y1003057D02*
X474745Y1003051D01*
G01X474749Y1003063D02*
X474746Y1003057D01*
G01X474753Y1003069D02*
X474749Y1003063D01*
G01X474758Y1003073D02*
X474753Y1003069D01*
G01X474763Y1003077D02*
X474758Y1003073D01*
G01X474745Y999902D02*
X474744Y999895D01*
G01X474746Y999908D02*
X474745Y999902D01*
G01X474749Y999914D02*
X474746Y999908D01*
G01X474753Y999919D02*
X474749Y999914D01*
G01X474758Y999924D02*
X474753Y999919D01*
G01X474763Y999927D02*
X474758Y999924D01*
G01X474745Y996752D02*
X474744Y996746D01*
G01X474746Y996758D02*
X474745Y996752D01*
G01X474749Y996764D02*
X474746Y996758D01*
G01X474753Y996769D02*
X474749Y996764D01*
G01X474758Y996774D02*
X474753Y996769D01*
G01X474763Y996778D02*
X474758Y996774D01*
G01X474745Y993602D02*
X474744Y993596D01*
G01X474746Y993609D02*
X474745Y993602D01*
G01X474749Y993615D02*
X474746Y993609D01*
G01X474753Y993620D02*
X474749Y993615D01*
G01X474758Y993624D02*
X474753Y993620D01*
G01X474763Y993628D02*
X474758Y993624D01*
G01X474745Y990453D02*
X474744Y990446D01*
G01X474746Y990459D02*
X474745Y990453D01*
G01X474749Y990465D02*
X474746Y990459D01*
G01X474753Y990470D02*
X474749Y990465D01*
G01X474758Y990475D02*
X474753Y990470D01*
G01X474763Y990478D02*
X474758Y990475D01*
G01X475700Y1008191D02*
X475687Y1008189D01*
G01X475710Y1008196D02*
X475700Y1008191D01*
G01Y1005041D02*
X475687Y1005039D01*
G01X475710Y1005046D02*
X475700Y1005041D01*
G01Y1001892D02*
X475687Y1001890D01*
G01X475710Y1001896D02*
X475700Y1001892D01*
G01Y998742D02*
X475687Y998740D01*
G01X475710Y998747D02*
X475700Y998742D01*
G01Y995593D02*
X475687Y995591D01*
G01X475710Y995597D02*
X475700Y995593D01*
G01Y992443D02*
X475687Y992441D01*
G01X475710Y992448D02*
X475700Y992443D01*
G01Y989293D02*
X475687Y989291D01*
G01X475710Y989298D02*
X475700Y989293D01*
G01X475721Y996754D02*
X475713Y996762D01*
G01X475726Y996743D02*
X475721Y996754D01*
G01X475727Y996732D02*
X475726Y996743D01*
G01X475721Y990454D02*
X475713Y990463D01*
G01X475726Y990444D02*
X475721Y990454D01*
G01X475727Y990433D02*
X475726Y990444D01*
G01X475721Y993604D02*
X475713Y993612D01*
G01X475726Y993594D02*
X475721Y993604D01*
G01X475727Y993583D02*
X475726Y993594D01*
G01X475721Y999903D02*
X475713Y999911D01*
G01X475726Y999893D02*
X475721Y999903D01*
G01X475727Y999882D02*
X475726Y999893D01*
G01X475721Y1003053D02*
X475713Y1003061D01*
G01X475726Y1003043D02*
X475721Y1003053D01*
G01X475727Y1003031D02*
X475726Y1003043D01*
G01X475721Y1006202D02*
X475713Y1006211D01*
G01X475726Y1006192D02*
X475721Y1006202D01*
G01X475727Y1006181D02*
X475726Y1006192D01*
G01X475721Y1009352D02*
X475713Y1009360D01*
G01X475726Y1009342D02*
X475721Y1009352D01*
G01X475727Y1009331D02*
X475726Y1009342D01*
G01X474766Y989294D02*
X474781Y989291D01*
G01X474753Y989303D02*
X474766Y989294D01*
G01X474743Y989323D02*
X474753Y989303D01*
G01X475728Y990453D02*
Y990446D01*
G01X475726Y990459D02*
X475728Y990453D01*
G01X475723Y990465D02*
X475726Y990459D01*
G01X475728Y993603D02*
Y993596D01*
G01X475726Y993609D02*
X475728Y993603D01*
G01X475723Y993615D02*
X475726Y993609D01*
G01X475728Y996752D02*
Y996746D01*
G01X475726Y996759D02*
X475728Y996752D01*
G01X475723Y996765D02*
X475726Y996759D01*
G01X475728Y999902D02*
Y999895D01*
G01X475726Y999908D02*
X475728Y999902D01*
G01X475723Y999914D02*
X475726Y999908D01*
G01X475728Y1003052D02*
Y1003045D01*
G01X475726Y1003058D02*
X475728Y1003052D01*
G01X475723Y1003064D02*
X475726Y1003058D01*
G01X475728Y1006201D02*
Y1006194D01*
G01X475726Y1006207D02*
X475728Y1006201D01*
G01X475723Y1006213D02*
X475726Y1006207D01*
G01X475728Y1009351D02*
Y1009344D01*
G01X475726Y1009357D02*
X475728Y1009351D01*
G01X475723Y1009363D02*
X475726Y1009357D01*
G01X475689Y989286D02*
X475690Y989280D01*
G01X475688Y989290D02*
X475689Y989286D01*
G01X475687Y989291D02*
X475688Y989290D01*
G01X475689Y992436D02*
X475690Y992430D01*
G01X475688Y992439D02*
X475689Y992436D01*
G01X475687Y992441D02*
X475688Y992439D01*
G01X475689Y995585D02*
X475690Y995579D01*
G01X475688Y995589D02*
X475689Y995585D01*
G01X475687Y995591D02*
X475688Y995589D01*
G01X475689Y998735D02*
X475690Y998729D01*
G01X475688Y998739D02*
X475689Y998735D01*
G01X475687Y998740D02*
X475688Y998739D01*
G01X475689Y1001885D02*
X475690Y1001878D01*
G01X475688Y1001888D02*
X475689Y1001885D01*
G01X475687Y1001890D02*
X475688Y1001888D01*
G01X475689Y1008184D02*
X475690Y1008178D01*
G01X475688Y1008187D02*
X475689Y1008184D01*
G01X475687Y1008189D02*
X475688Y1008187D01*
G01X474762Y998745D02*
X474781Y998740D01*
G01X474748Y998757D02*
X474762Y998745D01*
G01X474742Y998775D02*
X474748Y998757D01*
G01X474767Y992443D02*
X474781Y992441D01*
G01X474756Y992450D02*
X474767Y992443D01*
G01X474743Y992469D02*
X474756Y992450D01*
G01X474767Y1001892D02*
X474781Y1001890D01*
G01X474755Y1001900D02*
X474767Y1001892D01*
G01X474743Y1001918D02*
X474755Y1001900D01*
G01X474767Y995593D02*
X474781Y995591D01*
G01X474754Y995601D02*
X474767Y995593D01*
G01X474743Y995621D02*
X474754Y995601D01*
G01X474767Y1005042D02*
X474781Y1005039D01*
G01X474754Y1005050D02*
X474767Y1005042D01*
G01X474743Y1005070D02*
X474754Y1005050D01*
G01X475728Y989325D02*
Y989317D01*
G01Y989329D02*
Y989325D01*
G01X475727Y989331D02*
X475728Y989329D01*
G01Y992474D02*
Y992467D01*
G01Y992479D02*
Y992474D01*
G01X475727Y992480D02*
X475728Y992479D01*
G01Y995624D02*
Y995616D01*
G01Y995628D02*
Y995624D01*
G01X475727Y995630D02*
X475728Y995628D01*
G01Y998774D02*
Y998766D01*
G01Y998778D02*
Y998774D01*
G01X475727Y998780D02*
X475728Y998778D01*
G01Y1001923D02*
Y1001915D01*
G01Y1001928D02*
Y1001923D01*
G01X475727Y1001929D02*
X475728Y1001928D01*
G01Y1005073D02*
Y1005065D01*
G01Y1005077D02*
Y1005073D01*
G01X475727Y1005079D02*
X475728Y1005077D01*
G01Y1008222D02*
Y1008215D01*
G01Y1008227D02*
Y1008222D01*
G01X475727Y1008228D02*
X475728Y1008227D01*
G01X474767Y1008192D02*
X474781Y1008189D01*
G01X474754Y1008200D02*
X474767Y1008192D01*
G01X474743Y1008220D02*
X474754Y1008200D01*
G01X474783Y989286D02*
Y989280D01*
G01X474782Y989290D02*
X474783Y989286D01*
G01X474781Y989291D02*
X474782Y989290D01*
G01X475697Y996770D02*
X475687Y996772D01*
G01X475706Y996767D02*
X475697Y996770D01*
G01X475713Y996762D02*
X475706Y996767D01*
G01X475697Y990471D02*
X475687Y990472D01*
G01X475706Y990468D02*
X475697Y990471D01*
G01X475713Y990463D02*
X475706Y990468D01*
G01X475697Y993621D02*
X475687Y993622D01*
G01X475706Y993618D02*
X475697Y993621D01*
G01X475713Y993612D02*
X475706Y993618D01*
G01X475697Y999920D02*
X475687Y999921D01*
G01X475706Y999917D02*
X475697Y999920D01*
G01X475713Y999911D02*
X475706Y999917D01*
G01X475697Y1003070D02*
X475687Y1003071D01*
G01X475706Y1003067D02*
X475697Y1003070D01*
G01X475713Y1003061D02*
X475706Y1003067D01*
G01X475697Y1006219D02*
X475687Y1006220D01*
G01X475706Y1006216D02*
X475697Y1006219D01*
G01X475713Y1006211D02*
X475706Y1006216D01*
G01X475697Y1009369D02*
X475687Y1009370D01*
G01X475706Y1009366D02*
X475697Y1009369D01*
G01X475713Y1009360D02*
X475706Y1009366D01*
G01X474783Y992436D02*
Y992430D01*
G01X474782Y992440D02*
X474783Y992436D01*
G01X474781Y992441D02*
X474782Y992440D01*
G01X474783Y995585D02*
Y995579D01*
G01X474782Y995589D02*
X474783Y995585D01*
G01X474781Y995591D02*
X474782Y995589D01*
G01X474783Y998735D02*
Y998729D01*
G01X474782Y998739D02*
X474783Y998735D01*
G01X474781Y998740D02*
X474782Y998739D01*
G01X474783Y1001885D02*
Y1001878D01*
G01X474782Y1001889D02*
X474783Y1001885D01*
G01X474781Y1001890D02*
X474782Y1001889D01*
G01X474783Y1005034D02*
Y1005028D01*
G01X474782Y1005038D02*
X474783Y1005034D01*
G01X474781Y1005039D02*
X474782Y1005038D01*
G01X474783Y1008184D02*
Y1008178D01*
G01X474782Y1008188D02*
X474783Y1008184D01*
G01X474781Y1008189D02*
X474782Y1008188D01*
G01X474744Y992470D02*
Y992467D01*
G01X474746Y992464D02*
X474744Y992470D01*
G01X474757Y992449D02*
X474746Y992464D01*
G01X474782Y992441D02*
X474757Y992449D01*
G01X474744Y995620D02*
Y995616D01*
G01X474746Y995614D02*
X474744Y995620D01*
G01X474757Y995599D02*
X474746Y995614D01*
G01X474781Y995591D02*
X474757Y995599D01*
G01X474744Y1001919D02*
Y1001915D01*
G01X474746Y1001913D02*
X474744Y1001919D01*
G01X474757Y1001898D02*
X474746Y1001913D01*
G01X474781Y1001890D02*
X474757Y1001898D01*
G01X474744Y1005069D02*
Y1005065D01*
G01X474746Y1005063D02*
X474744Y1005069D01*
G01X474757Y1005048D02*
X474746Y1005063D01*
G01X474781Y1005039D02*
X474757Y1005048D01*
G01X474744Y989321D02*
Y989317D01*
G01X474746Y989315D02*
X474744Y989321D01*
G01X474757Y989300D02*
X474746Y989315D01*
G01X474781Y989291D02*
X474757Y989300D01*
G01X474744Y1008219D02*
Y1008215D01*
G01X474746Y1008213D02*
X474744Y1008219D01*
G01X474757Y1008197D02*
X474746Y1008213D01*
G01X474781Y1008189D02*
X474757Y1008197D01*
G01X474744Y998770D02*
Y998766D01*
G01X474746Y998764D02*
X474744Y998770D01*
G01X474756Y998750D02*
X474746Y998764D01*
G01X474779Y998740D02*
X474756Y998750D01*
G01X475698Y990471D02*
X475707Y990467D01*
G01X475687Y990472D02*
X475698Y990471D01*
G01Y993620D02*
X475707Y993617D01*
G01X475687Y993622D02*
X475698Y993620D01*
G01Y996770D02*
X475707Y996766D01*
G01X475687Y996772D02*
X475698Y996770D01*
G01Y999920D02*
X475707Y999916D01*
G01X475687Y999921D02*
X475698Y999920D01*
G01Y1003069D02*
X475707Y1003065D01*
G01X475687Y1003071D02*
X475698Y1003069D01*
G01Y1006219D02*
X475707Y1006215D01*
G01X475687Y1006220D02*
X475698Y1006219D01*
G01X475706Y989283D02*
X475709Y989285D01*
G01X475703Y989282D02*
X475706Y989283D01*
G01X475700Y989281D02*
X475703Y989282D01*
G01X475696Y989281D02*
X475700D01*
G01X475693Y989280D02*
X475696Y989281D01*
G01X475689Y989280D02*
X475693D01*
G01X474767Y990480D02*
X474763Y990478D01*
G01X474770Y990481D02*
X474767Y990480D01*
G01X474773Y990482D02*
X474770Y990481D01*
G01X474776Y990483D02*
X474773Y990482D01*
G01X474780Y990483D02*
X474776D01*
G01X474783D02*
X474780D01*
G01X475706Y992433D02*
X475709Y992435D01*
G01X475703Y992432D02*
X475706Y992433D01*
G01X475700Y992431D02*
X475703Y992432D01*
G01X475696Y992430D02*
X475700Y992431D01*
G01X475693Y992430D02*
X475696D01*
G01X475689D02*
X475693D01*
G01X474767Y993630D02*
X474763Y993628D01*
G01X474770Y993631D02*
X474767Y993630D01*
G01X474773Y993632D02*
X474770Y993631D01*
G01X474776Y993633D02*
X474773Y993632D01*
G01X474780Y993633D02*
X474776D01*
G01X474783D02*
X474780D01*
G01X475706Y995583D02*
X475709Y995585D01*
G01X475703Y995581D02*
X475706Y995583D01*
G01X475700Y995581D02*
X475703D01*
G01X475696Y995580D02*
X475700Y995581D01*
G01X475693Y995580D02*
X475696D01*
G01X475689Y995579D02*
X475693Y995580D01*
G01X474767Y996779D02*
X474763Y996778D01*
G01X474770Y996780D02*
X474767Y996779D01*
G01X474773Y996781D02*
X474770Y996780D01*
G01X474776Y996782D02*
X474773Y996781D01*
G01X474780Y996783D02*
X474776Y996782D01*
G01X474783Y996783D02*
X474780D01*
G01X475706Y998732D02*
X475709Y998734D01*
G01X475703Y998731D02*
X475706Y998732D01*
G01X475700Y998730D02*
X475703Y998731D01*
G01X475696Y998730D02*
X475700D01*
G01X475693Y998729D02*
X475696Y998730D01*
G01X475689Y998729D02*
X475693D01*
G01X474767Y999929D02*
X474763Y999927D01*
G01X474770Y999930D02*
X474767Y999929D01*
G01X474773Y999931D02*
X474770Y999930D01*
G01X474776Y999932D02*
X474773Y999931D01*
G01X474780Y999932D02*
X474776D01*
G01X474783D02*
X474780D01*
G01X473997Y992480D02*
X473563D01*
G01X474370D02*
X473997D01*
G01Y998780D02*
X473563D01*
G01X474370D02*
X473997D01*
G01Y1001929D02*
X473563D01*
G01X474370D02*
X473997D01*
G01X475719Y990471D02*
X475723Y990465D01*
G01X475714Y990475D02*
X475719Y990471D01*
G01X475708Y990479D02*
X475714Y990475D01*
G01X475702Y990481D02*
X475708Y990479D01*
G01X475696Y990483D02*
X475702Y990481D01*
G01X475689Y990483D02*
X475696D01*
G01X475719Y993620D02*
X475723Y993615D01*
G01X475714Y993625D02*
X475719Y993620D01*
G01X475708Y993628D02*
X475714Y993625D01*
G01X475702Y993631D02*
X475708Y993628D01*
G01X475696Y993633D02*
X475702Y993631D01*
G01X475689Y993633D02*
X475696D01*
G01X475719Y996770D02*
X475723Y996765D01*
G01X475714Y996774D02*
X475719Y996770D01*
G01X475708Y996778D02*
X475714Y996774D01*
G01X475702Y996781D02*
X475708Y996778D01*
G01X475696Y996782D02*
X475702Y996781D01*
G01X475689Y996783D02*
X475696Y996782D01*
G01X475719Y999920D02*
X475723Y999914D01*
G01X475714Y999924D02*
X475719Y999920D01*
G01X475708Y999928D02*
X475714Y999924D01*
G01X475702Y999930D02*
X475708Y999928D01*
G01X475696Y999932D02*
X475702Y999930D01*
G01X475689Y999932D02*
X475696D01*
G01X475719Y1003069D02*
X475723Y1003064D01*
G01X475714Y1003074D02*
X475719Y1003069D01*
G01X475708Y1003077D02*
X475714Y1003074D01*
G01X475702Y1003080D02*
X475708Y1003077D01*
G01X475696Y1003081D02*
X475702Y1003080D01*
G01X475689Y1003082D02*
X475696Y1003081D01*
G01X475719Y1006219D02*
X475723Y1006213D01*
G01X475714Y1006223D02*
X475719Y1006219D01*
G01X475708Y1006227D02*
X475714Y1006223D01*
G01X475702Y1006230D02*
X475708Y1006227D01*
G01X475696Y1006231D02*
X475702Y1006230D01*
G01X475689Y1006231D02*
X475696D01*
G01X475719Y1009369D02*
X475723Y1009363D01*
G01X475714Y1009373D02*
X475719Y1009369D01*
G01X475708Y1009376D02*
X475714Y1009373D01*
G01X475702Y1009379D02*
X475708Y1009376D01*
G01X475696Y1009381D02*
X475702Y1009379D01*
G01X475689Y1009381D02*
X475696D01*
G01X474745Y989310D02*
X474744Y989317D01*
G01X474747Y989303D02*
X474745Y989310D01*
G01X474751Y989296D02*
X474747Y989303D01*
G01X474756Y989291D02*
X474751Y989296D01*
G01X474762Y989286D02*
X474756Y989291D01*
G01X474769Y989283D02*
X474762Y989286D01*
G01X474776Y989281D02*
X474769Y989283D01*
G01X474783Y989280D02*
X474776Y989281D01*
G01X474745Y992459D02*
X474744Y992467D01*
G01X474747Y992452D02*
X474745Y992459D01*
G01X474751Y992446D02*
X474747Y992452D01*
G01X474756Y992441D02*
X474751Y992446D01*
G01X474762Y992436D02*
X474756Y992441D01*
G01X474769Y992432D02*
X474762Y992436D01*
G01X474776Y992430D02*
X474769Y992432D01*
G01X474783Y992430D02*
X474776D01*
G01X474745Y995609D02*
X474744Y995616D01*
G01X474747Y995602D02*
X474745Y995609D01*
G01X474751Y995596D02*
X474747Y995602D01*
G01X474756Y995590D02*
X474751Y995596D01*
G01X474762Y995585D02*
X474756Y995590D01*
G01X474769Y995582D02*
X474762Y995585D01*
G01X474776Y995580D02*
X474769Y995582D01*
G01X474783Y995579D02*
X474776Y995580D01*
G01X474745Y998759D02*
X474744Y998766D01*
G01X474747Y998752D02*
X474745Y998759D01*
G01X474751Y998745D02*
X474747Y998752D01*
G01X474756Y998740D02*
X474751Y998745D01*
G01X474762Y998735D02*
X474756Y998740D01*
G01X474769Y998731D02*
X474762Y998735D01*
G01X474776Y998730D02*
X474769Y998731D01*
G01X474783Y998729D02*
X474776Y998730D01*
G01X474745Y1001908D02*
X474744Y1001915D01*
G01X474747Y1001901D02*
X474745Y1001908D01*
G01X474751Y1001895D02*
X474747Y1001901D01*
G01X474756Y1001889D02*
X474751Y1001895D01*
G01X474762Y1001885D02*
X474756Y1001889D01*
G01X474769Y1001881D02*
X474762Y1001885D01*
G01X474776Y1001879D02*
X474769Y1001881D01*
G01X474783Y1001878D02*
X474776Y1001879D01*
G01X474745Y1005058D02*
X474744Y1005065D01*
G01X474747Y1005051D02*
X474745Y1005058D01*
G01X474751Y1005044D02*
X474747Y1005051D01*
G01X474756Y1005039D02*
X474751Y1005044D01*
G01X474762Y1005034D02*
X474756Y1005039D01*
G01X474769Y1005031D02*
X474762Y1005034D01*
G01X474776Y1005029D02*
X474769Y1005031D01*
G01X474783Y1005028D02*
X474776Y1005029D01*
G01X474745Y1008207D02*
X474744Y1008215D01*
G01X474747Y1008200D02*
X474745Y1008207D01*
G01X474751Y1008194D02*
X474747Y1008200D01*
G01X474756Y1008189D02*
X474751Y1008194D01*
G01X474762Y1008184D02*
X474756Y1008189D01*
G01X474769Y1008180D02*
X474762Y1008184D01*
G01X474776Y1008178D02*
X474769Y1008180D01*
G01X474783Y1008178D02*
X474776D01*
G01X475698Y1009369D02*
X475707Y1009365D01*
G01X475687Y1009370D02*
X475698Y1009369D01*
G01X475728Y1005058D02*
Y1005065D01*
G01X475725Y1005051D02*
X475728Y1005058D01*
G01X475722Y1005044D02*
X475725Y1005051D01*
G01X475717Y1005039D02*
X475722Y1005044D01*
G01X475711Y1005034D02*
X475717Y1005039D01*
G01X475704Y1005031D02*
X475711Y1005034D01*
G01X475697Y1005029D02*
X475704Y1005031D01*
G01X475689Y1005028D02*
X475697Y1005029D01*
G01X475706Y1001882D02*
X475709Y1001884D01*
G01X475703Y1001881D02*
X475706Y1001882D01*
G01X475700Y1001880D02*
X475703Y1001881D01*
G01X475696Y1001879D02*
X475700Y1001880D01*
G01X475693Y1001879D02*
X475696D01*
G01X475689Y1001878D02*
X475693Y1001879D01*
G01X474767Y1003078D02*
X474763Y1003077D01*
G01X474770Y1003080D02*
X474767Y1003078D01*
G01X474773Y1003081D02*
X474770Y1003080D01*
G01X474776Y1003081D02*
X474773D01*
G01X474780Y1003082D02*
X474776Y1003081D01*
G01X474783Y1003082D02*
X474780D01*
G01X474767Y1006228D02*
X474763Y1006226D01*
G01X474770Y1006229D02*
X474767Y1006228D01*
G01X474773Y1006230D02*
X474770Y1006229D01*
G01X474776Y1006231D02*
X474773Y1006230D01*
G01X474780Y1006231D02*
X474776D01*
G01X474783D02*
X474780D01*
G01X475706Y1008181D02*
X475709Y1008183D01*
G01X475703Y1008180D02*
X475706Y1008181D01*
G01X475700Y1008179D02*
X475703Y1008180D01*
G01X475696Y1008178D02*
X475700Y1008179D01*
G01X475693Y1008178D02*
X475696D01*
G01X475689D02*
X475693D01*
G01X474767Y1009378D02*
X474763Y1009376D01*
G01X474770Y1009379D02*
X474767Y1009378D01*
G01X474773Y1009380D02*
X474770Y1009379D01*
G01X474776Y1009381D02*
X474773Y1009380D01*
G01X474780Y1009381D02*
X474776D01*
G01X474783D02*
X474780D01*
G01X474747Y990453D02*
X474742Y990433D01*
G01X474761Y990467D02*
X474747Y990453D01*
G01X474781Y990472D02*
X474761Y990467D01*
G01X474747Y993602D02*
X474742Y993583D01*
G01X474761Y993617D02*
X474747Y993602D01*
G01X474781Y993622D02*
X474761Y993617D01*
G01X474747Y996752D02*
X474742Y996732D01*
G01X474761Y996766D02*
X474747Y996752D01*
G01X474781Y996772D02*
X474761Y996766D01*
G01X474747Y999902D02*
X474742Y999882D01*
G01X474761Y999916D02*
X474747Y999902D01*
G01X474781Y999921D02*
X474761Y999916D01*
G01X474747Y1003051D02*
X474742Y1003031D01*
G01X474761Y1003065D02*
X474747Y1003051D01*
G01X474781Y1003071D02*
X474761Y1003065D01*
G01X474747Y1006201D02*
X474742Y1006181D01*
G01X474761Y1006215D02*
X474747Y1006201D01*
G01X474781Y1006220D02*
X474761Y1006215D01*
G01X474747Y1009350D02*
X474742Y1009331D01*
G01X474761Y1009365D02*
X474747Y1009350D01*
G01X474781Y1009370D02*
X474761Y1009365D01*
G01X475722Y989311D02*
X475727Y989331D01*
G01X475707Y989296D02*
X475722Y989311D01*
G01X475687Y989291D02*
X475707Y989296D01*
G01X475722Y992461D02*
X475727Y992480D01*
G01X475707Y992446D02*
X475722Y992461D01*
G01X475687Y992441D02*
X475707Y992446D01*
G01X475722Y995610D02*
X475727Y995630D01*
G01X475707Y995596D02*
X475722Y995610D01*
G01X475687Y995591D02*
X475707Y995596D01*
G01X475722Y998760D02*
X475727Y998780D01*
G01X475707Y998745D02*
X475722Y998760D01*
G01X475687Y998740D02*
X475707Y998745D01*
G01X475722Y1001909D02*
X475727Y1001929D01*
G01X475707Y1001895D02*
X475722Y1001909D01*
G01X475687Y1001890D02*
X475707Y1001895D01*
G01X475722Y1005059D02*
X475727Y1005079D01*
G01X475707Y1005044D02*
X475722Y1005059D01*
G01X475687Y1005039D02*
X475707Y1005044D01*
G01X475722Y1008209D02*
X475727Y1008228D01*
G01X475707Y1008194D02*
X475722Y1008209D01*
G01X475687Y1008189D02*
X475707Y1008194D01*
G01X474631Y1008228D02*
X474743Y1008220D01*
G01X474742Y998775D02*
X474631Y998780D01*
G01X474742Y992477D02*
X474631Y992480D01*
G01X474742Y1001926D02*
X474631Y1001929D01*
G01X476181Y1011535D02*
X472835D01*
G01X475689Y1009567D02*
X474783D01*
G01X475728Y1009528D02*
X474744D01*
G01X475687Y1009370D02*
X469803D01*
G01Y1009331D02*
X475727D01*
G01Y1008228D02*
X469803D01*
G01X475687Y1008189D02*
X469803D01*
G01X474744Y1008031D02*
X475728D01*
G01X474783Y1007992D02*
X475689D01*
G01Y1006417D02*
X474783D01*
G01X475728Y1006378D02*
X474744D01*
G01X475687Y1006220D02*
X469803D01*
G01Y1006181D02*
X475727D01*
G01Y1005079D02*
X469803D01*
G01X475687Y1005039D02*
X469803D01*
G01X474744Y1004882D02*
X475728D01*
G01X474783Y1004843D02*
X475689D01*
G01Y1003268D02*
X474783D01*
G01X475728Y1003228D02*
X474744D01*
G01X475687Y1003071D02*
X469803D01*
G01Y1003031D02*
X475727D01*
G01Y1001929D02*
X469803D01*
G01X475687Y1001890D02*
X469803D01*
G01X474744Y1001732D02*
X475728D01*
G01X474783Y1001693D02*
X475689D01*
G01Y1000118D02*
X474783D01*
G01X475728Y1000079D02*
X474744D01*
G01X475687Y999921D02*
X469803D01*
G01Y999882D02*
X475727D01*
G01Y998780D02*
X469803D01*
G01X475687Y998740D02*
X469803D01*
G01X474744Y998583D02*
X475728D01*
G01X474783Y998543D02*
X475689D01*
G01Y996969D02*
X474783D01*
G01X475728Y996929D02*
X474744D01*
G01X475687Y996772D02*
X469803D01*
G01Y996732D02*
X475727D01*
G01Y995630D02*
X469803D01*
G01X475687Y995591D02*
X469803D01*
G01X474744Y995433D02*
X475728D01*
G01X474783Y995394D02*
X475689D01*
G01Y993819D02*
X474783D01*
G01X475728Y993780D02*
X474744D01*
G01X475687Y993622D02*
X469803D01*
G01Y993583D02*
X475727D01*
G01Y992480D02*
X469803D01*
G01X475687Y992441D02*
X469803D01*
G01X474744Y992283D02*
X475728D01*
G01X474783Y992244D02*
X475689D01*
G01Y990669D02*
X474783D01*
G01X475728Y990630D02*
X474744D01*
G01X475687Y990472D02*
X469803D01*
G01Y990433D02*
X475727D01*
G01Y989331D02*
X469803D01*
G01X475687Y989291D02*
X469803D01*
G01X474744Y989134D02*
X475728D01*
G01X474783Y989094D02*
X475689D01*
G01X476181Y987126D02*
X472835D01*
G01X484646Y953012D02*
X479134D01*
G01X475687Y1005039D02*
X475691Y1005028D01*
G01X475728Y990435D02*
Y990446D01*
G01Y993585D02*
Y993596D01*
G01Y996734D02*
Y996746D01*
G01Y999884D02*
Y999895D01*
G01Y1003033D02*
Y1003045D01*
G01Y1006183D02*
Y1006194D01*
G01Y1009333D02*
Y1009344D01*
G01X479134Y953012D02*
Y1085650D01*
G01X476181Y1090571D02*
Y1011535D01*
G01X475728Y1008031D02*
Y1009528D01*
G01Y1004881D02*
Y1006378D01*
G01Y1001732D02*
Y1003228D01*
G01Y998582D02*
Y1000079D01*
G01Y995433D02*
Y996929D01*
G01Y992283D02*
Y993780D01*
G01Y989133D02*
Y990630D01*
G01X475689Y989280D02*
Y989133D01*
G01Y990630D02*
Y990483D01*
G01Y995579D02*
Y995432D01*
G01Y992430D02*
Y992283D01*
G01Y993780D02*
Y993633D01*
G01Y998729D02*
Y998582D01*
G01Y1000079D02*
Y999932D01*
G01Y996930D02*
Y996783D01*
G01Y1001878D02*
Y1001731D01*
G01Y1003229D02*
Y1003082D01*
G01Y1008178D02*
Y1008031D01*
G01Y1009528D02*
Y1009381D01*
G01Y1005028D02*
Y1004881D01*
G01Y1006378D02*
Y1006231D01*
G01X474783Y1008031D02*
Y1008178D01*
G01Y1009381D02*
Y1009528D01*
G01Y1004881D02*
Y1005028D01*
G01Y1006231D02*
Y1006378D01*
G01Y1001731D02*
Y1001878D01*
G01Y1003082D02*
Y1003229D01*
G01Y998582D02*
Y998729D01*
G01Y999932D02*
Y1000079D01*
G01Y996783D02*
Y996930D01*
G01Y995432D02*
Y995579D01*
G01Y992283D02*
Y992430D01*
G01Y993633D02*
Y993780D01*
G01Y989133D02*
Y989280D01*
G01Y990483D02*
Y990630D01*
G01X474744D02*
Y989134D01*
G01Y993780D02*
Y992283D01*
G01Y1000079D02*
Y998583D01*
G01Y996929D02*
Y995433D01*
G01Y1003228D02*
Y1001732D01*
G01Y1009528D02*
Y1008031D01*
G01Y1006378D02*
Y1004882D01*
G01X473563Y990472D02*
Y989291D01*
G01Y996772D02*
Y995591D01*
G01Y993622D02*
Y992441D01*
G01Y999921D02*
Y998740D01*
G01Y1003071D02*
Y1001890D01*
G01Y1009370D02*
Y1008189D01*
G01Y1006220D02*
Y1005039D01*
G01X473228Y1011535D02*
Y987126D01*
G01X472835D02*
Y1011535D01*
G01X469803Y1008189D02*
Y1009370D01*
G01Y1005039D02*
Y1006220D01*
G01Y1001890D02*
Y1003071D01*
G01Y998740D02*
Y999921D01*
G01Y995591D02*
Y996772D01*
G01Y992441D02*
Y993622D01*
G01Y989291D02*
Y990472D01*
G01X475728Y1008215D02*
Y1008226D01*
G01Y1005065D02*
Y1005076D01*
G01Y1001916D02*
Y1001926D01*
G01Y998766D02*
Y998777D01*
G01Y995617D02*
Y995627D01*
G01Y992467D02*
Y992478D01*
G01Y989317D02*
Y989328D01*
G01X480315Y1108602D02*
G03X479724Y1108012I0J-591D01*
G01X481102Y1098917D02*
G03X479921Y1097736I0J-1181D01*
G01X474803Y1109390D02*
G03X472835Y1107421I1J-1969D01*
G01X492520Y1109390D02*
X474803D01*
G01X487008Y1108602D02*
X480315D01*
G01X487598Y1103484D02*
X479724D01*
G01Y1101909D02*
X487598D01*
G01X494488Y1098957D02*
X472835D01*
G01X481102Y1098917D02*
X486220D01*
G01X476181Y1090571D02*
X490551D01*
G01X476181Y1089193D02*
X479921D01*
G01X476181Y1088327D02*
X491142D01*
G01X477953Y1086831D02*
X485827D01*
G01X479134Y1085650D02*
X484646D01*
G01X477953Y1086831D02*
X479134Y1085650D01*
G01X472835Y1091673D02*
X476181Y1088327D01*
G01X482480Y1094232D02*
X480170Y1098461D01*
G01X479921Y1089193D02*
Y1097736D01*
G01X479724Y1101909D02*
Y1108012D01*
G01X472835Y1107421D02*
Y1091673D01*
G01X481177Y1090571D02*
X482480Y1092539D01*
G01X389213Y1183355D02*
G03X396138Y1170224I37662J11471D01*
G01X389213Y1183355D02*
G03X396138Y1170224I37662J11470D01*
G01X422953Y1333028D02*
X424980D01*
G01X392953D02*
X394980D01*
G01X415118D02*
X413091D01*
G01X394980Y1332755D02*
X393012D01*
G01X415059D02*
X413091D01*
G01X424980D02*
X423012D01*
G01X394980Y1331059D02*
X392953D01*
G01X415118D02*
X413091D01*
G01X424980D02*
X422953D01*
G01X423012Y1328070D02*
X424980D01*
G01X413091D02*
X415059D01*
G01X393012D02*
X394980D01*
G01Y1323972D02*
X392953D01*
G01X415118D02*
X413091D01*
G01X424980D02*
X422953D01*
G01X394980Y1322794D02*
X393012D01*
G01X415059D02*
X413091D01*
G01X424980D02*
X423012D01*
G01X422953Y1321790D02*
X424980D01*
G01X413091D02*
X415118D01*
G01X392953D02*
X394980D01*
G01X422953Y1319606D02*
X415118D01*
G01X423012Y1318109D02*
X424980D01*
G01X413091D02*
X415059D01*
G01X393012D02*
X394980D01*
G01X409035Y1311456D02*
X429035D01*
G01X409035Y1310275D02*
X399035D01*
G01X424980Y1333028D02*
Y1342716D01*
G01Y1318109D02*
Y1332755D01*
G01X423012Y1322794D02*
Y1318109D01*
G01Y1332755D02*
Y1328070D01*
G01X422953Y1319606D02*
Y1357086D01*
G01X415118D02*
Y1319606D01*
G01X415059Y1328070D02*
Y1332755D01*
G01Y1318109D02*
Y1322794D01*
G01X413091Y1333028D02*
Y1342716D01*
G01Y1318109D02*
Y1332755D01*
G01X409035Y1310275D02*
Y1311456D01*
G01X399035D02*
Y1310275D01*
G01X394980Y1333028D02*
Y1342716D01*
G01Y1318109D02*
Y1332755D01*
G01X393012Y1322794D02*
Y1318109D01*
G01Y1332755D02*
Y1328070D01*
G01X392953Y1319606D02*
Y1357086D01*
G01X452953Y1333028D02*
X454980D01*
G01X445118D02*
X443091D01*
G01X475118D02*
X473091D01*
G01X445059Y1332755D02*
X443091D01*
G01X454980D02*
X453012D01*
G01X475059D02*
X473091D01*
G01X445118Y1331059D02*
X443091D01*
G01X454980D02*
X452953D01*
G01X475118D02*
X473091D01*
G01Y1328070D02*
X475059D01*
G01X453012D02*
X454980D01*
G01X443091D02*
X445059D01*
G01X445118Y1323972D02*
X443091D01*
G01X454980D02*
X452953D01*
G01X475118D02*
X473091D01*
G01X445059Y1322794D02*
X443091D01*
G01X454980D02*
X453012D01*
G01X475059D02*
X473091D01*
G01Y1321790D02*
X475118D01*
G01X452953D02*
X454980D01*
G01X443091D02*
X445118D01*
G01X452953Y1319606D02*
X445118D01*
G01X482953D02*
X475118D01*
G01X473091Y1318109D02*
X475059D01*
G01X453012D02*
X454980D01*
G01X443091D02*
X445059D01*
G01X469035Y1311456D02*
X489035D01*
G01X439035D02*
X459035D01*
G01X439035Y1310275D02*
X429035D01*
G01X469035D02*
X459035D01*
G01X475118Y1357086D02*
Y1319606D01*
G01X475059Y1328070D02*
Y1332755D01*
G01Y1318109D02*
Y1322794D01*
G01X473091Y1333028D02*
Y1342716D01*
G01Y1318109D02*
Y1332755D01*
G01X469035Y1310275D02*
Y1311456D01*
G01X459035D02*
Y1310275D01*
G01X454980Y1333028D02*
Y1342716D01*
G01Y1318109D02*
Y1332755D01*
G01X453012Y1322794D02*
Y1318109D01*
G01Y1332755D02*
Y1328070D01*
G01X452953Y1319606D02*
Y1357086D01*
G01X445118D02*
Y1319606D01*
G01X445059Y1328070D02*
Y1332755D01*
G01Y1318109D02*
Y1322794D01*
G01X443091Y1333028D02*
Y1342716D01*
G01Y1318109D02*
Y1332755D01*
G01X439035Y1310275D02*
Y1311456D01*
G01X429035D02*
Y1310275D01*
G01X409035Y1360669D02*
X399035D01*
G01X409035Y1360472D02*
X429035D01*
G01X415118Y1357086D02*
X422953D01*
G01X394980Y1352676D02*
X393012D01*
G01X415059D02*
X413091D01*
G01X424980D02*
X423012D01*
G01X422953Y1352336D02*
X424980D01*
G01X413091D02*
X415118D01*
G01X392953D02*
X394980D01*
G01Y1350154D02*
X392953D01*
G01X415118D02*
X413091D01*
G01X424980D02*
X422953D01*
G01X423012Y1347991D02*
X424980D01*
G01X413091D02*
X415059D01*
G01X393012D02*
X394980D01*
G01X422953Y1343028D02*
X424980D01*
G01X392953D02*
X394980D01*
G01X415118D02*
X413091D01*
G01X394980Y1342716D02*
X393012D01*
G01X415059D02*
X413091D01*
G01X424980D02*
X423012D01*
G01X394980Y1341059D02*
X392953D01*
G01X415118D02*
X413091D01*
G01X424980D02*
X422953D01*
G01X423012Y1338031D02*
X424980D01*
G01X413091D02*
X415059D01*
G01X393012D02*
X394980D01*
G01X424980Y1343028D02*
Y1352676D01*
G01X423012Y1342716D02*
Y1338031D01*
G01Y1352676D02*
Y1347991D01*
G01X415059D02*
Y1352676D01*
G01Y1338031D02*
Y1342716D01*
G01X413091Y1343028D02*
Y1352676D01*
G01X409035Y1360472D02*
Y1360669D01*
G01X399035D02*
Y1360472D01*
G01X394980Y1343028D02*
Y1352676D01*
G01X393012Y1342716D02*
Y1338031D01*
G01Y1352676D02*
Y1347991D01*
G01X439035Y1360669D02*
X429035D01*
G01X469035D02*
X459035D01*
G01X469035Y1360472D02*
X489035D01*
G01X439035D02*
X459035D01*
G01X475118Y1357086D02*
X482953D01*
G01X445118D02*
X452953D01*
G01X445059Y1352676D02*
X443091D01*
G01X454980D02*
X453012D01*
G01X475059D02*
X473091D01*
G01Y1352336D02*
X475118D01*
G01X452953D02*
X454980D01*
G01X443091D02*
X445118D01*
G01Y1350154D02*
X443091D01*
G01X454980D02*
X452953D01*
G01X475118D02*
X473091D01*
G01Y1347991D02*
X475059D01*
G01X453012D02*
X454980D01*
G01X443091D02*
X445059D01*
G01X452953Y1343028D02*
X454980D01*
G01X445118D02*
X443091D01*
G01X475118D02*
X473091D01*
G01X445059Y1342716D02*
X443091D01*
G01X454980D02*
X453012D01*
G01X475059D02*
X473091D01*
G01X445118Y1341059D02*
X443091D01*
G01X454980D02*
X452953D01*
G01X475118D02*
X473091D01*
G01Y1338031D02*
X475059D01*
G01X453012D02*
X454980D01*
G01X443091D02*
X445059D01*
G01X475059Y1347991D02*
Y1352676D01*
G01Y1338031D02*
Y1342716D01*
G01X473091Y1343028D02*
Y1352676D01*
G01X469035Y1360472D02*
Y1360669D01*
G01X459035D02*
Y1360472D01*
G01X454980Y1343028D02*
Y1352676D01*
G01X453012Y1342716D02*
Y1338031D01*
G01Y1352676D02*
Y1347991D01*
G01X445059D02*
Y1352676D01*
G01Y1338031D02*
Y1342716D01*
G01X443091Y1343028D02*
Y1352676D01*
G01X439035Y1360472D02*
Y1360669D01*
G01X429035D02*
Y1360472D01*
G01X477559Y1503937D02*
G03Y1496063I0J-3937D01*
G01X459449D02*
G03Y1503937I0J3937D01*
G01X489370D02*
X477559D01*
G01D02*
G03Y1496063I0J-3937D01*
G01X459449D02*
G03Y1503937I0J3937D01*
G01X395048Y1511515D02*
G03I-4291J0D01*
G01D02*
G03I-4291J0D01*
G01X489370Y1503937D02*
X477559D01*
G01X478266Y1808346D02*
Y1789409D01*
G01X489141Y51999D02*
X489152Y51984D01*
G01X489117Y52008D02*
X489141Y51999D01*
G01Y56999D02*
X489152Y56984D01*
G01X489117Y57008D02*
X489141Y56999D01*
G01Y61999D02*
X489152Y61984D01*
G01X489117Y62008D02*
X489141Y61999D01*
G01Y66999D02*
X489152Y66984D01*
G01X489117Y67008D02*
X489141Y66999D01*
G01Y71999D02*
X489152Y71984D01*
G01X489117Y72008D02*
X489141Y71999D01*
G01X489154Y51975D02*
Y51982D01*
G01X489155Y51970D02*
X489154Y51975D01*
G01X489156Y51969D02*
X489155Y51970D01*
G01X489141Y76999D02*
X489152Y76984D01*
G01X489117Y77008D02*
X489141Y76999D01*
G01Y81999D02*
X489152Y81984D01*
G01X489117Y82008D02*
X489141Y81999D01*
G01X489154Y56975D02*
Y56982D01*
G01X489155Y56970D02*
X489154Y56975D01*
G01X489156Y56969D02*
X489155Y56970D01*
G01X489154Y61975D02*
Y61982D01*
G01X489155Y61970D02*
X489154Y61975D01*
G01X489156Y61969D02*
X489155Y61970D01*
G01X489154Y66975D02*
Y66982D01*
G01X489155Y66970D02*
X489154Y66975D01*
G01X489156Y66969D02*
X489155Y66970D01*
G01X489154Y71975D02*
Y71982D01*
G01X489155Y71970D02*
X489154Y71975D01*
G01X489156Y71969D02*
X489155Y71970D01*
G01X489154Y76975D02*
Y76982D01*
G01X489155Y76970D02*
X489154Y76975D01*
G01X489156Y76969D02*
X489155Y76970D01*
G01X489154Y81975D02*
Y81982D01*
G01X489155Y81970D02*
X489154Y81975D01*
G01X489156Y81969D02*
X489155Y81970D01*
G01X488169Y52015D02*
Y52024D01*
G01X488170Y52009D02*
X488169Y52015D01*
G01X488171Y52008D02*
X488170Y52009D01*
G01X488169Y57015D02*
Y57024D01*
G01X488170Y57009D02*
X488169Y57015D01*
G01X488171Y57008D02*
X488170Y57009D01*
G01X488169Y62015D02*
Y62024D01*
G01X488170Y62009D02*
X488169Y62015D01*
G01X488171Y62008D02*
X488170Y62009D01*
G01X488169Y67015D02*
Y67024D01*
G01X488170Y67009D02*
X488169Y67015D01*
G01X488171Y67008D02*
X488170Y67009D01*
G01X488169Y72015D02*
Y72024D01*
G01X488170Y72009D02*
X488169Y72015D01*
G01X488171Y72008D02*
X488170Y72009D01*
G01X488169Y77015D02*
Y77024D01*
G01X488170Y77009D02*
X488169Y77015D01*
G01X488171Y77008D02*
X488170Y77009D01*
G01X488169Y82015D02*
Y82024D01*
G01X488170Y82009D02*
X488169Y82015D01*
G01X488171Y82008D02*
X488170Y82009D01*
G01X489146Y52152D02*
X489154Y52125D01*
G01X489136Y52178D02*
X489146Y52152D01*
G01X489124Y52205D02*
X489136Y52178D01*
G01X489146Y57152D02*
X489154Y57125D01*
G01X489136Y57178D02*
X489146Y57152D01*
G01X489124Y57205D02*
X489136Y57178D01*
G01X489146Y62152D02*
X489154Y62125D01*
G01X489136Y62178D02*
X489146Y62152D01*
G01X489124Y62205D02*
X489136Y62178D01*
G01X489146Y67152D02*
X489154Y67125D01*
G01X489136Y67178D02*
X489146Y67152D01*
G01X489124Y67205D02*
X489136Y67178D01*
G01X489146Y72152D02*
X489154Y72125D01*
G01X489136Y72178D02*
X489146Y72152D01*
G01X489124Y72205D02*
X489136Y72178D01*
G01X489146Y77152D02*
X489154Y77125D01*
G01X489136Y77178D02*
X489146Y77152D01*
G01X489124Y77205D02*
X489136Y77178D01*
G01X489146Y82152D02*
X489154Y82125D01*
G01X489136Y82178D02*
X489146Y82152D01*
G01X489124Y82205D02*
X489136Y82178D01*
G01Y52003D02*
X489117Y52008D01*
G01X489151Y51988D02*
X489136Y52003D01*
G01X489156Y51969D02*
X489151Y51988D01*
G01X489136Y57003D02*
X489117Y57008D01*
G01X489151Y56988D02*
X489136Y57003D01*
G01X489156Y56969D02*
X489151Y56988D01*
G01X489136Y62003D02*
X489117Y62008D01*
G01X489151Y61988D02*
X489136Y62003D01*
G01X489156Y61969D02*
X489151Y61988D01*
G01X489136Y67003D02*
X489117Y67008D01*
G01X489151Y66988D02*
X489136Y67003D01*
G01X489156Y66969D02*
X489151Y66988D01*
G01X489136Y72003D02*
X489117Y72008D01*
G01X489151Y71988D02*
X489136Y72003D01*
G01X489156Y71969D02*
X489151Y71988D01*
G01X489136Y77003D02*
X489117Y77008D01*
G01X489151Y76988D02*
X489136Y77003D01*
G01X489156Y76969D02*
X489151Y76988D01*
G01X489136Y82003D02*
X489117Y82008D01*
G01X489151Y81988D02*
X489136Y82003D01*
G01X489156Y81969D02*
X489151Y81988D01*
G01X489120Y52106D02*
X489124Y52205D01*
G01X489115Y52034D02*
X489120Y52106D01*
G01X489117Y52008D02*
X489115Y52034D01*
G01X489120Y57106D02*
X489124Y57205D01*
G01X489115Y57034D02*
X489120Y57106D01*
G01X489117Y57008D02*
X489115Y57034D01*
G01X489120Y62106D02*
X489124Y62205D01*
G01X489115Y62034D02*
X489120Y62106D01*
G01X489117Y62008D02*
X489115Y62034D01*
G01X489120Y67106D02*
X489124Y67205D01*
G01X489115Y67034D02*
X489120Y67106D01*
G01X489117Y67008D02*
X489115Y67034D01*
G01X489120Y72106D02*
X489124Y72205D01*
G01X489115Y72034D02*
X489120Y72106D01*
G01X489117Y72008D02*
X489115Y72034D01*
G01X489120Y77106D02*
X489124Y77205D01*
G01X489115Y77034D02*
X489120Y77106D01*
G01X489117Y77008D02*
X489115Y77034D01*
G01X489120Y82106D02*
X489124Y82205D01*
G01X489115Y82034D02*
X489120Y82106D01*
G01X489117Y82008D02*
X489115Y82034D01*
G01X488170Y80628D02*
X488171Y80630D01*
G01X488169Y80622D02*
X488170Y80628D01*
G01X488169Y80614D02*
Y80622D01*
G01X488170Y75628D02*
X488171Y75630D01*
G01X488169Y75622D02*
X488170Y75628D01*
G01X488169Y75614D02*
Y75622D01*
G01X488170Y70628D02*
X488171Y70630D01*
G01X488169Y70622D02*
X488170Y70628D01*
G01X488169Y70614D02*
Y70622D01*
G01X488170Y65628D02*
X488171Y65630D01*
G01X488169Y65622D02*
X488170Y65628D01*
G01X488169Y65614D02*
Y65622D01*
G01X488170Y60628D02*
X488171Y60630D01*
G01X488169Y60622D02*
X488170Y60628D01*
G01X488169Y60614D02*
Y60622D01*
G01X488170Y55628D02*
X488171Y55630D01*
G01X488169Y55622D02*
X488170Y55628D01*
G01X488169Y55614D02*
Y55622D01*
G01X488170Y50628D02*
X488171Y50630D01*
G01X488169Y50622D02*
X488170Y50628D01*
G01X488169Y50614D02*
Y50622D01*
G01X489154Y80622D02*
Y80613D01*
G01X489155Y80628D02*
X489154Y80622D01*
G01X489156Y80630D02*
X489155Y80628D01*
G01X489154Y75622D02*
Y75613D01*
G01X489155Y75628D02*
X489154Y75622D01*
G01X489156Y75630D02*
X489155Y75628D01*
G01X489154Y70622D02*
Y70613D01*
G01X489155Y70628D02*
X489154Y70622D01*
G01X489156Y70630D02*
X489155Y70628D01*
G01X489154Y65622D02*
Y65613D01*
G01X489155Y65628D02*
X489154Y65622D01*
G01X489156Y65630D02*
X489155Y65628D01*
G01X489154Y60622D02*
Y60613D01*
G01X489155Y60628D02*
X489154Y60622D01*
G01X489156Y60630D02*
X489155Y60628D01*
G01X489154Y55622D02*
Y55613D01*
G01X489155Y55628D02*
X489154Y55622D01*
G01X489156Y55630D02*
X489155Y55628D01*
G01X489154Y50622D02*
Y50613D01*
G01X489155Y50628D02*
X489154Y50622D01*
G01X489156Y50630D02*
X489155Y50628D01*
G01X487008Y24547D02*
G03X487598Y25138I0J590D01*
G01X484843Y26319D02*
G03Y28287I0J984D01*
G01X484764Y39508D02*
G03I-1103J0D01*
G01X486220Y34232D02*
G03X487402Y35413I1J1181D01*
G01X485236Y39508D02*
G03I-1575J0D01*
G01X492520Y23760D02*
G03X494488Y25728I0J1968D01*
G01X482480Y28287D02*
G03Y26319I0J-984D01*
G01X486146Y42579D02*
X484843Y40610D01*
G01X489154Y51982D02*
Y51991D01*
G01Y56982D02*
Y56991D01*
G01Y61982D02*
Y61991D01*
G01Y66982D02*
Y66991D01*
G01Y71982D02*
Y71991D01*
G01Y76982D02*
Y76991D01*
G01Y81982D02*
Y81991D01*
G01X494488Y25728D02*
Y41476D01*
G01X493504Y80630D02*
Y82008D01*
G01Y75630D02*
Y77008D01*
G01Y70630D02*
Y72008D01*
G01Y65630D02*
Y67008D01*
G01Y60630D02*
Y62008D01*
G01Y55630D02*
Y57008D01*
G01Y50630D02*
Y52008D01*
G01X491142Y182815D02*
Y44823D01*
G01X490551Y185059D02*
Y42579D01*
G01X490335Y52008D02*
Y50630D01*
G01Y57008D02*
Y55630D01*
G01Y62008D02*
Y60630D01*
G01Y67008D02*
Y65630D01*
G01Y72008D02*
Y70630D01*
G01Y77008D02*
Y75630D01*
G01Y82008D02*
Y80630D01*
G01X489764Y104862D02*
Y82776D01*
G01X489154Y51982D02*
Y52125D01*
G01Y56982D02*
Y57125D01*
G01Y61982D02*
Y62125D01*
G01Y66982D02*
Y67125D01*
G01Y71982D02*
Y72125D01*
G01Y76982D02*
Y77125D01*
G01Y81982D02*
Y82125D01*
G01Y80138D02*
Y82500D01*
G01Y75138D02*
Y77500D01*
G01Y70138D02*
Y72500D01*
G01Y65138D02*
Y67500D01*
G01Y60138D02*
Y62500D01*
G01Y55138D02*
Y57500D01*
G01Y50138D02*
Y52500D01*
G01X488583Y103681D02*
Y83957D01*
G01X488169Y52500D02*
Y50138D01*
G01Y57500D02*
Y55138D01*
G01Y62500D02*
Y60138D01*
G01Y67500D02*
Y65138D01*
G01Y72500D02*
Y70138D01*
G01Y77500D02*
Y75138D01*
G01Y82500D02*
Y80138D01*
G01X487598Y31240D02*
Y25138D01*
G01X487402Y43957D02*
Y35413D01*
G01X485827Y82776D02*
Y46319D01*
G01X484843Y40610D02*
Y38917D01*
G01X484646Y83957D02*
Y47500D01*
G01X482480Y38917D02*
Y40610D01*
G01X488583Y83957D02*
X484646D01*
G01X489764Y82776D02*
X485827D01*
G01X489154Y82500D02*
X488169D01*
G01X488171Y82008D02*
X493504D01*
G01Y81969D02*
X489156D01*
G01X493504Y80630D02*
X488171D01*
G01X488169Y80138D02*
X489154D01*
G01Y77500D02*
X488169D01*
G01X488171Y77008D02*
X493504D01*
G01Y76969D02*
X489156D01*
G01X493504Y75630D02*
X488171D01*
G01X488169Y75138D02*
X489154D01*
G01Y72500D02*
X488169D01*
G01X488171Y72008D02*
X493504D01*
G01Y71969D02*
X489156D01*
G01X493504Y70630D02*
X488171D01*
G01X488169Y70138D02*
X489154D01*
G01Y67500D02*
X488169D01*
G01X488171Y67008D02*
X493504D01*
G01Y66969D02*
X489156D01*
G01X493504Y65630D02*
X488171D01*
G01X488169Y65138D02*
X489154D01*
G01Y62500D02*
X488169D01*
G01X488171Y62008D02*
X493504D01*
G01Y61969D02*
X489156D01*
G01X493504Y60630D02*
X488171D01*
G01X488169Y60138D02*
X489154D01*
G01Y57500D02*
X488169D01*
G01X488171Y57008D02*
X493504D01*
G01Y56969D02*
X489156D01*
G01X493504Y55630D02*
X488171D01*
G01X488169Y55138D02*
X489154D01*
G01Y52500D02*
X488169D01*
G01X488171Y52008D02*
X493504D01*
G01Y51969D02*
X489156D01*
G01X493504Y50630D02*
X488171D01*
G01X488169Y50138D02*
X489154D01*
G01X487402Y43957D02*
X490551D01*
G01X484843Y40610D02*
X482480D01*
G01X484843Y38917D02*
X482480D01*
G01X488169Y82204D02*
X489124Y82205D01*
G01X489154Y80434D02*
X488169Y80433D01*
G01Y77204D02*
X489124Y77205D01*
G01X489154Y75434D02*
X488169Y75433D01*
G01Y72204D02*
X489124Y72205D01*
G01X489154Y70434D02*
X488169Y70433D01*
G01Y67204D02*
X489124Y67205D01*
G01X489154Y65434D02*
X488169Y65433D01*
G01Y62204D02*
X489124Y62205D01*
G01X489154Y60434D02*
X488169Y60433D01*
G01Y57204D02*
X489124Y57205D01*
G01X489154Y55434D02*
X488169Y55433D01*
G01Y52204D02*
X489124Y52205D01*
G01X489154Y50434D02*
X488169Y50433D01*
G01X484843Y38917D02*
X487153Y34688D01*
G01X484843Y28287D02*
X482480D01*
G01Y26319D02*
X484843D01*
G01X488583Y83957D02*
X489764Y82776D01*
G01X484646Y83957D02*
X485827Y82776D01*
G01X491142Y44823D02*
X494488Y41476D01*
G01X484646Y47500D02*
X485827Y46319D01*
G01X489141Y106999D02*
X489152Y106984D01*
G01X489117Y107008D02*
X489141Y106999D01*
G01Y111999D02*
X489152Y111984D01*
G01X489117Y112008D02*
X489141Y111999D01*
G01Y116999D02*
X489152Y116984D01*
G01X489117Y117008D02*
X489141Y116999D01*
G01Y121999D02*
X489152Y121984D01*
G01X489117Y122008D02*
X489141Y121999D01*
G01Y126999D02*
X489152Y126984D01*
G01X489117Y127008D02*
X489141Y126999D01*
G01Y131999D02*
X489152Y131984D01*
G01X489117Y132008D02*
X489141Y131999D01*
G01Y136999D02*
X489152Y136984D01*
G01X489117Y137008D02*
X489141Y136999D01*
G01Y141999D02*
X489152Y141984D01*
G01X489117Y142008D02*
X489141Y141999D01*
G01Y146999D02*
X489152Y146984D01*
G01X489117Y147008D02*
X489141Y146999D01*
G01Y151999D02*
X489152Y151984D01*
G01X489117Y152008D02*
X489141Y151999D01*
G01Y156999D02*
X489152Y156984D01*
G01X489117Y157008D02*
X489141Y156999D01*
G01X489154Y106975D02*
Y106982D01*
G01X489155Y106970D02*
X489154Y106975D01*
G01X489156Y106969D02*
X489155Y106970D01*
G01X489154Y111975D02*
Y111982D01*
G01X489155Y111970D02*
X489154Y111975D01*
G01X489156Y111969D02*
X489155Y111970D01*
G01X489154Y116975D02*
Y116982D01*
G01X489155Y116970D02*
X489154Y116975D01*
G01X489156Y116969D02*
X489155Y116970D01*
G01X489154Y121975D02*
Y121982D01*
G01X489155Y121970D02*
X489154Y121975D01*
G01X489156Y121969D02*
X489155Y121970D01*
G01X489154Y126975D02*
Y126982D01*
G01X489155Y126970D02*
X489154Y126975D01*
G01X489156Y126969D02*
X489155Y126970D01*
G01X489154Y131975D02*
Y131982D01*
G01X489155Y131970D02*
X489154Y131975D01*
G01X489156Y131969D02*
X489155Y131970D01*
G01X489154Y136975D02*
Y136982D01*
G01X489155Y136970D02*
X489154Y136975D01*
G01X489156Y136969D02*
X489155Y136970D01*
G01X489154Y141975D02*
Y141982D01*
G01X489155Y141970D02*
X489154Y141975D01*
G01X489156Y141969D02*
X489155Y141970D01*
G01X489154Y146975D02*
Y146982D01*
G01X489155Y146970D02*
X489154Y146975D01*
G01X489156Y146969D02*
X489155Y146970D01*
G01X489154Y151975D02*
Y151982D01*
G01X489155Y151970D02*
X489154Y151975D01*
G01X489156Y151969D02*
X489155Y151970D01*
G01X489154Y156975D02*
Y156982D01*
G01X489155Y156970D02*
X489154Y156975D01*
G01X489156Y156969D02*
X489155Y156970D01*
G01X489154Y161975D02*
Y161982D01*
G01X489155Y161970D02*
X489154Y161975D01*
G01X489156Y161969D02*
X489155Y161970D01*
G01X489154Y166975D02*
Y166982D01*
G01X489155Y166970D02*
X489154Y166975D01*
G01X489156Y166969D02*
X489155Y166970D01*
G01X489154Y171975D02*
Y171982D01*
G01X489155Y171970D02*
X489154Y171975D01*
G01X489156Y171969D02*
X489155Y171970D01*
G01X489154Y176975D02*
Y176982D01*
G01X489155Y176970D02*
X489154Y176975D01*
G01X489156Y176969D02*
X489155Y176970D01*
G01X489141Y161999D02*
X489152Y161984D01*
G01X489117Y162008D02*
X489141Y161999D01*
G01Y166999D02*
X489152Y166984D01*
G01X489117Y167008D02*
X489141Y166999D01*
G01Y171999D02*
X489152Y171984D01*
G01X489117Y172008D02*
X489141Y171999D01*
G01Y176999D02*
X489152Y176984D01*
G01X489117Y177008D02*
X489141Y176999D01*
G01X488169Y107015D02*
Y107024D01*
G01X488170Y107009D02*
X488169Y107015D01*
G01X488171Y107008D02*
X488170Y107009D01*
G01X488169Y112015D02*
Y112024D01*
G01X488170Y112009D02*
X488169Y112015D01*
G01X488171Y112008D02*
X488170Y112009D01*
G01X488169Y117015D02*
Y117024D01*
G01X488170Y117009D02*
X488169Y117015D01*
G01X488171Y117008D02*
X488170Y117009D01*
G01X488169Y122015D02*
Y122024D01*
G01X488170Y122009D02*
X488169Y122015D01*
G01X488171Y122008D02*
X488170Y122009D01*
G01X488169Y127015D02*
Y127024D01*
G01X488170Y127009D02*
X488169Y127015D01*
G01X488171Y127008D02*
X488170Y127009D01*
G01X488169Y132015D02*
Y132024D01*
G01X488170Y132009D02*
X488169Y132015D01*
G01X488171Y132008D02*
X488170Y132009D01*
G01X488169Y137015D02*
Y137024D01*
G01X488170Y137009D02*
X488169Y137015D01*
G01X488171Y137008D02*
X488170Y137009D01*
G01X488169Y142015D02*
Y142024D01*
G01X488170Y142009D02*
X488169Y142015D01*
G01X488171Y142008D02*
X488170Y142009D01*
G01X488169Y147015D02*
Y147024D01*
G01X488170Y147009D02*
X488169Y147015D01*
G01X488171Y147008D02*
X488170Y147009D01*
G01X488169Y152015D02*
Y152024D01*
G01X488170Y152009D02*
X488169Y152015D01*
G01X488171Y152008D02*
X488170Y152009D01*
G01X488169Y157015D02*
Y157024D01*
G01X488170Y157009D02*
X488169Y157015D01*
G01X488171Y157008D02*
X488170Y157009D01*
G01X488169Y162015D02*
Y162024D01*
G01X488170Y162009D02*
X488169Y162015D01*
G01X488171Y162008D02*
X488170Y162009D01*
G01X488169Y167015D02*
Y167024D01*
G01X488170Y167009D02*
X488169Y167015D01*
G01X488171Y167008D02*
X488170Y167009D01*
G01X488169Y172015D02*
Y172024D01*
G01X488170Y172009D02*
X488169Y172015D01*
G01X488171Y172008D02*
X488170Y172009D01*
G01X488169Y177015D02*
Y177024D01*
G01X488170Y177009D02*
X488169Y177015D01*
G01X488171Y177008D02*
X488170Y177009D01*
G01X489146Y107152D02*
X489154Y107125D01*
G01X489136Y107178D02*
X489146Y107152D01*
G01X489124Y107205D02*
X489136Y107178D01*
G01X489146Y112152D02*
X489154Y112125D01*
G01X489136Y112178D02*
X489146Y112152D01*
G01X489124Y112205D02*
X489136Y112178D01*
G01X489146Y117152D02*
X489154Y117125D01*
G01X489136Y117178D02*
X489146Y117152D01*
G01X489124Y117205D02*
X489136Y117178D01*
G01X489146Y122152D02*
X489154Y122125D01*
G01X489136Y122178D02*
X489146Y122152D01*
G01X489124Y122205D02*
X489136Y122178D01*
G01X489146Y127152D02*
X489154Y127125D01*
G01X489136Y127178D02*
X489146Y127152D01*
G01X489124Y127205D02*
X489136Y127178D01*
G01X489146Y132152D02*
X489154Y132125D01*
G01X489136Y132178D02*
X489146Y132152D01*
G01X489124Y132205D02*
X489136Y132178D01*
G01X489146Y137152D02*
X489154Y137125D01*
G01X489136Y137178D02*
X489146Y137152D01*
G01X489124Y137205D02*
X489136Y137178D01*
G01X489146Y142152D02*
X489154Y142125D01*
G01X489136Y142178D02*
X489146Y142152D01*
G01X489124Y142205D02*
X489136Y142178D01*
G01X489146Y147152D02*
X489154Y147125D01*
G01X489136Y147178D02*
X489146Y147152D01*
G01X489124Y147205D02*
X489136Y147178D01*
G01X489146Y152152D02*
X489154Y152125D01*
G01X489136Y152178D02*
X489146Y152152D01*
G01X489124Y152205D02*
X489136Y152178D01*
G01X489146Y157152D02*
X489154Y157125D01*
G01X489136Y157178D02*
X489146Y157152D01*
G01X489124Y157205D02*
X489136Y157178D01*
G01X489146Y162152D02*
X489154Y162125D01*
G01X489136Y162178D02*
X489146Y162152D01*
G01X489124Y162205D02*
X489136Y162178D01*
G01X489146Y167152D02*
X489154Y167125D01*
G01X489136Y167178D02*
X489146Y167152D01*
G01X489124Y167205D02*
X489136Y167178D01*
G01X489146Y172152D02*
X489154Y172125D01*
G01X489136Y172178D02*
X489146Y172152D01*
G01X489124Y172205D02*
X489136Y172178D01*
G01X489146Y177152D02*
X489154Y177125D01*
G01X489136Y177178D02*
X489146Y177152D01*
G01X489124Y177205D02*
X489136Y177178D01*
G01Y107003D02*
X489117Y107008D01*
G01X489151Y106988D02*
X489136Y107003D01*
G01X489156Y106969D02*
X489151Y106988D01*
G01X489136Y112003D02*
X489117Y112008D01*
G01X489151Y111988D02*
X489136Y112003D01*
G01X489156Y111969D02*
X489151Y111988D01*
G01X489136Y117003D02*
X489117Y117008D01*
G01X489151Y116988D02*
X489136Y117003D01*
G01X489156Y116969D02*
X489151Y116988D01*
G01X489136Y122003D02*
X489117Y122008D01*
G01X489151Y121988D02*
X489136Y122003D01*
G01X489156Y121969D02*
X489151Y121988D01*
G01X489136Y127003D02*
X489117Y127008D01*
G01X489151Y126988D02*
X489136Y127003D01*
G01X489156Y126969D02*
X489151Y126988D01*
G01X489136Y132003D02*
X489117Y132008D01*
G01X489151Y131988D02*
X489136Y132003D01*
G01X489156Y131969D02*
X489151Y131988D01*
G01X489136Y137003D02*
X489117Y137008D01*
G01X489151Y136988D02*
X489136Y137003D01*
G01X489156Y136969D02*
X489151Y136988D01*
G01X489136Y142003D02*
X489117Y142008D01*
G01X489151Y141988D02*
X489136Y142003D01*
G01X489156Y141969D02*
X489151Y141988D01*
G01X489136Y147003D02*
X489117Y147008D01*
G01X489151Y146988D02*
X489136Y147003D01*
G01X489156Y146969D02*
X489151Y146988D01*
G01X489136Y152003D02*
X489117Y152008D01*
G01X489151Y151988D02*
X489136Y152003D01*
G01X489156Y151969D02*
X489151Y151988D01*
G01X489136Y157003D02*
X489117Y157008D01*
G01X489151Y156988D02*
X489136Y157003D01*
G01X489156Y156969D02*
X489151Y156988D01*
G01X489136Y162003D02*
X489117Y162008D01*
G01X489151Y161988D02*
X489136Y162003D01*
G01X489156Y161969D02*
X489151Y161988D01*
G01X489136Y167003D02*
X489117Y167008D01*
G01X489151Y166988D02*
X489136Y167003D01*
G01X489156Y166969D02*
X489151Y166988D01*
G01X489136Y172003D02*
X489117Y172008D01*
G01X489151Y171988D02*
X489136Y172003D01*
G01X489156Y171969D02*
X489151Y171988D01*
G01X489136Y177003D02*
X489117Y177008D01*
G01X489151Y176988D02*
X489136Y177003D01*
G01X489156Y176969D02*
X489151Y176988D01*
G01X489120Y107106D02*
X489124Y107205D01*
G01X489115Y107034D02*
X489120Y107106D01*
G01X489117Y107008D02*
X489115Y107034D01*
G01X489120Y112106D02*
X489124Y112205D01*
G01X489115Y112034D02*
X489120Y112106D01*
G01X489117Y112008D02*
X489115Y112034D01*
G01X489120Y117106D02*
X489124Y117205D01*
G01X489115Y117034D02*
X489120Y117106D01*
G01X489117Y117008D02*
X489115Y117034D01*
G01X489120Y122106D02*
X489124Y122205D01*
G01X489115Y122034D02*
X489120Y122106D01*
G01X489117Y122008D02*
X489115Y122034D01*
G01X489120Y127106D02*
X489124Y127205D01*
G01X489115Y127034D02*
X489120Y127106D01*
G01X489117Y127008D02*
X489115Y127034D01*
G01X489120Y132106D02*
X489124Y132205D01*
G01X489115Y132034D02*
X489120Y132106D01*
G01X489117Y132008D02*
X489115Y132034D01*
G01X489120Y137106D02*
X489124Y137205D01*
G01X489115Y137034D02*
X489120Y137106D01*
G01X489117Y137008D02*
X489115Y137034D01*
G01X489120Y142106D02*
X489124Y142205D01*
G01X489115Y142034D02*
X489120Y142106D01*
G01X489117Y142008D02*
X489115Y142034D01*
G01X489120Y147106D02*
X489124Y147205D01*
G01X489115Y147034D02*
X489120Y147106D01*
G01X489117Y147008D02*
X489115Y147034D01*
G01X489120Y152106D02*
X489124Y152205D01*
G01X489115Y152034D02*
X489120Y152106D01*
G01X489117Y152008D02*
X489115Y152034D01*
G01X489120Y157106D02*
X489124Y157205D01*
G01X489115Y157034D02*
X489120Y157106D01*
G01X489117Y157008D02*
X489115Y157034D01*
G01X489120Y162106D02*
X489124Y162205D01*
G01X489115Y162034D02*
X489120Y162106D01*
G01X489117Y162008D02*
X489115Y162034D01*
G01X489120Y167106D02*
X489124Y167205D01*
G01X489115Y167034D02*
X489120Y167106D01*
G01X489117Y167008D02*
X489115Y167034D01*
G01X489120Y172106D02*
X489124Y172205D01*
G01X489115Y172034D02*
X489120Y172106D01*
G01X489117Y172008D02*
X489115Y172034D01*
G01X489120Y177106D02*
X489124Y177205D01*
G01X489115Y177034D02*
X489120Y177106D01*
G01X489117Y177008D02*
X489115Y177034D01*
G01X488170Y175628D02*
X488171Y175630D01*
G01X488169Y175622D02*
X488170Y175628D01*
G01X488169Y175614D02*
Y175622D01*
G01X488170Y170628D02*
X488171Y170630D01*
G01X488169Y170622D02*
X488170Y170628D01*
G01X488169Y170614D02*
Y170622D01*
G01X488170Y165628D02*
X488171Y165630D01*
G01X488169Y165622D02*
X488170Y165628D01*
G01X488169Y165614D02*
Y165622D01*
G01X488170Y160628D02*
X488171Y160630D01*
G01X488169Y160622D02*
X488170Y160628D01*
G01X488169Y160614D02*
Y160622D01*
G01X488170Y155628D02*
X488171Y155630D01*
G01X488169Y155622D02*
X488170Y155628D01*
G01X488169Y155614D02*
Y155622D01*
G01X488170Y150628D02*
X488171Y150630D01*
G01X488169Y150622D02*
X488170Y150628D01*
G01X488169Y150614D02*
Y150622D01*
G01X488170Y145628D02*
X488171Y145630D01*
G01X488169Y145622D02*
X488170Y145628D01*
G01X488169Y145614D02*
Y145622D01*
G01X488170Y140628D02*
X488171Y140630D01*
G01X488169Y140622D02*
X488170Y140628D01*
G01X488169Y140614D02*
Y140622D01*
G01X488170Y135628D02*
X488171Y135630D01*
G01X488169Y135622D02*
X488170Y135628D01*
G01X488169Y135614D02*
Y135622D01*
G01X488170Y130628D02*
X488171Y130630D01*
G01X488169Y130622D02*
X488170Y130628D01*
G01X488169Y130614D02*
Y130622D01*
G01X488170Y125628D02*
X488171Y125630D01*
G01X488169Y125622D02*
X488170Y125628D01*
G01X488169Y125614D02*
Y125622D01*
G01X488170Y120628D02*
X488171Y120630D01*
G01X488169Y120622D02*
X488170Y120628D01*
G01X488169Y120614D02*
Y120622D01*
G01X488170Y115628D02*
X488171Y115630D01*
G01X488169Y115622D02*
X488170Y115628D01*
G01X488169Y115614D02*
Y115622D01*
G01X488170Y110628D02*
X488171Y110630D01*
G01X488169Y110622D02*
X488170Y110628D01*
G01X488169Y110614D02*
Y110622D01*
G01X488170Y105628D02*
X488171Y105630D01*
G01X488169Y105622D02*
X488170Y105628D01*
G01X488169Y105614D02*
Y105622D01*
G01X489154Y175622D02*
Y175613D01*
G01X489155Y175628D02*
X489154Y175622D01*
G01X489156Y175630D02*
X489155Y175628D01*
G01X489154Y170622D02*
Y170613D01*
G01X489155Y170628D02*
X489154Y170622D01*
G01X489156Y170630D02*
X489155Y170628D01*
G01X489154Y165622D02*
Y165613D01*
G01X489155Y165628D02*
X489154Y165622D01*
G01X489156Y165630D02*
X489155Y165628D01*
G01X489154Y160622D02*
Y160613D01*
G01X489155Y160628D02*
X489154Y160622D01*
G01X489156Y160630D02*
X489155Y160628D01*
G01X489154Y155622D02*
Y155613D01*
G01X489155Y155628D02*
X489154Y155622D01*
G01X489156Y155630D02*
X489155Y155628D01*
G01X489154Y150622D02*
Y150613D01*
G01X489155Y150628D02*
X489154Y150622D01*
G01X489156Y150630D02*
X489155Y150628D01*
G01X489154Y145622D02*
Y145613D01*
G01X489155Y145628D02*
X489154Y145622D01*
G01X489156Y145630D02*
X489155Y145628D01*
G01X489154Y140622D02*
Y140613D01*
G01X489155Y140628D02*
X489154Y140622D01*
G01X489156Y140630D02*
X489155Y140628D01*
G01X489154Y135622D02*
Y135613D01*
G01X489155Y135628D02*
X489154Y135622D01*
G01X489156Y135630D02*
X489155Y135628D01*
G01X489154Y130622D02*
Y130613D01*
G01X489155Y130628D02*
X489154Y130622D01*
G01X489156Y130630D02*
X489155Y130628D01*
G01X489154Y125622D02*
Y125613D01*
G01X489155Y125628D02*
X489154Y125622D01*
G01X489156Y125630D02*
X489155Y125628D01*
G01X489154Y120622D02*
Y120613D01*
G01X489155Y120628D02*
X489154Y120622D01*
G01X489156Y120630D02*
X489155Y120628D01*
G01X489154Y115622D02*
Y115613D01*
G01X489155Y115628D02*
X489154Y115622D01*
G01X489156Y115630D02*
X489155Y115628D01*
G01X489154Y110622D02*
Y110613D01*
G01X489155Y110628D02*
X489154Y110622D01*
G01X489156Y110630D02*
X489155Y110628D01*
G01X489154Y105622D02*
Y105613D01*
G01X489155Y105628D02*
X489154Y105622D01*
G01X489156Y105630D02*
X489155Y105628D01*
G01X485551Y188130D02*
G03I-1890J0D01*
G01X486024D02*
G03I-2363J0D01*
G01X488583Y103681D02*
X489764Y104862D01*
G01X484646Y103681D02*
X485827Y104862D01*
G01X494488Y186161D02*
X491142Y182815D01*
G01X484646Y180138D02*
X485827Y181319D01*
G01X487153Y192950D02*
X484843Y188720D01*
G01X489154Y106982D02*
Y106991D01*
G01Y111982D02*
Y111991D01*
G01Y116982D02*
Y116991D01*
G01Y121982D02*
Y121991D01*
G01Y126982D02*
Y126991D01*
G01Y131982D02*
Y131991D01*
G01Y136982D02*
Y136991D01*
G01Y141982D02*
Y141991D01*
G01Y146982D02*
Y146991D01*
G01Y151982D02*
Y151991D01*
G01Y156982D02*
Y156991D01*
G01Y161982D02*
Y161991D01*
G01Y166982D02*
Y166991D01*
G01Y171982D02*
Y171991D01*
G01Y176982D02*
Y176991D01*
G01X494488Y186161D02*
Y201909D01*
G01X493504Y175630D02*
Y177008D01*
G01Y170630D02*
Y172008D01*
G01Y165630D02*
Y167008D01*
G01Y160630D02*
Y162008D01*
G01Y155630D02*
Y157008D01*
G01Y150630D02*
Y152008D01*
G01Y145630D02*
Y147008D01*
G01Y140630D02*
Y142008D01*
G01Y135630D02*
Y137008D01*
G01Y130630D02*
Y132008D01*
G01Y125630D02*
Y127008D01*
G01Y120630D02*
Y122008D01*
G01Y115630D02*
Y117008D01*
G01Y110630D02*
Y112008D01*
G01Y105630D02*
Y107008D01*
G01X490335D02*
Y105630D01*
G01Y112008D02*
Y110630D01*
G01Y117008D02*
Y115630D01*
G01Y122008D02*
Y120630D01*
G01Y127008D02*
Y125630D01*
G01Y132008D02*
Y130630D01*
G01Y137008D02*
Y135630D01*
G01Y142008D02*
Y140630D01*
G01Y147008D02*
Y145630D01*
G01Y152008D02*
Y150630D01*
G01Y157008D02*
Y155630D01*
G01Y162008D02*
Y160630D01*
G01Y167008D02*
Y165630D01*
G01Y172008D02*
Y170630D01*
G01Y177008D02*
Y175630D01*
G01X489154Y106982D02*
Y107125D01*
G01Y111982D02*
Y112125D01*
G01Y116982D02*
Y117125D01*
G01Y121982D02*
Y122125D01*
G01Y126982D02*
Y127125D01*
G01Y131982D02*
Y132125D01*
G01Y136982D02*
Y137125D01*
G01Y141982D02*
Y142125D01*
G01Y146982D02*
Y147125D01*
G01Y151982D02*
Y152125D01*
G01Y156982D02*
Y157125D01*
G01Y161982D02*
Y162125D01*
G01Y166982D02*
Y167125D01*
G01Y171982D02*
Y172125D01*
G01Y176982D02*
Y177125D01*
G01Y175138D02*
Y177500D01*
G01Y170138D02*
Y172500D01*
G01Y165138D02*
Y167500D01*
G01Y160138D02*
Y162500D01*
G01Y155138D02*
Y157500D01*
G01Y150138D02*
Y152500D01*
G01Y145138D02*
Y147500D01*
G01Y140138D02*
Y142500D01*
G01Y135138D02*
Y137500D01*
G01Y130138D02*
Y132500D01*
G01Y125138D02*
Y127500D01*
G01Y120138D02*
Y122500D01*
G01Y115138D02*
Y117500D01*
G01Y110138D02*
Y112500D01*
G01Y105138D02*
Y107500D01*
G01X488169D02*
Y105138D01*
G01Y112500D02*
Y110138D01*
G01Y117500D02*
Y115138D01*
G01Y122500D02*
Y120138D01*
G01Y127500D02*
Y125138D01*
G01Y132500D02*
Y130138D01*
G01Y137500D02*
Y135138D01*
G01Y142500D02*
Y140138D01*
G01Y147500D02*
Y145138D01*
G01Y152500D02*
Y150138D01*
G01Y157500D02*
Y155138D01*
G01Y162500D02*
Y160138D01*
G01Y167500D02*
Y165138D01*
G01Y172500D02*
Y170138D01*
G01Y177500D02*
Y175138D01*
G01X487402Y192224D02*
Y183681D01*
G01X485827Y181319D02*
Y104862D01*
G01X484843Y188720D02*
Y187028D01*
G01X484646Y180138D02*
Y103681D01*
G01X482480Y187028D02*
Y188720D01*
G01Y187028D02*
X484843D01*
G01X490551Y183681D02*
X487402D01*
G01X489154Y177500D02*
X488169D01*
G01X488171Y177008D02*
X493504D01*
G01Y176969D02*
X489156D01*
G01X493504Y175630D02*
X488171D01*
G01X488169Y175138D02*
X489154D01*
G01Y172500D02*
X488169D01*
G01X488171Y172008D02*
X493504D01*
G01Y171969D02*
X489156D01*
G01X493504Y170630D02*
X488171D01*
G01X488169Y170138D02*
X489154D01*
G01Y167500D02*
X488169D01*
G01X488171Y167008D02*
X493504D01*
G01Y166969D02*
X489156D01*
G01X493504Y165630D02*
X488171D01*
G01X488169Y165138D02*
X489154D01*
G01Y162500D02*
X488169D01*
G01X488171Y162008D02*
X493504D01*
G01Y161969D02*
X489156D01*
G01X493504Y160630D02*
X488171D01*
G01X488169Y160138D02*
X489154D01*
G01Y157500D02*
X488169D01*
G01X488171Y157008D02*
X493504D01*
G01Y156969D02*
X489156D01*
G01X493504Y155630D02*
X488171D01*
G01X488169Y155138D02*
X489154D01*
G01Y152500D02*
X488169D01*
G01X488171Y152008D02*
X493504D01*
G01Y151969D02*
X489156D01*
G01X493504Y150630D02*
X488171D01*
G01X488169Y150138D02*
X489154D01*
G01Y147500D02*
X488169D01*
G01X488171Y147008D02*
X493504D01*
G01Y146969D02*
X489156D01*
G01X493504Y145630D02*
X488171D01*
G01X488169Y145138D02*
X489154D01*
G01Y142500D02*
X488169D01*
G01X488171Y142008D02*
X493504D01*
G01Y141969D02*
X489156D01*
G01X493504Y140630D02*
X488171D01*
G01X488169Y140138D02*
X489154D01*
G01Y137500D02*
X488169D01*
G01X488171Y137008D02*
X493504D01*
G01Y136969D02*
X489156D01*
G01X493504Y135630D02*
X488171D01*
G01X488169Y135138D02*
X489154D01*
G01Y132500D02*
X488169D01*
G01X488171Y132008D02*
X493504D01*
G01Y131969D02*
X489156D01*
G01X493504Y130630D02*
X488171D01*
G01X488169Y130138D02*
X489154D01*
G01Y127500D02*
X488169D01*
G01X488171Y127008D02*
X493504D01*
G01Y126969D02*
X489156D01*
G01X493504Y125630D02*
X488171D01*
G01X488169Y125138D02*
X489154D01*
G01Y122500D02*
X488169D01*
G01X488171Y122008D02*
X493504D01*
G01Y121969D02*
X489156D01*
G01X493504Y120630D02*
X488171D01*
G01X488169Y120138D02*
X489154D01*
G01Y117500D02*
X488169D01*
G01Y177204D02*
X489124Y177205D01*
G01X489154Y175434D02*
X488169Y175433D01*
G01Y172204D02*
X489124Y172205D01*
G01X489154Y170434D02*
X488169Y170433D01*
G01Y167204D02*
X489124Y167205D01*
G01X489154Y165434D02*
X488169Y165433D01*
G01Y162204D02*
X489124Y162205D01*
G01X489154Y160434D02*
X488169Y160433D01*
G01Y157204D02*
X489124Y157205D01*
G01X489154Y155434D02*
X488169Y155433D01*
G01Y152204D02*
X489124Y152205D01*
G01X489154Y150434D02*
X488169Y150433D01*
G01Y147204D02*
X489124Y147205D01*
G01X489154Y145434D02*
X488169Y145433D01*
G01Y142204D02*
X489124Y142205D01*
G01X489154Y140434D02*
X488169Y140433D01*
G01Y137204D02*
X489124Y137205D01*
G01X489154Y135434D02*
X488169Y135433D01*
G01Y132204D02*
X489124Y132205D01*
G01X489154Y130434D02*
X488169Y130433D01*
G01Y127204D02*
X489124Y127205D01*
G01X489154Y125434D02*
X488169Y125433D01*
G01Y122204D02*
X489124Y122205D01*
G01X489154Y120434D02*
X488169Y120433D01*
G01Y117204D02*
X489124Y117205D01*
G01X484843Y187028D02*
X486146Y185059D01*
G01X488171Y117008D02*
X493504D01*
G01Y116969D02*
X489156D01*
G01X493504Y115630D02*
X488171D01*
G01X488169Y115138D02*
X489154D01*
G01Y112500D02*
X488169D01*
G01X488171Y112008D02*
X493504D01*
G01Y111969D02*
X489156D01*
G01X493504Y110630D02*
X488171D01*
G01X488169Y110138D02*
X489154D01*
G01Y107500D02*
X488169D01*
G01X488171Y107008D02*
X493504D01*
G01Y106969D02*
X489156D01*
G01X493504Y105630D02*
X488171D01*
G01X488169Y105138D02*
X489154D01*
G01X485827Y104862D02*
X489764D01*
G01X484646Y103681D02*
X488583D01*
G01X489154Y115434D02*
X488169Y115433D01*
G01Y112204D02*
X489124Y112205D01*
G01X489154Y110434D02*
X488169Y110433D01*
G01Y107204D02*
X489124Y107205D01*
G01X489154Y105434D02*
X488169Y105433D01*
G01X567913Y260630D02*
G03X569094I591J0D01*
G01Y254331D02*
G03X567913I-590J0D01*
G01X565945D02*
G03X564764I-590J0D01*
G01Y260630D02*
G03X565945I590J0D01*
G01X567913D02*
G03X569094I591J0D01*
G01Y254331D02*
G03X567913I-590J0D01*
G01X565945D02*
G03X564764I-590J0D01*
G01Y260630D02*
G03X565945I590J0D01*
G01X487598Y202500D02*
G03X487008Y203091I-591J0D01*
G01X484843Y199350D02*
G03Y201319I0J984D01*
G01X487402Y192224D02*
G03X486220Y193406I-1181J1D01*
G01X494488Y201909D02*
G03X492520Y203878I-1968J1D01*
G01X482480Y201319D02*
G03Y199350I0J-985D01*
G01X569882Y254331D02*
Y260630D01*
G01Y254331D02*
Y260630D01*
G01X563976Y254331D02*
Y260630D01*
G01D02*
Y254331D01*
G01X487598Y196398D02*
Y202500D01*
G01X567913Y260630D02*
X565945D01*
G01X564764D02*
X563976D01*
G01X567913D02*
X565945D01*
G01X564764D02*
X563976D01*
G01X569882D02*
X569094D01*
G01X569882D02*
X569094D01*
G01X569882Y259646D02*
X563976D01*
G01Y259449D02*
X569882D01*
G01X563976Y255512D02*
X569882D01*
G01Y255315D02*
X563976D01*
G01X569094Y254331D02*
X569882D01*
G01X569094D02*
X569882D01*
G01X565945D02*
X567913D01*
G01X563976D02*
X564764D01*
G01X565945D02*
X567913D01*
G01X563976D02*
X564764D01*
G01X484843Y201319D02*
X482480D01*
G01Y199350D02*
X484843D01*
G01X482480Y188720D02*
X484843D01*
G01X489120Y504862D02*
X489124Y504961D01*
G01X489115Y504790D02*
X489120Y504862D01*
G01X489117Y504764D02*
X489115Y504790D01*
G01X489120Y509862D02*
X489124Y509961D01*
G01X489115Y509790D02*
X489120Y509862D01*
G01X489117Y509764D02*
X489115Y509790D01*
G01X489120Y514862D02*
X489124Y514961D01*
G01X489115Y514790D02*
X489120Y514862D01*
G01X489117Y514764D02*
X489115Y514790D01*
G01X489120Y519862D02*
X489124Y519961D01*
G01X489115Y519790D02*
X489120Y519862D01*
G01X489117Y519764D02*
X489115Y519790D01*
G01X489120Y524862D02*
X489124Y524961D01*
G01X489115Y524790D02*
X489120Y524862D01*
G01X489117Y524764D02*
X489115Y524790D01*
G01X489120Y529862D02*
X489124Y529961D01*
G01X489115Y529790D02*
X489120Y529862D01*
G01X489117Y529764D02*
X489115Y529790D01*
G01X489120Y534862D02*
X489124Y534961D01*
G01X489115Y534790D02*
X489120Y534862D01*
G01X489117Y534764D02*
X489115Y534790D01*
G01X489120Y559862D02*
X489124Y559961D01*
G01X489115Y559790D02*
X489120Y559862D01*
G01X489117Y559764D02*
X489115Y559790D01*
G01X489120Y564862D02*
X489124Y564961D01*
G01X489115Y564790D02*
X489120Y564862D01*
G01X489117Y564764D02*
X489115Y564790D01*
G01X489120Y569862D02*
X489124Y569961D01*
G01X489115Y569790D02*
X489120Y569862D01*
G01X489117Y569764D02*
X489115Y569790D01*
G01X489154Y504731D02*
Y504738D01*
G01X489155Y504726D02*
X489154Y504731D01*
G01X489156Y504724D02*
X489155Y504726D01*
G01X489154Y509731D02*
Y509738D01*
G01X489155Y509726D02*
X489154Y509731D01*
G01X489156Y509724D02*
X489155Y509726D01*
G01X489154Y514731D02*
Y514738D01*
G01X489155Y514726D02*
X489154Y514731D01*
G01X489156Y514724D02*
X489155Y514726D01*
G01X489154Y519731D02*
Y519738D01*
G01X489155Y519726D02*
X489154Y519731D01*
G01X489156Y519724D02*
X489155Y519726D01*
G01X489154Y524731D02*
Y524738D01*
G01X489155Y524726D02*
X489154Y524731D01*
G01X489156Y524724D02*
X489155Y524726D01*
G01X489154Y529731D02*
Y529738D01*
G01X489155Y529726D02*
X489154Y529731D01*
G01X489156Y529724D02*
X489155Y529726D01*
G01X489154Y534731D02*
Y534738D01*
G01X489155Y534726D02*
X489154Y534731D01*
G01X489156Y534724D02*
X489155Y534726D01*
G01X489154Y559731D02*
Y559738D01*
G01X489155Y559726D02*
X489154Y559731D01*
G01X489156Y559724D02*
X489155Y559726D01*
G01X489154Y564731D02*
Y564738D01*
G01X489155Y564726D02*
X489154Y564731D01*
G01X489156Y564724D02*
X489155Y564726D01*
G01X489154Y569731D02*
Y569738D01*
G01X489155Y569726D02*
X489154Y569731D01*
G01X489156Y569724D02*
X489155Y569726D01*
G01X488169Y504771D02*
Y504780D01*
G01X488170Y504765D02*
X488169Y504771D01*
G01X488171Y504764D02*
X488170Y504765D01*
G01X488169Y509771D02*
Y509780D01*
G01X488170Y509765D02*
X488169Y509771D01*
G01X488171Y509764D02*
X488170Y509765D01*
G01X488169Y514771D02*
Y514780D01*
G01X488170Y514765D02*
X488169Y514771D01*
G01X488171Y514764D02*
X488170Y514765D01*
G01X488169Y519771D02*
Y519780D01*
G01X488170Y519765D02*
X488169Y519771D01*
G01X488171Y519764D02*
X488170Y519765D01*
G01X488169Y524771D02*
Y524780D01*
G01X488170Y524765D02*
X488169Y524771D01*
G01X488171Y524764D02*
X488170Y524765D01*
G01X488169Y529771D02*
Y529780D01*
G01X488170Y529765D02*
X488169Y529771D01*
G01X488171Y529764D02*
X488170Y529765D01*
G01X488169Y534771D02*
Y534780D01*
G01X488170Y534765D02*
X488169Y534771D01*
G01X488171Y534764D02*
X488170Y534765D01*
G01X488169Y559771D02*
Y559780D01*
G01X488170Y559765D02*
X488169Y559771D01*
G01X488171Y559764D02*
X488170Y559765D01*
G01X488169Y564771D02*
Y564780D01*
G01X488170Y564765D02*
X488169Y564771D01*
G01X488171Y564764D02*
X488170Y564765D01*
G01X488169Y569771D02*
Y569780D01*
G01X488170Y569765D02*
X488169Y569771D01*
G01X488171Y569764D02*
X488170Y569765D01*
G01X489146Y504907D02*
X489154Y504881D01*
G01X489136Y504934D02*
X489146Y504907D01*
G01X489124Y504961D02*
X489136Y504934D01*
G01X489146Y509907D02*
X489154Y509881D01*
G01X489136Y509934D02*
X489146Y509907D01*
G01X489124Y509961D02*
X489136Y509934D01*
G01X489146Y514907D02*
X489154Y514881D01*
G01X489136Y514934D02*
X489146Y514907D01*
G01X489124Y514961D02*
X489136Y514934D01*
G01X489146Y519907D02*
X489154Y519881D01*
G01X489136Y519934D02*
X489146Y519907D01*
G01X489124Y519961D02*
X489136Y519934D01*
G01X489146Y524907D02*
X489154Y524881D01*
G01X489136Y524934D02*
X489146Y524907D01*
G01X489124Y524961D02*
X489136Y524934D01*
G01X489146Y529907D02*
X489154Y529881D01*
G01X489136Y529934D02*
X489146Y529907D01*
G01X489124Y529961D02*
X489136Y529934D01*
G01X489146Y534907D02*
X489154Y534881D01*
G01X489136Y534934D02*
X489146Y534907D01*
G01X489124Y534961D02*
X489136Y534934D01*
G01X489146Y559907D02*
X489154Y559881D01*
G01X489136Y559934D02*
X489146Y559907D01*
G01X489124Y559961D02*
X489136Y559934D01*
G01X489146Y564907D02*
X489154Y564881D01*
G01X489136Y564934D02*
X489146Y564907D01*
G01X489124Y564961D02*
X489136Y564934D01*
G01X489146Y569907D02*
X489154Y569881D01*
G01X489136Y569934D02*
X489146Y569907D01*
G01X489124Y569961D02*
X489136Y569934D01*
G01Y504759D02*
X489117Y504764D01*
G01X489151Y504744D02*
X489136Y504759D01*
G01X489156Y504724D02*
X489151Y504744D01*
G01X489136Y509759D02*
X489117Y509764D01*
G01X489151Y509744D02*
X489136Y509759D01*
G01X489156Y509724D02*
X489151Y509744D01*
G01X489136Y514759D02*
X489117Y514764D01*
G01X489151Y514744D02*
X489136Y514759D01*
G01X489156Y514724D02*
X489151Y514744D01*
G01X489136Y519759D02*
X489117Y519764D01*
G01X489151Y519744D02*
X489136Y519759D01*
G01X489156Y519724D02*
X489151Y519744D01*
G01X489136Y524759D02*
X489117Y524764D01*
G01X489151Y524744D02*
X489136Y524759D01*
G01X489156Y524724D02*
X489151Y524744D01*
G01X489136Y529759D02*
X489117Y529764D01*
G01X489151Y529744D02*
X489136Y529759D01*
G01X489156Y529724D02*
X489151Y529744D01*
G01X489136Y534759D02*
X489117Y534764D01*
G01X489151Y534744D02*
X489136Y534759D01*
G01X489156Y534724D02*
X489151Y534744D01*
G01X489136Y559759D02*
X489117Y559764D01*
G01X489151Y559744D02*
X489136Y559759D01*
G01X489156Y559724D02*
X489151Y559744D01*
G01X489136Y564759D02*
X489117Y564764D01*
G01X489151Y564744D02*
X489136Y564759D01*
G01X489156Y564724D02*
X489151Y564744D01*
G01X489136Y569759D02*
X489117Y569764D01*
G01X489151Y569744D02*
X489136Y569759D01*
G01X489156Y569724D02*
X489151Y569744D01*
G01X488170Y568384D02*
X488171Y568386D01*
G01X488169Y568378D02*
X488170Y568384D01*
G01X488169Y568370D02*
Y568378D01*
G01X488170Y563384D02*
X488171Y563386D01*
G01X488169Y563378D02*
X488170Y563384D01*
G01X488169Y563370D02*
Y563378D01*
G01X488170Y558384D02*
X488171Y558386D01*
G01X488169Y558378D02*
X488170Y558384D01*
G01X488169Y558370D02*
Y558378D01*
G01X488170Y533384D02*
X488171Y533386D01*
G01X488169Y533378D02*
X488170Y533384D01*
G01X488169Y533370D02*
Y533378D01*
G01X488170Y528384D02*
X488171Y528386D01*
G01X488169Y528378D02*
X488170Y528384D01*
G01X488169Y528370D02*
Y528378D01*
G01X488170Y523384D02*
X488171Y523386D01*
G01X488169Y523378D02*
X488170Y523384D01*
G01X488169Y523370D02*
Y523378D01*
G01X488170Y518384D02*
X488171Y518386D01*
G01X488169Y518378D02*
X488170Y518384D01*
G01X488169Y518370D02*
Y518378D01*
G01X488170Y513384D02*
X488171Y513386D01*
G01X488169Y513378D02*
X488170Y513384D01*
G01X488169Y513370D02*
Y513378D01*
G01X488170Y508384D02*
X488171Y508386D01*
G01X488169Y508378D02*
X488170Y508384D01*
G01X488169Y508370D02*
Y508378D01*
G01X488170Y503384D02*
X488171Y503386D01*
G01X488169Y503378D02*
X488170Y503384D01*
G01X488169Y503370D02*
Y503378D01*
G01X489141Y504755D02*
X489152Y504740D01*
G01X489117Y504764D02*
X489141Y504755D01*
G01Y509755D02*
X489152Y509740D01*
G01X489117Y509764D02*
X489141Y509755D01*
G01Y514755D02*
X489152Y514740D01*
G01X489117Y514764D02*
X489141Y514755D01*
G01Y519755D02*
X489152Y519740D01*
G01X489117Y519764D02*
X489141Y519755D01*
G01Y524755D02*
X489152Y524740D01*
G01X489117Y524764D02*
X489141Y524755D01*
G01Y529755D02*
X489152Y529740D01*
G01X489117Y529764D02*
X489141Y529755D01*
G01Y534755D02*
X489152Y534740D01*
G01X489117Y534764D02*
X489141Y534755D01*
G01Y559755D02*
X489152Y559740D01*
G01X489117Y559764D02*
X489141Y559755D01*
G01Y564755D02*
X489152Y564740D01*
G01X489117Y564764D02*
X489141Y564755D01*
G01Y569755D02*
X489152Y569740D01*
G01X489117Y569764D02*
X489141Y569755D01*
G01X489154Y568378D02*
Y568369D01*
G01X489155Y568384D02*
X489154Y568378D01*
G01X489156Y568386D02*
X489155Y568384D01*
G01X489154Y563378D02*
Y563369D01*
G01X489155Y563384D02*
X489154Y563378D01*
G01X489156Y563386D02*
X489155Y563384D01*
G01X489154Y558378D02*
Y558369D01*
G01X489155Y558384D02*
X489154Y558378D01*
G01X489156Y558386D02*
X489155Y558384D01*
G01X489154Y533378D02*
Y533369D01*
G01X489155Y533384D02*
X489154Y533378D01*
G01X489156Y533386D02*
X489155Y533384D01*
G01X489154Y528378D02*
Y528369D01*
G01X489155Y528384D02*
X489154Y528378D01*
G01X489156Y528386D02*
X489155Y528384D01*
G01X489154Y523378D02*
Y523369D01*
G01X489155Y523384D02*
X489154Y523378D01*
G01X489156Y523386D02*
X489155Y523384D01*
G01X489154Y518378D02*
Y518369D01*
G01X489155Y518384D02*
X489154Y518378D01*
G01X489156Y518386D02*
X489155Y518384D01*
G01X489154Y513378D02*
Y513369D01*
G01X489155Y513384D02*
X489154Y513378D01*
G01X489156Y513386D02*
X489155Y513384D01*
G01X489154Y508378D02*
Y508369D01*
G01X489155Y508384D02*
X489154Y508378D01*
G01X489156Y508386D02*
X489155Y508384D01*
G01X489154Y503378D02*
Y503369D01*
G01X489155Y503384D02*
X489154Y503378D01*
G01X489156Y503386D02*
X489155Y503384D01*
G01X487008Y477303D02*
G03X487598Y477894I0J590D01*
G01X484843Y479075D02*
G03Y481043I0J984D01*
G01X484764Y492264D02*
G03I-1103J0D01*
G01X486220Y486988D02*
G03X487402Y488169I1J1181D01*
G01X485236Y492264D02*
G03I-1575J0D01*
G01X492520Y476516D02*
G03X494488Y478484I0J1968D01*
G01X482480Y481043D02*
G03Y479075I0J-984D01*
G01X489154Y570256D02*
X488169D01*
G01X488171Y569764D02*
X493504D01*
G01Y569724D02*
X489156D01*
G01X493504Y568386D02*
X488171D01*
G01X488169Y567894D02*
X489154D01*
G01Y565256D02*
X488169D01*
G01X488171Y564764D02*
X493504D01*
G01Y564724D02*
X489156D01*
G01X493504Y563386D02*
X488171D01*
G01X488169Y562894D02*
X489154D01*
G01Y560256D02*
X488169D01*
G01X488171Y559764D02*
X493504D01*
G01Y559724D02*
X489156D01*
G01X493504Y558386D02*
X488171D01*
G01X488169Y557894D02*
X489154D01*
G01X485827Y557618D02*
X489764D01*
G01X484646Y556437D02*
X488583D01*
G01Y536713D02*
X484646D01*
G01X489764Y535531D02*
X485827D01*
G01X489154Y535256D02*
X488169D01*
G01X488171Y534764D02*
X493504D01*
G01Y534724D02*
X489156D01*
G01X493504Y533386D02*
X488171D01*
G01X488169Y532894D02*
X489154D01*
G01Y530256D02*
X488169D01*
G01X488171Y529764D02*
X493504D01*
G01Y529724D02*
X489156D01*
G01X493504Y528386D02*
X488171D01*
G01X488169Y569959D02*
X489124Y569961D01*
G01X489154Y568190D02*
X488169Y568189D01*
G01Y564959D02*
X489124Y564961D01*
G01X489154Y563190D02*
X488169Y563189D01*
G01Y559959D02*
X489124Y559961D01*
G01X489154Y558190D02*
X488169Y558189D01*
G01Y534959D02*
X489124Y534961D01*
G01X489154Y533190D02*
X488169Y533189D01*
G01Y529959D02*
X489124Y529961D01*
G01X489154Y528190D02*
X488169Y528189D01*
G01X488583Y556437D02*
X489764Y557618D01*
G01X484646Y556437D02*
X485827Y557618D01*
G01X488169Y527894D02*
X489154D01*
G01Y525256D02*
X488169D01*
G01X488171Y524764D02*
X493504D01*
G01Y524724D02*
X489156D01*
G01X493504Y523386D02*
X488171D01*
G01X488169Y522894D02*
X489154D01*
G01Y520256D02*
X488169D01*
G01X488171Y519764D02*
X493504D01*
G01Y519724D02*
X489156D01*
G01X493504Y518386D02*
X488171D01*
G01X488169Y517894D02*
X489154D01*
G01Y515256D02*
X488169D01*
G01X488171Y514764D02*
X493504D01*
G01Y514724D02*
X489156D01*
G01X493504Y513386D02*
X488171D01*
G01X488169Y512894D02*
X489154D01*
G01Y510256D02*
X488169D01*
G01X488171Y509764D02*
X493504D01*
G01Y509724D02*
X489156D01*
G01X493504Y508386D02*
X488171D01*
G01X488169Y507894D02*
X489154D01*
G01Y505256D02*
X488169D01*
G01X488171Y504764D02*
X493504D01*
G01Y504724D02*
X489156D01*
G01X493504Y503386D02*
X488171D01*
G01X488169Y502894D02*
X489154D01*
G01X487402Y496713D02*
X490551D01*
G01X484843Y493366D02*
X482480D01*
G01X484843Y491673D02*
X482480D01*
G01X484843Y481043D02*
X482480D01*
G01Y479075D02*
X484843D01*
G01X488169Y524959D02*
X489124Y524961D01*
G01X489154Y523190D02*
X488169Y523189D01*
G01Y519959D02*
X489124Y519961D01*
G01X489154Y518190D02*
X488169Y518189D01*
G01Y514959D02*
X489124Y514961D01*
G01X489154Y513190D02*
X488169Y513189D01*
G01Y509959D02*
X489124Y509961D01*
G01X489154Y508190D02*
X488169Y508189D01*
G01Y504959D02*
X489124Y504961D01*
G01X489154Y503190D02*
X488169Y503189D01*
G01X486146Y495335D02*
X484843Y493366D01*
G01X489154Y504738D02*
Y504746D01*
G01Y509738D02*
Y509746D01*
G01Y514738D02*
Y514746D01*
G01Y519738D02*
Y519746D01*
G01Y524738D02*
Y524746D01*
G01Y529738D02*
Y529746D01*
G01Y534738D02*
Y534746D01*
G01Y559738D02*
Y559746D01*
G01Y564738D02*
Y564746D01*
G01Y569738D02*
Y569746D01*
G01X494488Y478484D02*
Y494232D01*
G01X493504Y568386D02*
Y569764D01*
G01Y563386D02*
Y564764D01*
G01Y558386D02*
Y559764D01*
G01Y533386D02*
Y534764D01*
G01Y528386D02*
Y529764D01*
G01Y523386D02*
Y524764D01*
G01Y518386D02*
Y519764D01*
G01Y513386D02*
Y514764D01*
G01Y508386D02*
Y509764D01*
G01Y503386D02*
Y504764D01*
G01X491142Y635571D02*
Y497579D01*
G01X490551Y637815D02*
Y495335D01*
G01X490335Y504764D02*
Y503386D01*
G01Y509764D02*
Y508386D01*
G01Y514764D02*
Y513386D01*
G01Y519764D02*
Y518386D01*
G01Y524764D02*
Y523386D01*
G01Y529764D02*
Y528386D01*
G01Y534764D02*
Y533386D01*
G01Y559764D02*
Y558386D01*
G01Y564764D02*
Y563386D01*
G01Y569764D02*
Y568386D01*
G01X489764Y557618D02*
Y535531D01*
G01X489154Y504738D02*
Y504881D01*
G01Y509738D02*
Y509881D01*
G01Y514738D02*
Y514881D01*
G01Y519738D02*
Y519881D01*
G01Y524738D02*
Y524881D01*
G01Y529738D02*
Y529881D01*
G01Y534738D02*
Y534881D01*
G01Y559738D02*
Y559881D01*
G01Y564738D02*
Y564881D01*
G01Y567894D02*
Y570256D01*
G01Y562894D02*
Y565256D01*
G01Y557894D02*
Y560256D01*
G01Y532894D02*
Y535256D01*
G01Y527894D02*
Y530256D01*
G01Y522894D02*
Y525256D01*
G01Y517894D02*
Y520256D01*
G01Y512894D02*
Y515256D01*
G01Y507894D02*
Y510256D01*
G01Y502894D02*
Y505256D01*
G01X488583Y556437D02*
Y536713D01*
G01X488169Y505256D02*
Y502894D01*
G01Y510256D02*
Y507894D01*
G01Y515256D02*
Y512894D01*
G01Y520256D02*
Y517894D01*
G01Y525256D02*
Y522894D01*
G01Y530256D02*
Y527894D01*
G01Y535256D02*
Y532894D01*
G01Y560256D02*
Y557894D01*
G01Y565256D02*
Y562894D01*
G01Y570256D02*
Y567894D01*
G01X487598Y483996D02*
Y477894D01*
G01X487402Y496713D02*
Y488169D01*
G01X485827Y535531D02*
Y499075D01*
G01Y634075D02*
Y557618D01*
G01X484843Y491673D02*
X487153Y487444D01*
G01X488583Y536713D02*
X489764Y535531D01*
G01X484646Y536713D02*
X485827Y535531D01*
G01X491142Y497579D02*
X494488Y494232D01*
G01X484646Y500256D02*
X485827Y499075D01*
G01X484843Y493366D02*
Y491673D01*
G01X484646Y536713D02*
Y500256D01*
G01Y632894D02*
Y556437D01*
G01X482480Y491673D02*
Y493366D01*
G01X489120Y574862D02*
X489124Y574961D01*
G01X489115Y574790D02*
X489120Y574862D01*
G01X489117Y574764D02*
X489115Y574790D01*
G01X489120Y579862D02*
X489124Y579961D01*
G01X489115Y579790D02*
X489120Y579862D01*
G01X489117Y579764D02*
X489115Y579790D01*
G01X489120Y584862D02*
X489124Y584961D01*
G01X489115Y584790D02*
X489120Y584862D01*
G01X489117Y584764D02*
X489115Y584790D01*
G01X489120Y589862D02*
X489124Y589961D01*
G01X489115Y589790D02*
X489120Y589862D01*
G01X489117Y589764D02*
X489115Y589790D01*
G01X489120Y594862D02*
X489124Y594961D01*
G01X489115Y594790D02*
X489120Y594862D01*
G01X489117Y594764D02*
X489115Y594790D01*
G01X489120Y599862D02*
X489124Y599961D01*
G01X489115Y599790D02*
X489120Y599862D01*
G01X489117Y599764D02*
X489115Y599790D01*
G01X489120Y604862D02*
X489124Y604961D01*
G01X489115Y604790D02*
X489120Y604862D01*
G01X489117Y604764D02*
X489115Y604790D01*
G01X489120Y609862D02*
X489124Y609961D01*
G01X489115Y609790D02*
X489120Y609862D01*
G01X489117Y609764D02*
X489115Y609790D01*
G01X489120Y614862D02*
X489124Y614961D01*
G01X489115Y614790D02*
X489120Y614862D01*
G01X489117Y614764D02*
X489115Y614790D01*
G01X489120Y619862D02*
X489124Y619961D01*
G01X489115Y619790D02*
X489120Y619862D01*
G01X489117Y619764D02*
X489115Y619790D01*
G01X489120Y624862D02*
X489124Y624961D01*
G01X489115Y624790D02*
X489120Y624862D01*
G01X489117Y624764D02*
X489115Y624790D01*
G01X489120Y629862D02*
X489124Y629961D01*
G01X489115Y629790D02*
X489120Y629862D01*
G01X489117Y629764D02*
X489115Y629790D01*
G01X489154Y574731D02*
Y574738D01*
G01X489155Y574726D02*
X489154Y574731D01*
G01X489156Y574724D02*
X489155Y574726D01*
G01X489154Y579731D02*
Y579738D01*
G01X489155Y579726D02*
X489154Y579731D01*
G01X489156Y579724D02*
X489155Y579726D01*
G01X489154Y584731D02*
Y584738D01*
G01X489155Y584726D02*
X489154Y584731D01*
G01X489156Y584724D02*
X489155Y584726D01*
G01X489154Y589731D02*
Y589738D01*
G01X489155Y589726D02*
X489154Y589731D01*
G01X489156Y589724D02*
X489155Y589726D01*
G01X489154Y594731D02*
Y594738D01*
G01X489155Y594726D02*
X489154Y594731D01*
G01X489156Y594724D02*
X489155Y594726D01*
G01X488169Y574771D02*
Y574780D01*
G01X488170Y574765D02*
X488169Y574771D01*
G01X488171Y574764D02*
X488170Y574765D01*
G01X488169Y579771D02*
Y579780D01*
G01X488170Y579765D02*
X488169Y579771D01*
G01X488171Y579764D02*
X488170Y579765D01*
G01X488169Y584771D02*
Y584780D01*
G01X488170Y584765D02*
X488169Y584771D01*
G01X488171Y584764D02*
X488170Y584765D01*
G01X488169Y589771D02*
Y589780D01*
G01X488170Y589765D02*
X488169Y589771D01*
G01X488171Y589764D02*
X488170Y589765D01*
G01X488169Y594771D02*
Y594780D01*
G01X488170Y594765D02*
X488169Y594771D01*
G01X488171Y594764D02*
X488170Y594765D01*
G01X488169Y599771D02*
Y599780D01*
G01X488170Y599765D02*
X488169Y599771D01*
G01X488171Y599764D02*
X488170Y599765D01*
G01X488169Y604771D02*
Y604780D01*
G01X488170Y604765D02*
X488169Y604771D01*
G01X488171Y604764D02*
X488170Y604765D01*
G01X488169Y609771D02*
Y609780D01*
G01X488170Y609765D02*
X488169Y609771D01*
G01X488171Y609764D02*
X488170Y609765D01*
G01X488169Y614771D02*
Y614780D01*
G01X488170Y614765D02*
X488169Y614771D01*
G01X488171Y614764D02*
X488170Y614765D01*
G01X488169Y619771D02*
Y619780D01*
G01X488170Y619765D02*
X488169Y619771D01*
G01X488171Y619764D02*
X488170Y619765D01*
G01X488169Y624771D02*
Y624780D01*
G01X488170Y624765D02*
X488169Y624771D01*
G01X488171Y624764D02*
X488170Y624765D01*
G01X488169Y629771D02*
Y629780D01*
G01X488170Y629765D02*
X488169Y629771D01*
G01X488171Y629764D02*
X488170Y629765D01*
G01X489146Y574907D02*
X489154Y574881D01*
G01X489136Y574934D02*
X489146Y574907D01*
G01X489124Y574961D02*
X489136Y574934D01*
G01X489146Y579907D02*
X489154Y579881D01*
G01X489136Y579934D02*
X489146Y579907D01*
G01X489124Y579961D02*
X489136Y579934D01*
G01X489146Y584907D02*
X489154Y584881D01*
G01X489136Y584934D02*
X489146Y584907D01*
G01X489124Y584961D02*
X489136Y584934D01*
G01X489146Y589907D02*
X489154Y589881D01*
G01X489136Y589934D02*
X489146Y589907D01*
G01X489124Y589961D02*
X489136Y589934D01*
G01X489146Y594907D02*
X489154Y594881D01*
G01X489136Y594934D02*
X489146Y594907D01*
G01X489124Y594961D02*
X489136Y594934D01*
G01X489146Y599907D02*
X489154Y599881D01*
G01X489136Y599934D02*
X489146Y599907D01*
G01X489124Y599961D02*
X489136Y599934D01*
G01X489146Y604907D02*
X489154Y604881D01*
G01X489136Y604934D02*
X489146Y604907D01*
G01X489124Y604961D02*
X489136Y604934D01*
G01X489146Y609907D02*
X489154Y609881D01*
G01X489136Y609934D02*
X489146Y609907D01*
G01X489124Y609961D02*
X489136Y609934D01*
G01X489146Y614907D02*
X489154Y614881D01*
G01X489136Y614934D02*
X489146Y614907D01*
G01X489124Y614961D02*
X489136Y614934D01*
G01X489146Y619907D02*
X489154Y619881D01*
G01X489136Y619934D02*
X489146Y619907D01*
G01X489124Y619961D02*
X489136Y619934D01*
G01X489146Y624907D02*
X489154Y624881D01*
G01X489136Y624934D02*
X489146Y624907D01*
G01X489124Y624961D02*
X489136Y624934D01*
G01X489146Y629907D02*
X489154Y629881D01*
G01X489136Y629934D02*
X489146Y629907D01*
G01X489124Y629961D02*
X489136Y629934D01*
G01Y574759D02*
X489117Y574764D01*
G01X489151Y574744D02*
X489136Y574759D01*
G01X489156Y574724D02*
X489151Y574744D01*
G01X489136Y579759D02*
X489117Y579764D01*
G01X489151Y579744D02*
X489136Y579759D01*
G01X489156Y579724D02*
X489151Y579744D01*
G01X489136Y584759D02*
X489117Y584764D01*
G01X489151Y584744D02*
X489136Y584759D01*
G01X489156Y584724D02*
X489151Y584744D01*
G01X489136Y589759D02*
X489117Y589764D01*
G01X489151Y589744D02*
X489136Y589759D01*
G01X489156Y589724D02*
X489151Y589744D01*
G01X489136Y594759D02*
X489117Y594764D01*
G01X489151Y594744D02*
X489136Y594759D01*
G01X489156Y594724D02*
X489151Y594744D01*
G01X489136Y599759D02*
X489117Y599764D01*
G01X489151Y599744D02*
X489136Y599759D01*
G01X489156Y599724D02*
X489151Y599744D01*
G01X489136Y604759D02*
X489117Y604764D01*
G01X489151Y604744D02*
X489136Y604759D01*
G01X489156Y604724D02*
X489151Y604744D01*
G01X489136Y609759D02*
X489117Y609764D01*
G01X489151Y609744D02*
X489136Y609759D01*
G01X489156Y609724D02*
X489151Y609744D01*
G01X489136Y614759D02*
X489117Y614764D01*
G01X489151Y614744D02*
X489136Y614759D01*
G01X489156Y614724D02*
X489151Y614744D01*
G01X489136Y619759D02*
X489117Y619764D01*
G01X489151Y619744D02*
X489136Y619759D01*
G01X489156Y619724D02*
X489151Y619744D01*
G01X489136Y624759D02*
X489117Y624764D01*
G01X489151Y624744D02*
X489136Y624759D01*
G01X489156Y624724D02*
X489151Y624744D01*
G01X489136Y629759D02*
X489117Y629764D01*
G01X489151Y629744D02*
X489136Y629759D01*
G01X489156Y629724D02*
X489151Y629744D01*
G01X488170Y628384D02*
X488171Y628386D01*
G01X488169Y628378D02*
X488170Y628384D01*
G01X488169Y628370D02*
Y628378D01*
G01X488170Y623384D02*
X488171Y623386D01*
G01X488169Y623378D02*
X488170Y623384D01*
G01X488169Y623370D02*
Y623378D01*
G01X488170Y618384D02*
X488171Y618386D01*
G01X488169Y618378D02*
X488170Y618384D01*
G01X488169Y618370D02*
Y618378D01*
G01X488170Y613384D02*
X488171Y613386D01*
G01X488169Y613378D02*
X488170Y613384D01*
G01X488169Y613370D02*
Y613378D01*
G01X488170Y608384D02*
X488171Y608386D01*
G01X488169Y608378D02*
X488170Y608384D01*
G01X488169Y608370D02*
Y608378D01*
G01X488170Y603384D02*
X488171Y603386D01*
G01X488169Y603378D02*
X488170Y603384D01*
G01X488169Y603370D02*
Y603378D01*
G01X488170Y598384D02*
X488171Y598386D01*
G01X488169Y598378D02*
X488170Y598384D01*
G01X488169Y598370D02*
Y598378D01*
G01X488170Y593384D02*
X488171Y593386D01*
G01X488169Y593378D02*
X488170Y593384D01*
G01X488169Y593370D02*
Y593378D01*
G01X488170Y588384D02*
X488171Y588386D01*
G01X488169Y588378D02*
X488170Y588384D01*
G01X488169Y588370D02*
Y588378D01*
G01X488170Y583384D02*
X488171Y583386D01*
G01X488169Y583378D02*
X488170Y583384D01*
G01X488169Y583370D02*
Y583378D01*
G01X488170Y578384D02*
X488171Y578386D01*
G01X488169Y578378D02*
X488170Y578384D01*
G01X488169Y578370D02*
Y578378D01*
G01X488170Y573384D02*
X488171Y573386D01*
G01X488169Y573378D02*
X488170Y573384D01*
G01X488169Y573370D02*
Y573378D01*
G01X489154Y599731D02*
Y599738D01*
G01X489155Y599726D02*
X489154Y599731D01*
G01X489156Y599724D02*
X489155Y599726D01*
G01X489154Y604731D02*
Y604738D01*
G01X489155Y604726D02*
X489154Y604731D01*
G01X489156Y604724D02*
X489155Y604726D01*
G01X489154Y609731D02*
Y609738D01*
G01X489155Y609726D02*
X489154Y609731D01*
G01X489156Y609724D02*
X489155Y609726D01*
G01X489154Y614731D02*
Y614738D01*
G01X489155Y614726D02*
X489154Y614731D01*
G01X489156Y614724D02*
X489155Y614726D01*
G01X489154Y619731D02*
Y619738D01*
G01X489155Y619726D02*
X489154Y619731D01*
G01X489156Y619724D02*
X489155Y619726D01*
G01X489154Y624731D02*
Y624738D01*
G01X489155Y624726D02*
X489154Y624731D01*
G01X489156Y624724D02*
X489155Y624726D01*
G01X489154Y629731D02*
Y629738D01*
G01X489155Y629726D02*
X489154Y629731D01*
G01X489156Y629724D02*
X489155Y629726D01*
G01X489141Y574755D02*
X489152Y574740D01*
G01X489117Y574764D02*
X489141Y574755D01*
G01Y579755D02*
X489152Y579740D01*
G01X489117Y579764D02*
X489141Y579755D01*
G01Y584755D02*
X489152Y584740D01*
G01X489117Y584764D02*
X489141Y584755D01*
G01Y589755D02*
X489152Y589740D01*
G01X489117Y589764D02*
X489141Y589755D01*
G01Y594755D02*
X489152Y594740D01*
G01X489117Y594764D02*
X489141Y594755D01*
G01X489154Y628378D02*
Y628369D01*
G01X489155Y628384D02*
X489154Y628378D01*
G01X489156Y628386D02*
X489155Y628384D01*
G01X489154Y623378D02*
Y623369D01*
G01X489155Y623384D02*
X489154Y623378D01*
G01X489156Y623386D02*
X489155Y623384D01*
G01X489154Y618378D02*
Y618369D01*
G01X489155Y618384D02*
X489154Y618378D01*
G01X489156Y618386D02*
X489155Y618384D01*
G01X489154Y613378D02*
Y613369D01*
G01X489155Y613384D02*
X489154Y613378D01*
G01X489156Y613386D02*
X489155Y613384D01*
G01X489154Y608378D02*
Y608369D01*
G01X489155Y608384D02*
X489154Y608378D01*
G01X489156Y608386D02*
X489155Y608384D01*
G01X489154Y603378D02*
Y603369D01*
G01X489155Y603384D02*
X489154Y603378D01*
G01X489156Y603386D02*
X489155Y603384D01*
G01X489154Y598378D02*
Y598369D01*
G01X489155Y598384D02*
X489154Y598378D01*
G01X489156Y598386D02*
X489155Y598384D01*
G01X489154Y593378D02*
Y593369D01*
G01X489155Y593384D02*
X489154Y593378D01*
G01X489156Y593386D02*
X489155Y593384D01*
G01X489154Y588378D02*
Y588369D01*
G01X489155Y588384D02*
X489154Y588378D01*
G01X489156Y588386D02*
X489155Y588384D01*
G01X489154Y583378D02*
Y583369D01*
G01X489155Y583384D02*
X489154Y583378D01*
G01X489156Y583386D02*
X489155Y583384D01*
G01X489154Y578378D02*
Y578369D01*
G01X489155Y578384D02*
X489154Y578378D01*
G01X489156Y578386D02*
X489155Y578384D01*
G01X489154Y573378D02*
Y573369D01*
G01X489155Y573384D02*
X489154Y573378D01*
G01X489156Y573386D02*
X489155Y573384D01*
G01X489141Y599755D02*
X489152Y599740D01*
G01X489117Y599764D02*
X489141Y599755D01*
G01Y604755D02*
X489152Y604740D01*
G01X489117Y604764D02*
X489141Y604755D01*
G01Y609755D02*
X489152Y609740D01*
G01X489117Y609764D02*
X489141Y609755D01*
G01Y614755D02*
X489152Y614740D01*
G01X489117Y614764D02*
X489141Y614755D01*
G01Y619755D02*
X489152Y619740D01*
G01X489117Y619764D02*
X489141Y619755D01*
G01Y624755D02*
X489152Y624740D01*
G01X489117Y624764D02*
X489141Y624755D01*
G01Y629755D02*
X489152Y629740D01*
G01X489117Y629764D02*
X489141Y629755D01*
G01X487598Y655256D02*
G03X487008Y655846I-590J0D01*
G01X484843Y652106D02*
G03Y654075I0J984D01*
G01X487402Y644980D02*
G03X486220Y646161I-1181J0D01*
G01X485551Y640886D02*
G03I-1890J0D01*
G01X494488Y654665D02*
G03X492520Y656634I-1969J0D01*
G01X486024Y640886D02*
G03I-2363J0D01*
G01X482480Y654075D02*
G03Y652106I0J-985D01*
G01X484843Y654075D02*
X482480D01*
G01Y652106D02*
X484843D01*
G01X482480Y641476D02*
X484843D01*
G01X482480Y639783D02*
X484843D01*
G01X490551Y636437D02*
X487402D01*
G01X489154Y630256D02*
X488169D01*
G01X488171Y629764D02*
X493504D01*
G01Y629724D02*
X489156D01*
G01X493504Y628386D02*
X488171D01*
G01X488169Y627894D02*
X489154D01*
G01Y625256D02*
X488169D01*
G01X488171Y624764D02*
X493504D01*
G01Y624724D02*
X489156D01*
G01X493504Y623386D02*
X488171D01*
G01X488169Y622894D02*
X489154D01*
G01Y620256D02*
X488169D01*
G01X488171Y619764D02*
X493504D01*
G01Y619724D02*
X489156D01*
G01X493504Y618386D02*
X488171D01*
G01X488169Y617894D02*
X489154D01*
G01Y615256D02*
X488169D01*
G01X488171Y614764D02*
X493504D01*
G01Y614724D02*
X489156D01*
G01X493504Y613386D02*
X488171D01*
G01X488169Y612894D02*
X489154D01*
G01Y610256D02*
X488169D01*
G01Y629959D02*
X489124Y629961D01*
G01X489154Y628190D02*
X488169Y628189D01*
G01Y624959D02*
X489124Y624961D01*
G01X489154Y623190D02*
X488169Y623189D01*
G01Y619959D02*
X489124Y619961D01*
G01X489154Y618190D02*
X488169Y618189D01*
G01Y614959D02*
X489124Y614961D01*
G01X489154Y613190D02*
X488169Y613189D01*
G01Y609959D02*
X489124Y609961D01*
G01X488171Y609764D02*
X493504D01*
G01Y609724D02*
X489156D01*
G01X493504Y608386D02*
X488171D01*
G01X488169Y607894D02*
X489154D01*
G01Y605256D02*
X488169D01*
G01X488171Y604764D02*
X493504D01*
G01Y604724D02*
X489156D01*
G01X493504Y603386D02*
X488171D01*
G01X488169Y602894D02*
X489154D01*
G01Y600256D02*
X488169D01*
G01X488171Y599764D02*
X493504D01*
G01Y599724D02*
X489156D01*
G01X493504Y598386D02*
X488171D01*
G01X488169Y597894D02*
X489154D01*
G01Y595256D02*
X488169D01*
G01X488171Y594764D02*
X493504D01*
G01Y594724D02*
X489156D01*
G01X493504Y593386D02*
X488171D01*
G01X488169Y592894D02*
X489154D01*
G01Y590256D02*
X488169D01*
G01X488171Y589764D02*
X493504D01*
G01Y589724D02*
X489156D01*
G01X493504Y588386D02*
X488171D01*
G01X488169Y587894D02*
X489154D01*
G01Y585256D02*
X488169D01*
G01X488171Y584764D02*
X493504D01*
G01Y584724D02*
X489156D01*
G01X493504Y583386D02*
X488171D01*
G01X488169Y582894D02*
X489154D01*
G01Y580256D02*
X488169D01*
G01X488171Y579764D02*
X493504D01*
G01Y579724D02*
X489156D01*
G01X493504Y578386D02*
X488171D01*
G01X488169Y577894D02*
X489154D01*
G01Y575256D02*
X488169D01*
G01X488171Y574764D02*
X493504D01*
G01Y574724D02*
X489156D01*
G01X493504Y573386D02*
X488171D01*
G01X488169Y572894D02*
X489154D01*
G01Y608190D02*
X488169Y608189D01*
G01Y604959D02*
X489124Y604961D01*
G01X489154Y603190D02*
X488169Y603189D01*
G01Y599959D02*
X489124Y599961D01*
G01X489154Y598190D02*
X488169Y598189D01*
G01Y594959D02*
X489124Y594961D01*
G01X489154Y593190D02*
X488169Y593189D01*
G01Y589959D02*
X489124Y589961D01*
G01X489154Y588190D02*
X488169Y588189D01*
G01Y584959D02*
X489124Y584961D01*
G01X489154Y583190D02*
X488169Y583189D01*
G01Y579959D02*
X489124Y579961D01*
G01X489154Y578190D02*
X488169Y578189D01*
G01Y574959D02*
X489124Y574961D01*
G01X489154Y573190D02*
X488169Y573189D01*
G01X494488Y638917D02*
X491142Y635571D01*
G01X484646Y632894D02*
X485827Y634075D01*
G01X487153Y645706D02*
X484843Y641476D01*
G01Y639783D02*
X486146Y637815D01*
G01X489154Y574738D02*
Y574746D01*
G01Y579738D02*
Y579746D01*
G01Y584738D02*
Y584746D01*
G01Y589738D02*
Y589746D01*
G01Y594738D02*
Y594746D01*
G01Y599738D02*
Y599746D01*
G01Y604738D02*
Y604746D01*
G01Y609738D02*
Y609746D01*
G01Y614738D02*
Y614746D01*
G01Y619738D02*
Y619746D01*
G01Y624738D02*
Y624746D01*
G01Y629738D02*
Y629746D01*
G01X494488Y638917D02*
Y654665D01*
G01X493504Y628386D02*
Y629764D01*
G01Y623386D02*
Y624764D01*
G01Y618386D02*
Y619764D01*
G01Y613386D02*
Y614764D01*
G01Y608386D02*
Y609764D01*
G01Y603386D02*
Y604764D01*
G01Y598386D02*
Y599764D01*
G01Y593386D02*
Y594764D01*
G01Y588386D02*
Y589764D01*
G01Y583386D02*
Y584764D01*
G01Y578386D02*
Y579764D01*
G01Y573386D02*
Y574764D01*
G01X490335D02*
Y573386D01*
G01Y579764D02*
Y578386D01*
G01Y584764D02*
Y583386D01*
G01Y589764D02*
Y588386D01*
G01Y594764D02*
Y593386D01*
G01Y599764D02*
Y598386D01*
G01Y604764D02*
Y603386D01*
G01Y609764D02*
Y608386D01*
G01Y614764D02*
Y613386D01*
G01Y619764D02*
Y618386D01*
G01Y624764D02*
Y623386D01*
G01Y629764D02*
Y628386D01*
G01X489154Y627894D02*
Y630256D01*
G01Y622894D02*
Y625256D01*
G01Y617894D02*
Y620256D01*
G01Y612894D02*
Y615256D01*
G01Y607894D02*
Y610256D01*
G01Y602894D02*
Y605256D01*
G01Y597894D02*
Y600256D01*
G01Y592894D02*
Y595256D01*
G01Y587894D02*
Y590256D01*
G01Y582894D02*
Y585256D01*
G01Y577894D02*
Y580256D01*
G01Y572894D02*
Y575256D01*
G01X488169D02*
Y572894D01*
G01Y580256D02*
Y577894D01*
G01Y585256D02*
Y582894D01*
G01Y590256D02*
Y587894D01*
G01Y595256D02*
Y592894D01*
G01Y600256D02*
Y597894D01*
G01Y605256D02*
Y602894D01*
G01Y610256D02*
Y607894D01*
G01Y615256D02*
Y612894D01*
G01Y620256D02*
Y617894D01*
G01Y625256D02*
Y622894D01*
G01Y630256D02*
Y627894D01*
G01X487598Y649154D02*
Y655256D01*
G01X487402Y644980D02*
Y636437D01*
G01X484843Y641476D02*
Y639783D01*
G01X482480D02*
Y641476D01*
G01X523327Y715748D02*
G03X483169I-20079J0D01*
G01D02*
G03X523327I20079J0D01*
G01X567913Y713386D02*
G03X569094I591J0D01*
G01Y707087D02*
G03X567913I-590J0D01*
G01X565945D02*
G03X564764I-590J0D01*
G01Y713386D02*
G03X565945I590J0D01*
G01X567913D02*
G03X569094I591J0D01*
G01Y707087D02*
G03X567913I-590J0D01*
G01X565945D02*
G03X564764I-590J0D01*
G01Y713386D02*
G03X565945I590J0D01*
G01X523327Y715748D02*
G03I-20079J0D01*
G01X567913Y713386D02*
X565945D01*
G01X564764D02*
X563976D01*
G01X567913D02*
X565945D01*
G01X564764D02*
X563976D01*
G01X569882D02*
X569094D01*
G01X569882D02*
X569094D01*
G01X569882Y712402D02*
X563976D01*
G01Y712205D02*
X569882D01*
G01X563976Y708268D02*
X569882D01*
G01Y708071D02*
X563976D01*
G01X569094Y707087D02*
X569882D01*
G01X569094D02*
X569882D01*
G01X565945D02*
X567913D01*
G01X563976D02*
X564764D01*
G01X565945D02*
X567913D01*
G01X563976D02*
X564764D01*
G01X569882D02*
Y713386D01*
G01Y707087D02*
Y713386D01*
G01X563976Y707087D02*
Y713386D01*
G01D02*
Y707087D01*
G01X487008Y930059D02*
G03X487598Y930650I0J590D01*
G01X484843Y931831D02*
G03Y933799I0J984D01*
G01X484764Y945020D02*
G03I-1103J0D01*
G01X486220Y939744D02*
G03X487402Y940925I1J1181D01*
G01X485236Y945020D02*
G03I-1575J0D01*
G01X492520Y929272D02*
G03X494488Y931240I0J1968D01*
G01X482480Y933799D02*
G03Y931831I0J-984D01*
G01X487402Y949469D02*
X490551D01*
G01X484843Y946122D02*
X482480D01*
G01X484843Y944429D02*
X482480D01*
G01X484843Y933799D02*
X482480D01*
G01Y931831D02*
X484843D01*
G01X491142Y950335D02*
X494488Y946988D01*
G01X484646Y953012D02*
X485827Y951831D01*
G01X484843Y944429D02*
X487153Y940200D01*
G01X494488Y931240D02*
Y946988D01*
G01X491142Y1088327D02*
Y950335D01*
G01X490551Y1090571D02*
Y948091D01*
G01X487598Y936752D02*
Y930650D01*
G01X487402Y949469D02*
Y940925D01*
G01X485827Y988287D02*
Y951831D01*
G01X486146Y948091D02*
X484843Y946122D01*
G01D02*
Y944429D01*
G01X482480D02*
Y946122D01*
G01X488170Y1046140D02*
X488171Y1046142D01*
G01X488169Y1046134D02*
X488170Y1046140D01*
G01X488169Y1046126D02*
Y1046134D01*
G01X488170Y1041140D02*
X488171Y1041142D01*
G01X488169Y1041134D02*
X488170Y1041140D01*
G01X488169Y1041126D02*
Y1041134D01*
G01X488170Y1036140D02*
X488171Y1036142D01*
G01X488169Y1036134D02*
X488170Y1036140D01*
G01X488169Y1036126D02*
Y1036134D01*
G01X488170Y1031140D02*
X488171Y1031142D01*
G01X488169Y1031134D02*
X488170Y1031140D01*
G01X488169Y1031126D02*
Y1031134D01*
G01X488170Y1026140D02*
X488171Y1026142D01*
G01X488169Y1026134D02*
X488170Y1026140D01*
G01X488169Y1026126D02*
Y1026134D01*
G01X488170Y1021140D02*
X488171Y1021142D01*
G01X488169Y1021134D02*
X488170Y1021140D01*
G01X488169Y1021126D02*
Y1021134D01*
G01X488170Y1016140D02*
X488171Y1016142D01*
G01X488169Y1016134D02*
X488170Y1016140D01*
G01X488169Y1016126D02*
Y1016134D01*
G01X488170Y1011140D02*
X488171Y1011142D01*
G01X488169Y1011134D02*
X488170Y1011140D01*
G01X488169Y1011126D02*
Y1011134D01*
G01X488170Y986140D02*
X488171Y986142D01*
G01X488169Y986134D02*
X488170Y986140D01*
G01X488169Y986126D02*
Y986134D01*
G01X488170Y981140D02*
X488171Y981142D01*
G01X488169Y981134D02*
X488170Y981140D01*
G01X488169Y981126D02*
Y981134D01*
G01X488170Y976140D02*
X488171Y976142D01*
G01X488169Y976134D02*
X488170Y976140D01*
G01X488169Y976126D02*
Y976134D01*
G01X488170Y971140D02*
X488171Y971142D01*
G01X488169Y971134D02*
X488170Y971140D01*
G01X488169Y971126D02*
Y971134D01*
G01X488170Y966140D02*
X488171Y966142D01*
G01X488169Y966134D02*
X488170Y966140D01*
G01X488169Y966126D02*
Y966134D01*
G01X488170Y961140D02*
X488171Y961142D01*
G01X488169Y961134D02*
X488170Y961140D01*
G01X488169Y961126D02*
Y961134D01*
G01X488170Y956140D02*
X488171Y956142D01*
G01X488169Y956134D02*
X488170Y956140D01*
G01X488169Y956126D02*
Y956134D01*
G01X489154Y1046134D02*
Y1046125D01*
G01X489155Y1046140D02*
X489154Y1046134D01*
G01X489156Y1046142D02*
X489155Y1046140D01*
G01X489154Y1041134D02*
Y1041125D01*
G01X489155Y1041140D02*
X489154Y1041134D01*
G01X489156Y1041142D02*
X489155Y1041140D01*
G01X489154Y1036134D02*
Y1036125D01*
G01X489155Y1036140D02*
X489154Y1036134D01*
G01X489156Y1036142D02*
X489155Y1036140D01*
G01X489154Y1031134D02*
Y1031125D01*
G01X489155Y1031140D02*
X489154Y1031134D01*
G01X489156Y1031142D02*
X489155Y1031140D01*
G01X489154Y1026134D02*
Y1026125D01*
G01X489155Y1026140D02*
X489154Y1026134D01*
G01X489156Y1026142D02*
X489155Y1026140D01*
G01X489154Y1021134D02*
Y1021125D01*
G01X489155Y1021140D02*
X489154Y1021134D01*
G01X489156Y1021142D02*
X489155Y1021140D01*
G01X489154Y1016134D02*
Y1016125D01*
G01X489155Y1016140D02*
X489154Y1016134D01*
G01X489156Y1016142D02*
X489155Y1016140D01*
G01X489154Y1011134D02*
Y1011125D01*
G01X489155Y1011140D02*
X489154Y1011134D01*
G01X489156Y1011142D02*
X489155Y1011140D01*
G01X489154Y986134D02*
Y986125D01*
G01X489155Y986140D02*
X489154Y986134D01*
G01X489156Y986142D02*
X489155Y986140D01*
G01X489154Y981134D02*
Y981125D01*
G01X489155Y981140D02*
X489154Y981134D01*
G01X489156Y981142D02*
X489155Y981140D01*
G01X489154Y976134D02*
Y976125D01*
G01X489155Y976140D02*
X489154Y976134D01*
G01X489156Y976142D02*
X489155Y976140D01*
G01X489154Y971134D02*
Y971125D01*
G01X489155Y971140D02*
X489154Y971134D01*
G01X489156Y971142D02*
X489155Y971140D01*
G01X489154Y966134D02*
Y966125D01*
G01X489155Y966140D02*
X489154Y966134D01*
G01X489156Y966142D02*
X489155Y966140D01*
G01X489154Y961134D02*
Y961125D01*
G01X489155Y961140D02*
X489154Y961134D01*
G01X489156Y961142D02*
X489155Y961140D01*
G01X489154Y956134D02*
Y956125D01*
G01X489155Y956140D02*
X489154Y956134D01*
G01X489156Y956142D02*
X489155Y956140D01*
G01X489120Y957618D02*
X489124Y957717D01*
G01X489115Y957546D02*
X489120Y957618D01*
G01X489117Y957520D02*
X489115Y957546D01*
G01X489120Y962618D02*
X489124Y962717D01*
G01X489115Y962546D02*
X489120Y962618D01*
G01X489117Y962520D02*
X489115Y962546D01*
G01X489120Y967618D02*
X489124Y967717D01*
G01X489115Y967546D02*
X489120Y967618D01*
G01X489117Y967520D02*
X489115Y967546D01*
G01X489120Y972618D02*
X489124Y972717D01*
G01X489115Y972546D02*
X489120Y972618D01*
G01X489117Y972520D02*
X489115Y972546D01*
G01X489120Y977618D02*
X489124Y977717D01*
G01X489115Y977546D02*
X489120Y977618D01*
G01X489117Y977520D02*
X489115Y977546D01*
G01X489120Y982618D02*
X489124Y982717D01*
G01X489115Y982546D02*
X489120Y982618D01*
G01X489117Y982520D02*
X489115Y982546D01*
G01X489120Y987618D02*
X489124Y987717D01*
G01X489115Y987546D02*
X489120Y987618D01*
G01X489117Y987520D02*
X489115Y987546D01*
G01X489120Y1012618D02*
X489124Y1012717D01*
G01X489115Y1012546D02*
X489120Y1012618D01*
G01X489117Y1012520D02*
X489115Y1012546D01*
G01X489120Y1017618D02*
X489124Y1017717D01*
G01X489115Y1017546D02*
X489120Y1017618D01*
G01X489117Y1017520D02*
X489115Y1017546D01*
G01X489120Y1022618D02*
X489124Y1022717D01*
G01X489115Y1022546D02*
X489120Y1022618D01*
G01X489117Y1022520D02*
X489115Y1022546D01*
G01X489120Y1027618D02*
X489124Y1027717D01*
G01X489115Y1027546D02*
X489120Y1027618D01*
G01X489117Y1027520D02*
X489115Y1027546D01*
G01X489120Y1032618D02*
X489124Y1032717D01*
G01X489115Y1032546D02*
X489120Y1032618D01*
G01X489117Y1032520D02*
X489115Y1032546D01*
G01X489120Y1037618D02*
X489124Y1037717D01*
G01X489115Y1037546D02*
X489120Y1037618D01*
G01X489117Y1037520D02*
X489115Y1037546D01*
G01X489120Y1042618D02*
X489124Y1042717D01*
G01X489115Y1042546D02*
X489120Y1042618D01*
G01X489117Y1042520D02*
X489115Y1042546D01*
G01X489136Y957515D02*
X489117Y957520D01*
G01X489151Y957500D02*
X489136Y957515D01*
G01X489156Y957480D02*
X489151Y957500D01*
G01X489136Y962515D02*
X489117Y962520D01*
G01X489151Y962500D02*
X489136Y962515D01*
G01X489156Y962480D02*
X489151Y962500D01*
G01X489136Y967515D02*
X489117Y967520D01*
G01X489151Y967500D02*
X489136Y967515D01*
G01X489156Y967480D02*
X489151Y967500D01*
G01X489136Y972515D02*
X489117Y972520D01*
G01X489151Y972500D02*
X489136Y972515D01*
G01X489156Y972480D02*
X489151Y972500D01*
G01X489136Y977515D02*
X489117Y977520D01*
G01X489151Y977500D02*
X489136Y977515D01*
G01X489156Y977480D02*
X489151Y977500D01*
G01X489136Y982515D02*
X489117Y982520D01*
G01X489151Y982500D02*
X489136Y982515D01*
G01X489156Y982480D02*
X489151Y982500D01*
G01X489136Y987515D02*
X489117Y987520D01*
G01X489151Y987500D02*
X489136Y987515D01*
G01X489156Y987480D02*
X489151Y987500D01*
G01X488169Y957527D02*
Y957536D01*
G01X488170Y957521D02*
X488169Y957527D01*
G01X488171Y957520D02*
X488170Y957521D01*
G01X488169Y962527D02*
Y962536D01*
G01X488170Y962521D02*
X488169Y962527D01*
G01X488171Y962520D02*
X488170Y962521D01*
G01X488169Y967527D02*
Y967536D01*
G01X488170Y967521D02*
X488169Y967527D01*
G01X488171Y967520D02*
X488170Y967521D01*
G01X488169Y972527D02*
Y972536D01*
G01X488170Y972521D02*
X488169Y972527D01*
G01X488171Y972520D02*
X488170Y972521D01*
G01X488169Y977527D02*
Y977536D01*
G01X488170Y977521D02*
X488169Y977527D01*
G01X488171Y977520D02*
X488170Y977521D01*
G01X488169Y982527D02*
Y982536D01*
G01X488170Y982521D02*
X488169Y982527D01*
G01X488171Y982520D02*
X488170Y982521D01*
G01X488169Y987527D02*
Y987536D01*
G01X488170Y987521D02*
X488169Y987527D01*
G01X488171Y987520D02*
X488170Y987521D01*
G01X488169Y1012527D02*
Y1012536D01*
G01X488170Y1012521D02*
X488169Y1012527D01*
G01X488171Y1012520D02*
X488170Y1012521D01*
G01X488169Y1017527D02*
Y1017536D01*
G01X488170Y1017521D02*
X488169Y1017527D01*
G01X488171Y1017520D02*
X488170Y1017521D01*
G01X488169Y1022527D02*
Y1022536D01*
G01X488170Y1022521D02*
X488169Y1022527D01*
G01X488171Y1022520D02*
X488170Y1022521D01*
G01X488169Y1027527D02*
Y1027536D01*
G01X488170Y1027521D02*
X488169Y1027527D01*
G01X488171Y1027520D02*
X488170Y1027521D01*
G01X488169Y1032527D02*
Y1032536D01*
G01X488170Y1032521D02*
X488169Y1032527D01*
G01X488171Y1032520D02*
X488170Y1032521D01*
G01X488169Y1037527D02*
Y1037536D01*
G01X488170Y1037521D02*
X488169Y1037527D01*
G01X488171Y1037520D02*
X488170Y1037521D01*
G01X488169Y1042527D02*
Y1042536D01*
G01X488170Y1042521D02*
X488169Y1042527D01*
G01X488171Y1042520D02*
X488170Y1042521D01*
G01X488171Y1047520D02*
X488170Y1047521D01*
G01X489146Y957663D02*
X489154Y957637D01*
G01X489136Y957690D02*
X489146Y957663D01*
G01X489124Y957717D02*
X489136Y957690D01*
G01X489146Y962663D02*
X489154Y962637D01*
G01X489136Y962690D02*
X489146Y962663D01*
G01X489124Y962717D02*
X489136Y962690D01*
G01X489146Y967663D02*
X489154Y967637D01*
G01X489136Y967690D02*
X489146Y967663D01*
G01X489124Y967717D02*
X489136Y967690D01*
G01X489146Y972663D02*
X489154Y972637D01*
G01X489136Y972690D02*
X489146Y972663D01*
G01X489124Y972717D02*
X489136Y972690D01*
G01X489146Y977663D02*
X489154Y977637D01*
G01X489136Y977690D02*
X489146Y977663D01*
G01X489124Y977717D02*
X489136Y977690D01*
G01X489146Y982663D02*
X489154Y982637D01*
G01X489136Y982690D02*
X489146Y982663D01*
G01X489124Y982717D02*
X489136Y982690D01*
G01X489146Y987663D02*
X489154Y987637D01*
G01X489136Y987690D02*
X489146Y987663D01*
G01X489124Y987717D02*
X489136Y987690D01*
G01X489146Y1012663D02*
X489154Y1012637D01*
G01X489136Y1012690D02*
X489146Y1012663D01*
G01X489124Y1012717D02*
X489136Y1012690D01*
G01X489146Y1017663D02*
X489154Y1017637D01*
G01X489136Y1017690D02*
X489146Y1017663D01*
G01X489124Y1017717D02*
X489136Y1017690D01*
G01X489146Y1022663D02*
X489154Y1022637D01*
G01X489136Y1022690D02*
X489146Y1022663D01*
G01X489124Y1022717D02*
X489136Y1022690D01*
G01X489146Y1027663D02*
X489154Y1027637D01*
G01X489136Y1027690D02*
X489146Y1027663D01*
G01X489124Y1027717D02*
X489136Y1027690D01*
G01X489146Y1032663D02*
X489154Y1032637D01*
G01X489136Y1032690D02*
X489146Y1032663D01*
G01X489124Y1032717D02*
X489136Y1032690D01*
G01X489146Y1037663D02*
X489154Y1037637D01*
G01X489136Y1037690D02*
X489146Y1037663D01*
G01X489124Y1037717D02*
X489136Y1037690D01*
G01X489146Y1042663D02*
X489154Y1042637D01*
G01X489136Y1042690D02*
X489146Y1042663D01*
G01X489124Y1042717D02*
X489136Y1042690D01*
G01Y1012515D02*
X489117Y1012520D01*
G01X489151Y1012500D02*
X489136Y1012515D01*
G01X489156Y1012480D02*
X489151Y1012500D01*
G01X489136Y1017515D02*
X489117Y1017520D01*
G01X489151Y1017500D02*
X489136Y1017515D01*
G01X489156Y1017480D02*
X489151Y1017500D01*
G01X489136Y1022515D02*
X489117Y1022520D01*
G01X489151Y1022500D02*
X489136Y1022515D01*
G01X489156Y1022480D02*
X489151Y1022500D01*
G01X489136Y1027515D02*
X489117Y1027520D01*
G01X489151Y1027500D02*
X489136Y1027515D01*
G01X489156Y1027480D02*
X489151Y1027500D01*
G01X489136Y1032515D02*
X489117Y1032520D01*
G01X489151Y1032500D02*
X489136Y1032515D01*
G01X489156Y1032480D02*
X489151Y1032500D01*
G01X489136Y1037515D02*
X489117Y1037520D01*
G01X489151Y1037500D02*
X489136Y1037515D01*
G01X489156Y1037480D02*
X489151Y1037500D01*
G01X489136Y1042515D02*
X489117Y1042520D01*
G01X489151Y1042500D02*
X489136Y1042515D01*
G01X489156Y1042480D02*
X489151Y1042500D01*
G01X489136Y1047515D02*
X489117Y1047520D01*
G01X489151Y1047500D02*
X489136Y1047515D01*
G01X489156Y1047480D02*
X489151Y1047500D01*
G01X489154Y957487D02*
Y957494D01*
G01X489155Y957482D02*
X489154Y957487D01*
G01X489156Y957480D02*
X489155Y957482D01*
G01X489154Y962487D02*
Y962494D01*
G01X489155Y962482D02*
X489154Y962487D01*
G01X489156Y962480D02*
X489155Y962482D01*
G01X489154Y967487D02*
Y967494D01*
G01X489155Y967482D02*
X489154Y967487D01*
G01X489156Y967480D02*
X489155Y967482D01*
G01X489154Y972487D02*
Y972494D01*
G01X489155Y972482D02*
X489154Y972487D01*
G01X489156Y972480D02*
X489155Y972482D01*
G01X489154Y977487D02*
Y977494D01*
G01X489155Y977482D02*
X489154Y977487D01*
G01X489156Y977480D02*
X489155Y977482D01*
G01X489154Y982487D02*
Y982494D01*
G01X489155Y982482D02*
X489154Y982487D01*
G01X489156Y982480D02*
X489155Y982482D01*
G01X489154Y987487D02*
Y987494D01*
G01X489155Y987482D02*
X489154Y987487D01*
G01X489156Y987480D02*
X489155Y987482D01*
G01X489154Y1012487D02*
Y1012494D01*
G01X489155Y1012482D02*
X489154Y1012487D01*
G01X489156Y1012480D02*
X489155Y1012482D01*
G01X489154Y1017487D02*
Y1017494D01*
G01X489155Y1017482D02*
X489154Y1017487D01*
G01X489156Y1017480D02*
X489155Y1017482D01*
G01X489154Y1022487D02*
Y1022494D01*
G01X489155Y1022482D02*
X489154Y1022487D01*
G01X489156Y1022480D02*
X489155Y1022482D01*
G01X489154Y1027487D02*
Y1027494D01*
G01X489155Y1027482D02*
X489154Y1027487D01*
G01X489156Y1027480D02*
X489155Y1027482D01*
G01X489154Y1032487D02*
Y1032494D01*
G01X489155Y1032482D02*
X489154Y1032487D01*
G01X489156Y1032480D02*
X489155Y1032482D01*
G01X489154Y1037487D02*
Y1037494D01*
G01X489155Y1037482D02*
X489154Y1037487D01*
G01X489156Y1037480D02*
X489155Y1037482D01*
G01X489154Y1042487D02*
Y1042494D01*
G01X489155Y1042482D02*
X489154Y1042487D01*
G01X489156Y1042480D02*
X489155Y1042482D01*
G01Y1047482D02*
X489154Y1047487D01*
G01X489156Y1047480D02*
X489155Y1047482D01*
G01X489141Y957511D02*
X489152Y957496D01*
G01X489117Y957520D02*
X489141Y957511D01*
G01Y962511D02*
X489152Y962496D01*
G01X489117Y962520D02*
X489141Y962511D01*
G01Y967511D02*
X489152Y967496D01*
G01X489117Y967520D02*
X489141Y967511D01*
G01Y972511D02*
X489152Y972496D01*
G01X489117Y972520D02*
X489141Y972511D01*
G01Y977511D02*
X489152Y977496D01*
G01X489117Y977520D02*
X489141Y977511D01*
G01Y982511D02*
X489152Y982496D01*
G01X489117Y982520D02*
X489141Y982511D01*
G01Y987511D02*
X489152Y987496D01*
G01X489117Y987520D02*
X489141Y987511D01*
G01Y1012511D02*
X489152Y1012496D01*
G01X489117Y1012520D02*
X489141Y1012511D01*
G01Y1017511D02*
X489152Y1017496D01*
G01X489117Y1017520D02*
X489141Y1017511D01*
G01Y1022511D02*
X489152Y1022496D01*
G01X489117Y1022520D02*
X489141Y1022511D01*
G01Y1027511D02*
X489152Y1027496D01*
G01X489117Y1027520D02*
X489141Y1027511D01*
G01Y1032511D02*
X489152Y1032496D01*
G01X489117Y1032520D02*
X489141Y1032511D01*
G01Y1037511D02*
X489152Y1037496D01*
G01X489117Y1037520D02*
X489141Y1037511D01*
G01Y1042511D02*
X489152Y1042496D01*
G01X489117Y1042520D02*
X489141Y1042511D01*
G01Y1047511D02*
X489152Y1047496D01*
G01X489117Y1047520D02*
X489141Y1047511D01*
G01X493504Y1046142D02*
X488171D01*
G01X488169Y1045650D02*
X489154D01*
G01Y1043012D02*
X488169D01*
G01X488171Y1042520D02*
X493504D01*
G01Y1042480D02*
X489156D01*
G01X493504Y1041142D02*
X488171D01*
G01X488169Y1040650D02*
X489154D01*
G01Y1038012D02*
X488169D01*
G01X488171Y1037520D02*
X493504D01*
G01Y1037480D02*
X489156D01*
G01X493504Y1036142D02*
X488171D01*
G01X488169Y1035650D02*
X489154D01*
G01Y1033012D02*
X488169D01*
G01X488171Y1032520D02*
X493504D01*
G01Y1032480D02*
X489156D01*
G01X493504Y1031142D02*
X488171D01*
G01X488169Y1030650D02*
X489154D01*
G01Y1028012D02*
X488169D01*
G01X488171Y1027520D02*
X493504D01*
G01Y1027480D02*
X489156D01*
G01X493504Y1026142D02*
X488171D01*
G01X488169Y1025650D02*
X489154D01*
G01Y1023012D02*
X488169D01*
G01X488171Y1022520D02*
X493504D01*
G01Y1022480D02*
X489156D01*
G01X493504Y1021142D02*
X488171D01*
G01X489154Y1045946D02*
X488169Y1045945D01*
G01Y1042715D02*
X489124Y1042717D01*
G01X489154Y1040946D02*
X488169Y1040945D01*
G01Y1037715D02*
X489124Y1037717D01*
G01X489154Y1035946D02*
X488169Y1035945D01*
G01Y1032715D02*
X489124Y1032717D01*
G01X489154Y1030946D02*
X488169Y1030945D01*
G01Y1027715D02*
X489124Y1027717D01*
G01X489154Y1025946D02*
X488169Y1025945D01*
G01Y1022715D02*
X489124Y1022717D01*
G01X489154Y1020946D02*
X488169Y1020945D01*
G01Y1020650D02*
X489154D01*
G01Y1018012D02*
X488169D01*
G01X488171Y1017520D02*
X493504D01*
G01Y1017480D02*
X489156D01*
G01X493504Y1016142D02*
X488171D01*
G01X488169Y1015650D02*
X489154D01*
G01Y1013012D02*
X488169D01*
G01X488171Y1012520D02*
X493504D01*
G01Y1012480D02*
X489156D01*
G01X493504Y1011142D02*
X488171D01*
G01X488169Y1010650D02*
X489154D01*
G01X485827Y1010374D02*
X489764D01*
G01X484646Y1009193D02*
X488583D01*
G01Y989469D02*
X484646D01*
G01X489764Y988287D02*
X485827D01*
G01X489154Y988012D02*
X488169D01*
G01X488171Y987520D02*
X493504D01*
G01Y987480D02*
X489156D01*
G01X493504Y986142D02*
X488171D01*
G01X488169Y985650D02*
X489154D01*
G01Y983012D02*
X488169D01*
G01X488171Y982520D02*
X493504D01*
G01Y982480D02*
X489156D01*
G01X493504Y981142D02*
X488171D01*
G01X488169Y980650D02*
X489154D01*
G01Y978012D02*
X488169D01*
G01X488171Y977520D02*
X493504D01*
G01Y977480D02*
X489156D01*
G01X493504Y976142D02*
X488171D01*
G01X488169Y975650D02*
X489154D01*
G01Y973012D02*
X488169D01*
G01X488171Y972520D02*
X493504D01*
G01Y972480D02*
X489156D01*
G01X493504Y971142D02*
X488171D01*
G01X488169Y970650D02*
X489154D01*
G01Y968012D02*
X488169D01*
G01X488171Y967520D02*
X493504D01*
G01Y967480D02*
X489156D01*
G01X493504Y966142D02*
X488171D01*
G01X488169Y965650D02*
X489154D01*
G01Y963012D02*
X488169D01*
G01X488171Y962520D02*
X493504D01*
G01Y962480D02*
X489156D01*
G01X493504Y961142D02*
X488171D01*
G01X488169Y960650D02*
X489154D01*
G01Y958012D02*
X488169D01*
G01X488171Y957520D02*
X493504D01*
G01Y957480D02*
X489156D01*
G01X493504Y956142D02*
X488171D01*
G01X488169Y955650D02*
X489154D01*
G01X488169Y1017715D02*
X489124Y1017717D01*
G01X489154Y1015946D02*
X488169Y1015945D01*
G01Y1012715D02*
X489124Y1012717D01*
G01X489154Y1010946D02*
X488169Y1010945D01*
G01Y987715D02*
X489124Y987717D01*
G01X489154Y985946D02*
X488169Y985945D01*
G01Y982715D02*
X489124Y982717D01*
G01X489154Y980946D02*
X488169Y980945D01*
G01Y977715D02*
X489124Y977717D01*
G01X489154Y975946D02*
X488169Y975945D01*
G01Y972715D02*
X489124Y972717D01*
G01X489154Y970946D02*
X488169Y970945D01*
G01Y967715D02*
X489124Y967717D01*
G01X489154Y965946D02*
X488169Y965945D01*
G01Y962715D02*
X489124Y962717D01*
G01X489154Y960946D02*
X488169Y960945D01*
G01Y957715D02*
X489124Y957717D01*
G01X489154Y955946D02*
X488169Y955945D01*
G01X488583Y989469D02*
X489764Y988287D01*
G01X484646Y989469D02*
X485827Y988287D01*
G01X493504Y1046142D02*
Y1047520D01*
G01Y1041142D02*
Y1042520D01*
G01Y1036142D02*
Y1037520D01*
G01Y1031142D02*
Y1032520D01*
G01Y1026142D02*
Y1027520D01*
G01Y1021142D02*
Y1022520D01*
G01Y1016142D02*
Y1017520D01*
G01Y1011142D02*
Y1012520D01*
G01Y986142D02*
Y987520D01*
G01Y981142D02*
Y982520D01*
G01Y976142D02*
Y977520D01*
G01Y971142D02*
Y972520D01*
G01Y966142D02*
Y967520D01*
G01Y961142D02*
Y962520D01*
G01Y956142D02*
Y957520D01*
G01X490335D02*
Y956142D01*
G01Y962520D02*
Y961142D01*
G01Y967520D02*
Y966142D01*
G01Y972520D02*
Y971142D01*
G01Y977520D02*
Y976142D01*
G01Y982520D02*
Y981142D01*
G01Y987520D02*
Y986142D01*
G01Y1012520D02*
Y1011142D01*
G01Y1017520D02*
Y1016142D01*
G01Y1022520D02*
Y1021142D01*
G01Y1027520D02*
Y1026142D01*
G01Y1032520D02*
Y1031142D01*
G01Y1037520D02*
Y1036142D01*
G01Y1042520D02*
Y1041142D01*
G01Y1047520D02*
Y1046142D01*
G01X489764Y1010374D02*
Y988287D01*
G01X489154Y1045650D02*
Y1048012D01*
G01Y1040650D02*
Y1043012D01*
G01Y1035650D02*
Y1038012D01*
G01Y1030650D02*
Y1033012D01*
G01Y1025650D02*
Y1028012D01*
G01Y1020650D02*
Y1023012D01*
G01Y1015650D02*
Y1018012D01*
G01Y1010650D02*
Y1013012D01*
G01Y985650D02*
Y988012D01*
G01Y980650D02*
Y983012D01*
G01Y975650D02*
Y978012D01*
G01Y970650D02*
Y973012D01*
G01Y965650D02*
Y968012D01*
G01Y960650D02*
Y963012D01*
G01Y955650D02*
Y958012D01*
G01Y962494D02*
Y962637D01*
G01Y967494D02*
Y967637D01*
G01Y972494D02*
Y972637D01*
G01Y977494D02*
Y977637D01*
G01Y982494D02*
Y982637D01*
G01Y987494D02*
Y987637D01*
G01Y1012494D02*
Y1012637D01*
G01Y1017494D02*
Y1017637D01*
G01Y1022494D02*
Y1022637D01*
G01Y1027494D02*
Y1027637D01*
G01Y1032494D02*
Y1032637D01*
G01Y1037494D02*
Y1037637D01*
G01Y1042494D02*
Y1042637D01*
G01X488583Y1009193D02*
Y989469D01*
G01X488169Y958012D02*
Y955650D01*
G01Y963012D02*
Y960650D01*
G01Y968012D02*
Y965650D01*
G01Y973012D02*
Y970650D01*
G01Y978012D02*
Y975650D01*
G01Y983012D02*
Y980650D01*
G01Y988012D02*
Y985650D01*
G01Y1013012D02*
Y1010650D01*
G01Y1018012D02*
Y1015650D01*
G01Y1023012D02*
Y1020650D01*
G01Y1028012D02*
Y1025650D01*
G01Y1033012D02*
Y1030650D01*
G01Y1038012D02*
Y1035650D01*
G01Y1043012D02*
Y1040650D01*
G01Y1048012D02*
Y1045650D01*
G01X485827Y1086831D02*
Y1010374D01*
G01X488583Y1009193D02*
X489764Y1010374D01*
G01X484646Y1009193D02*
X485827Y1010374D01*
G01X489154Y957494D02*
Y957502D01*
G01Y962494D02*
Y962502D01*
G01Y967494D02*
Y967502D01*
G01Y972494D02*
Y972502D01*
G01Y977494D02*
Y977502D01*
G01Y982494D02*
Y982502D01*
G01Y987494D02*
Y987502D01*
G01Y1012494D02*
Y1012502D01*
G01Y1017494D02*
Y1017502D01*
G01Y1022494D02*
Y1022502D01*
G01Y1027494D02*
Y1027502D01*
G01Y1032494D02*
Y1032502D01*
G01Y1037494D02*
Y1037502D01*
G01Y1042494D02*
Y1042502D01*
G01X484646Y989469D02*
Y953012D01*
G01Y1085650D02*
Y1009193D01*
G01X489154Y1081134D02*
Y1081125D01*
G01X489155Y1081140D02*
X489154Y1081134D01*
G01X489156Y1081142D02*
X489155Y1081140D01*
G01X489154Y1076134D02*
Y1076125D01*
G01X489155Y1076140D02*
X489154Y1076134D01*
G01X489156Y1076142D02*
X489155Y1076140D01*
G01X489154Y1071134D02*
Y1071125D01*
G01X489155Y1071140D02*
X489154Y1071134D01*
G01X489156Y1071142D02*
X489155Y1071140D01*
G01X488170Y1081140D02*
X488171Y1081142D01*
G01X488169Y1081134D02*
X488170Y1081140D01*
G01X488169Y1081126D02*
Y1081134D01*
G01X488170Y1076140D02*
X488171Y1076142D01*
G01X488169Y1076134D02*
X488170Y1076140D01*
G01X488169Y1076126D02*
Y1076134D01*
G01X488170Y1071140D02*
X488171Y1071142D01*
G01X488169Y1071134D02*
X488170Y1071140D01*
G01X488169Y1071126D02*
Y1071134D01*
G01X488170Y1066140D02*
X488171Y1066142D01*
G01X488169Y1066134D02*
X488170Y1066140D01*
G01X488169Y1066126D02*
Y1066134D01*
G01X488170Y1061140D02*
X488171Y1061142D01*
G01X488169Y1061134D02*
X488170Y1061140D01*
G01X488169Y1061126D02*
Y1061134D01*
G01X488170Y1056140D02*
X488171Y1056142D01*
G01X488169Y1056134D02*
X488170Y1056140D01*
G01X488169Y1056126D02*
Y1056134D01*
G01X488170Y1051140D02*
X488171Y1051142D01*
G01X488169Y1051134D02*
X488170Y1051140D01*
G01X488169Y1051126D02*
Y1051134D01*
G01X489154Y1066134D02*
Y1066125D01*
G01X489155Y1066140D02*
X489154Y1066134D01*
G01X489156Y1066142D02*
X489155Y1066140D01*
G01X489154Y1061134D02*
Y1061125D01*
G01X489155Y1061140D02*
X489154Y1061134D01*
G01X489156Y1061142D02*
X489155Y1061140D01*
G01X489154Y1056134D02*
Y1056125D01*
G01X489155Y1056140D02*
X489154Y1056134D01*
G01X489156Y1056142D02*
X489155Y1056140D01*
G01X489154Y1051134D02*
Y1051125D01*
G01X489155Y1051140D02*
X489154Y1051134D01*
G01X489156Y1051142D02*
X489155Y1051140D01*
G01X489120Y1047618D02*
X489124Y1047717D01*
G01X489115Y1047546D02*
X489120Y1047618D01*
G01X489117Y1047520D02*
X489115Y1047546D01*
G01X489120Y1052618D02*
X489124Y1052717D01*
G01X489115Y1052546D02*
X489120Y1052618D01*
G01X489117Y1052520D02*
X489115Y1052546D01*
G01X489120Y1057618D02*
X489124Y1057717D01*
G01X489115Y1057546D02*
X489120Y1057618D01*
G01X489117Y1057520D02*
X489115Y1057546D01*
G01X489120Y1062618D02*
X489124Y1062717D01*
G01X489115Y1062546D02*
X489120Y1062618D01*
G01X489117Y1062520D02*
X489115Y1062546D01*
G01X489120Y1067618D02*
X489124Y1067717D01*
G01X489115Y1067546D02*
X489120Y1067618D01*
G01X489117Y1067520D02*
X489115Y1067546D01*
G01X489120Y1072618D02*
X489124Y1072717D01*
G01X489115Y1072546D02*
X489120Y1072618D01*
G01X489117Y1072520D02*
X489115Y1072546D01*
G01X489120Y1077618D02*
X489124Y1077717D01*
G01X489115Y1077546D02*
X489120Y1077618D01*
G01X489117Y1077520D02*
X489115Y1077546D01*
G01X489120Y1082618D02*
X489124Y1082717D01*
G01X489115Y1082546D02*
X489120Y1082618D01*
G01X489117Y1082520D02*
X489115Y1082546D01*
G01X488169Y1047527D02*
Y1047536D01*
G01X488170Y1047521D02*
X488169Y1047527D01*
G01Y1052527D02*
Y1052536D01*
G01X488170Y1052521D02*
X488169Y1052527D01*
G01X488171Y1052520D02*
X488170Y1052521D01*
G01X488169Y1057527D02*
Y1057536D01*
G01X488170Y1057521D02*
X488169Y1057527D01*
G01X488171Y1057520D02*
X488170Y1057521D01*
G01X488169Y1062527D02*
Y1062536D01*
G01X488170Y1062521D02*
X488169Y1062527D01*
G01X488171Y1062520D02*
X488170Y1062521D01*
G01X489146Y1047663D02*
X489154Y1047637D01*
G01X489136Y1047690D02*
X489146Y1047663D01*
G01X489124Y1047717D02*
X489136Y1047690D01*
G01X489146Y1052663D02*
X489154Y1052637D01*
G01X489136Y1052690D02*
X489146Y1052663D01*
G01X489124Y1052717D02*
X489136Y1052690D01*
G01X489146Y1057663D02*
X489154Y1057637D01*
G01X489136Y1057690D02*
X489146Y1057663D01*
G01X489124Y1057717D02*
X489136Y1057690D01*
G01X489146Y1062663D02*
X489154Y1062637D01*
G01X489136Y1062690D02*
X489146Y1062663D01*
G01X489124Y1062717D02*
X489136Y1062690D01*
G01X489146Y1067663D02*
X489154Y1067637D01*
G01X489136Y1067690D02*
X489146Y1067663D01*
G01X489124Y1067717D02*
X489136Y1067690D01*
G01Y1052515D02*
X489117Y1052520D01*
G01X489151Y1052500D02*
X489136Y1052515D01*
G01X489156Y1052480D02*
X489151Y1052500D01*
G01X489136Y1057515D02*
X489117Y1057520D01*
G01X489151Y1057500D02*
X489136Y1057515D01*
G01X489156Y1057480D02*
X489151Y1057500D01*
G01X489136Y1062515D02*
X489117Y1062520D01*
G01X489151Y1062500D02*
X489136Y1062515D01*
G01X489156Y1062480D02*
X489151Y1062500D01*
G01X489136Y1067515D02*
X489117Y1067520D01*
G01X489151Y1067500D02*
X489136Y1067515D01*
G01X489156Y1067480D02*
X489151Y1067500D01*
G01X489136Y1072515D02*
X489117Y1072520D01*
G01X489151Y1072500D02*
X489136Y1072515D01*
G01X489156Y1072480D02*
X489151Y1072500D01*
G01X489136Y1077515D02*
X489117Y1077520D01*
G01X489151Y1077500D02*
X489136Y1077515D01*
G01X489156Y1077480D02*
X489151Y1077500D01*
G01X489136Y1082515D02*
X489117Y1082520D01*
G01X489151Y1082500D02*
X489136Y1082515D01*
G01X489156Y1082480D02*
X489151Y1082500D01*
G01X488169Y1067527D02*
Y1067536D01*
G01X488170Y1067521D02*
X488169Y1067527D01*
G01X488171Y1067520D02*
X488170Y1067521D01*
G01X488169Y1072527D02*
Y1072536D01*
G01X488170Y1072521D02*
X488169Y1072527D01*
G01X488171Y1072520D02*
X488170Y1072521D01*
G01X488169Y1077527D02*
Y1077536D01*
G01X488170Y1077521D02*
X488169Y1077527D01*
G01X488171Y1077520D02*
X488170Y1077521D01*
G01X488169Y1082527D02*
Y1082536D01*
G01X488170Y1082521D02*
X488169Y1082527D01*
G01X488171Y1082520D02*
X488170Y1082521D01*
G01X489146Y1072663D02*
X489154Y1072637D01*
G01X489136Y1072690D02*
X489146Y1072663D01*
G01X489124Y1072717D02*
X489136Y1072690D01*
G01X489146Y1077663D02*
X489154Y1077637D01*
G01X489136Y1077690D02*
X489146Y1077663D01*
G01X489124Y1077717D02*
X489136Y1077690D01*
G01X489146Y1082663D02*
X489154Y1082637D01*
G01X489136Y1082690D02*
X489146Y1082663D01*
G01X489124Y1082717D02*
X489136Y1082690D01*
G01X489154Y1047487D02*
Y1047494D01*
G01Y1052487D02*
Y1052494D01*
G01X489155Y1052482D02*
X489154Y1052487D01*
G01X489156Y1052480D02*
X489155Y1052482D01*
G01X489154Y1057487D02*
Y1057494D01*
G01X489155Y1057482D02*
X489154Y1057487D01*
G01X489156Y1057480D02*
X489155Y1057482D01*
G01X489154Y1062487D02*
Y1062494D01*
G01X489155Y1062482D02*
X489154Y1062487D01*
G01X489156Y1062480D02*
X489155Y1062482D01*
G01X489154Y1067487D02*
Y1067494D01*
G01X489155Y1067482D02*
X489154Y1067487D01*
G01X489156Y1067480D02*
X489155Y1067482D01*
G01X489154Y1072487D02*
Y1072494D01*
G01X489155Y1072482D02*
X489154Y1072487D01*
G01X489156Y1072480D02*
X489155Y1072482D01*
G01X489154Y1077487D02*
Y1077494D01*
G01X489155Y1077482D02*
X489154Y1077487D01*
G01X489156Y1077480D02*
X489155Y1077482D01*
G01X489154Y1082487D02*
Y1082494D01*
G01X489155Y1082482D02*
X489154Y1082487D01*
G01X489156Y1082480D02*
X489155Y1082482D01*
G01X489141Y1052511D02*
X489152Y1052496D01*
G01X489117Y1052520D02*
X489141Y1052511D01*
G01Y1057511D02*
X489152Y1057496D01*
G01X489117Y1057520D02*
X489141Y1057511D01*
G01Y1062511D02*
X489152Y1062496D01*
G01X489117Y1062520D02*
X489141Y1062511D01*
G01Y1067511D02*
X489152Y1067496D01*
G01X489117Y1067520D02*
X489141Y1067511D01*
G01Y1072511D02*
X489152Y1072496D01*
G01X489117Y1072520D02*
X489141Y1072511D01*
G01Y1077511D02*
X489152Y1077496D01*
G01X489117Y1077520D02*
X489141Y1077511D01*
G01Y1082511D02*
X489152Y1082496D01*
G01X489117Y1082520D02*
X489141Y1082511D01*
G01X487598Y1108012D02*
G03X487008Y1108602I-590J0D01*
G01X484843Y1104862D02*
G03Y1106831I0J984D01*
G01X487402Y1097736D02*
G03X486220Y1098917I-1181J0D01*
G01X485551Y1093642D02*
G03I-1890J0D01*
G01X494488Y1107421D02*
G03X492520Y1109390I-1969J0D01*
G01X486024Y1093642D02*
G03I-2363J0D01*
G01X482480Y1106831D02*
G03Y1104862I0J-985D01*
G01X484843Y1106831D02*
X482480D01*
G01Y1104862D02*
X484843D01*
G01X482480Y1094232D02*
X484843D01*
G01X482480Y1092539D02*
X484843D01*
G01X490551Y1089193D02*
X487402D01*
G01X489154Y1083012D02*
X488169D01*
G01X488171Y1082520D02*
X493504D01*
G01Y1082480D02*
X489156D01*
G01X493504Y1081142D02*
X488171D01*
G01X488169Y1080650D02*
X489154D01*
G01Y1078012D02*
X488169D01*
G01X488171Y1077520D02*
X493504D01*
G01Y1077480D02*
X489156D01*
G01X493504Y1076142D02*
X488171D01*
G01X488169Y1075650D02*
X489154D01*
G01Y1073012D02*
X488169D01*
G01X488171Y1072520D02*
X493504D01*
G01Y1072480D02*
X489156D01*
G01X493504Y1071142D02*
X488171D01*
G01X488169Y1070650D02*
X489154D01*
G01Y1068012D02*
X488169D01*
G01X488171Y1067520D02*
X493504D01*
G01Y1067480D02*
X489156D01*
G01X493504Y1066142D02*
X488171D01*
G01X488169Y1065650D02*
X489154D01*
G01Y1063012D02*
X488169D01*
G01X488171Y1062520D02*
X493504D01*
G01Y1062480D02*
X489156D01*
G01X493504Y1061142D02*
X488171D01*
G01X488169Y1060650D02*
X489154D01*
G01Y1058012D02*
X488169D01*
G01X488171Y1057520D02*
X493504D01*
G01Y1057480D02*
X489156D01*
G01X493504Y1056142D02*
X488171D01*
G01X488169Y1055650D02*
X489154D01*
G01Y1053012D02*
X488169D01*
G01X488171Y1052520D02*
X493504D01*
G01Y1052480D02*
X489156D01*
G01X493504Y1051142D02*
X488171D01*
G01X488169Y1050650D02*
X489154D01*
G01Y1048012D02*
X488169D01*
G01X488171Y1047520D02*
X493504D01*
G01Y1047480D02*
X489156D01*
G01X488169Y1082715D02*
X489124Y1082717D01*
G01X489154Y1080946D02*
X488169Y1080945D01*
G01Y1077715D02*
X489124Y1077717D01*
G01X489154Y1075946D02*
X488169Y1075945D01*
G01Y1072715D02*
X489124Y1072717D01*
G01X489154Y1070946D02*
X488169Y1070945D01*
G01Y1067715D02*
X489124Y1067717D01*
G01X489154Y1065946D02*
X488169Y1065945D01*
G01Y1062715D02*
X489124Y1062717D01*
G01X489154Y1060946D02*
X488169Y1060945D01*
G01Y1057715D02*
X489124Y1057717D01*
G01X489154Y1055946D02*
X488169Y1055945D01*
G01Y1052715D02*
X489124Y1052717D01*
G01X489154Y1050946D02*
X488169Y1050945D01*
G01Y1047715D02*
X489124Y1047717D01*
G01X484843Y1092539D02*
X486146Y1090571D01*
G01X494488Y1091673D02*
Y1107421D01*
G01X493504Y1081142D02*
Y1082520D01*
G01Y1076142D02*
Y1077520D01*
G01Y1071142D02*
Y1072520D01*
G01Y1066142D02*
Y1067520D01*
G01Y1061142D02*
Y1062520D01*
G01Y1056142D02*
Y1057520D01*
G01Y1051142D02*
Y1052520D01*
G01X490335D02*
Y1051142D01*
G01Y1057520D02*
Y1056142D01*
G01Y1062520D02*
Y1061142D01*
G01Y1067520D02*
Y1066142D01*
G01Y1072520D02*
Y1071142D01*
G01Y1077520D02*
Y1076142D01*
G01Y1082520D02*
Y1081142D01*
G01X489154Y1080650D02*
Y1083012D01*
G01Y1075650D02*
Y1078012D01*
G01Y1070650D02*
Y1073012D01*
G01Y1065650D02*
Y1068012D01*
G01Y1060650D02*
Y1063012D01*
G01Y1055650D02*
Y1058012D01*
G01Y1050650D02*
Y1053012D01*
G01Y1047494D02*
Y1047637D01*
G01Y1052494D02*
Y1052637D01*
G01Y1057494D02*
Y1057637D01*
G01Y1062494D02*
Y1062637D01*
G01Y1067494D02*
Y1067637D01*
G01Y1072494D02*
Y1072637D01*
G01Y1077494D02*
Y1077637D01*
G01Y1082494D02*
Y1082637D01*
G01X488169Y1053012D02*
Y1050650D01*
G01Y1058012D02*
Y1055650D01*
G01Y1063012D02*
Y1060650D01*
G01Y1068012D02*
Y1065650D01*
G01Y1073012D02*
Y1070650D01*
G01Y1078012D02*
Y1075650D01*
G01Y1083012D02*
Y1080650D01*
G01X487598Y1101909D02*
Y1108012D01*
G01X487402Y1097736D02*
Y1089193D01*
G01X489154Y1047494D02*
Y1047502D01*
G01Y1052494D02*
Y1052502D01*
G01Y1057494D02*
Y1057502D01*
G01Y1062494D02*
Y1062502D01*
G01Y1067494D02*
Y1067502D01*
G01Y1072494D02*
Y1072502D01*
G01Y1077494D02*
Y1077502D01*
G01Y1082494D02*
Y1082502D01*
G01X484843Y1094232D02*
Y1092539D01*
G01X482480D02*
Y1094232D01*
G01X494488Y1091673D02*
X491142Y1088327D01*
G01X484646Y1085650D02*
X485827Y1086831D01*
G01X487153Y1098461D02*
X484843Y1094232D01*
G01X516398Y1320472D02*
G03I-4902J0D01*
G01X511496Y1336220D02*
G03Y1304724I0J-15748D01*
G01X482953Y1333028D02*
X484980D01*
G01Y1332755D02*
X483012D01*
G01X484980Y1331059D02*
X482953D01*
G01X483012Y1328070D02*
X484980D01*
G01X507535Y1326272D02*
X500535D01*
G01X484980Y1323972D02*
X482953D01*
G01X484980Y1322794D02*
X483012D01*
G01X516485Y1321822D02*
X506585D01*
G01X482953Y1321790D02*
X484980D01*
G01X506585Y1319122D02*
X516485D01*
G01X483012Y1318109D02*
X484980D01*
G01X496535Y1310275D02*
X489035D01*
G01X507535Y1309772D02*
X496535D01*
G01X531496Y1304724D02*
X511496D01*
G01X516485Y1319122D02*
Y1321822D01*
G01X511535Y1334172D02*
Y1306772D01*
G01X507535Y1326272D02*
Y1309772D01*
G01X506585Y1321822D02*
Y1319122D01*
G01X500535Y1326272D02*
Y1361172D01*
G01X496535Y1309772D02*
Y1361172D01*
G01X489035Y1311456D02*
Y1310275D01*
G01X484980Y1333028D02*
Y1342716D01*
G01Y1318109D02*
Y1332755D01*
G01X483012Y1322794D02*
Y1318109D01*
G01Y1332755D02*
Y1328070D01*
G01X482953Y1319606D02*
Y1357086D01*
G01X537635Y1320472D02*
G03I-6100J0D01*
G01X537756D02*
G03I-6260J0D01*
G01X531496Y1304724D02*
G03Y1336220I0J15748D01*
G01X541535Y1334172D02*
Y1306772D01*
G01X500535Y1361172D02*
X496535D01*
G01Y1360669D02*
X489035D01*
G01X484980Y1352676D02*
X483012D01*
G01X482953Y1352336D02*
X484980D01*
G01Y1350154D02*
X482953D01*
G01X483012Y1347991D02*
X484980D01*
G01X482953Y1343028D02*
X484980D01*
G01Y1342716D02*
X483012D01*
G01X484980Y1341059D02*
X482953D01*
G01X483012Y1338031D02*
X484980D01*
G01X511496Y1336220D02*
X531496D01*
G01X541535Y1334172D02*
X505035D01*
G01X513035D02*
Y1364172D01*
G01X505535Y1334172D02*
Y1364172D01*
G01X505035D02*
Y1334172D01*
G01X489035Y1360669D02*
Y1360472D01*
G01X484980Y1343028D02*
Y1352676D01*
G01X483012Y1342716D02*
Y1338031D01*
G01Y1352676D02*
Y1347991D01*
G01X489370Y1515748D02*
G03X485433Y1519685I-3937J0D01*
G01X489370Y1515748D02*
Y1503937D01*
G01Y1515748D02*
G03X485433Y1519685I-3937J0D01*
G01X493307Y1496063D02*
G03X497244Y1500000I0J3937D01*
G01Y1515748D02*
Y1500000D01*
G01X501181Y1519685D02*
G03X497244Y1515748I0J-3937D01*
G01X680512Y1519685D02*
X501181D01*
G01X489370Y1515748D02*
Y1503937D01*
G01X548031Y1494280D02*
G03Y1497059I1J1389D01*
G01Y1492575D02*
G03Y1498764I0J3094D01*
G01X493307Y1496063D02*
G03X497244Y1500000I0J3937D01*
G01X501181Y1519685D02*
G03X497244Y1515748I0J-3937D01*
G01X549292Y1491732D02*
G03Y1499606I-1260J3937D01*
G01X552165Y1491732D02*
G03Y1499606I-4134J3937D01*
G01X564567Y1523622D02*
X597638D01*
G01X526772D02*
X560630D01*
G01X530315Y1521654D02*
X526772D01*
G01X564567Y1520210D02*
X548031D01*
G01X680512Y1519685D02*
X501181D01*
G01X564567Y1518110D02*
X597638D01*
G01X621260Y1516929D02*
X540945D01*
G01X621260Y1512992D02*
X540945D01*
G01X564567Y1512598D02*
X597638D01*
G01X536022D02*
X535787D01*
G01X568504Y1510954D02*
X579134D01*
G01X537402D02*
X560630D01*
G01Y1509843D02*
X601575D01*
G01X562500Y1505512D02*
X566634D01*
G01X545965D02*
X550098D01*
G01X564567Y1505210D02*
X568504D01*
G01X552165Y1499606D02*
X548031D01*
G01X526772Y1492913D02*
X537402D01*
G01X552165Y1491732D02*
X548031D01*
G01X555118Y1485827D02*
X540945D01*
G01X571654D02*
X557480D01*
G01X588189D02*
X574016D01*
G01X535787Y1471260D02*
X624803D01*
G01X550098Y1469783D02*
X545965D01*
G01X566634D02*
X562500D01*
G01X550098Y1468996D02*
X545965D01*
G01X566634D02*
X562500D01*
G01X550098Y1464862D02*
X545965D01*
G01X566634D02*
X562500D01*
G01X550098Y1448130D02*
X545965D01*
G01X566634D02*
X562500D01*
G01X550098Y1447343D02*
X545965D01*
G01X566634D02*
X562500D01*
G01X550098Y1443209D02*
X545965D01*
G01X566634D02*
X562500D01*
G01X540945Y1516929D02*
X530315Y1521654D01*
G01Y1526772D02*
X540945Y1516929D01*
G01X526772Y1523622D02*
X537402Y1510954D01*
G01X574016Y1485827D02*
Y1512992D01*
G01X571654Y1485827D02*
Y1512992D01*
G01X568504Y1523622D02*
Y1505210D01*
G01X567717Y1485827D02*
Y1512992D01*
G01X566634Y1443209D02*
Y1471260D01*
G01Y1505512D02*
Y1485827D01*
G01X564567Y1505210D02*
Y1526772D01*
G01X562500Y1471260D02*
Y1443209D01*
G01Y1505512D02*
Y1485827D01*
G01X561417D02*
Y1512992D01*
G01X560630Y1509843D02*
Y1523622D01*
G01X557480Y1485827D02*
Y1512992D01*
G01X555118Y1485827D02*
Y1512992D01*
G01X551181Y1485827D02*
Y1512992D01*
G01X550098Y1443209D02*
Y1471260D01*
G01Y1505512D02*
Y1485827D01*
G01X548031Y1492574D02*
Y1494279D01*
G01Y1510954D02*
Y1526772D01*
G01Y1499606D02*
Y1491732D01*
G01Y1497059D02*
Y1498764D01*
G01X545965Y1471260D02*
Y1443209D01*
G01Y1505512D02*
Y1485827D01*
G01X545669Y1523622D02*
Y1471260D01*
G01X544882Y1485827D02*
Y1512992D01*
G01X542165Y1523622D02*
Y1471260D01*
G01X540945Y1516929D02*
Y1485827D01*
G01X537402Y1510954D02*
Y1471260D01*
G01X537362Y1511001D02*
Y1471260D01*
G01X535787Y1512598D02*
Y1471260D01*
G01X530315Y1526772D02*
Y1521654D01*
G01X528465Y1519685D02*
Y1521604D01*
G01X526772Y1526772D02*
Y1492913D01*
G01X497244Y1515748D02*
Y1500000D01*
G01X526772Y1526772D02*
X635433D01*
G01X598957Y86959D02*
Y86955D01*
G01X598958Y86952D02*
X598957Y86959D01*
G01X598970Y86937D02*
X598958Y86952D01*
G01X598995Y86929D02*
X598970Y86937D01*
G01X598957Y90108D02*
Y90104D01*
G01X598958Y90102D02*
X598957Y90108D01*
G01X598970Y90087D02*
X598958Y90102D01*
G01X598994Y90079D02*
X598970Y90087D01*
G01X598957Y83809D02*
Y83806D01*
G01X598958Y83803D02*
X598957Y83809D01*
G01X598970Y83788D02*
X598958Y83803D01*
G01X598994Y83780D02*
X598970Y83788D01*
G01X613354Y51999D02*
X613365Y51984D01*
G01X613329Y52008D02*
X613354Y51999D01*
G01Y56999D02*
X613365Y56984D01*
G01X613329Y57008D02*
X613354Y56999D01*
G01Y61999D02*
X613365Y61984D01*
G01X613329Y62008D02*
X613354Y61999D01*
G01Y66999D02*
X613365Y66984D01*
G01X613329Y67008D02*
X613354Y66999D01*
G01Y71999D02*
X613365Y71984D01*
G01X613329Y72008D02*
X613354Y71999D01*
G01Y76999D02*
X613365Y76984D01*
G01X613329Y77008D02*
X613354Y76999D01*
G01Y81999D02*
X613365Y81984D01*
G01X613329Y82008D02*
X613354Y81999D01*
G01X598957Y93258D02*
Y93254D01*
G01X598958Y93252D02*
X598957Y93258D01*
G01X598969Y93238D02*
X598958Y93252D01*
G01X598991Y93228D02*
X598969Y93238D01*
G01X599909Y91259D02*
X599900Y91260D01*
G01X599918Y91256D02*
X599909Y91259D01*
G01X599926Y91250D02*
X599918Y91256D01*
G01X599909Y84959D02*
X599900Y84961D01*
G01X599919Y84956D02*
X599909Y84959D01*
G01X599926Y84951D02*
X599919Y84956D01*
G01X599909Y88109D02*
X599900Y88110D01*
G01X599919Y88106D02*
X599909Y88109D01*
G01X599926Y88100D02*
X599919Y88106D01*
G01X598996Y83774D02*
Y83768D01*
G01X598995Y83778D02*
X598996Y83774D01*
G01X598994Y83780D02*
X598995Y83778D01*
G01X598996Y86924D02*
Y86918D01*
G01X598995Y86928D02*
X598996Y86924D01*
G01X598994Y86929D02*
X598995Y86928D01*
G01X598996Y90074D02*
Y90067D01*
G01X598995Y90078D02*
X598996Y90074D01*
G01X598994Y90079D02*
X598995Y90078D01*
G01X598996Y93223D02*
Y93217D01*
G01X598995Y93227D02*
X598996Y93223D01*
G01X598994Y93228D02*
X598995Y93227D01*
G01X599919Y83772D02*
X599922Y83774D01*
G01X599915Y83770D02*
X599919Y83772D01*
G01X599912Y83770D02*
X599915D01*
G01X599909Y83769D02*
X599912Y83770D01*
G01X599905Y83769D02*
X599909D01*
G01X599902Y83768D02*
X599905Y83769D01*
G01X598979Y84968D02*
X598976Y84967D01*
G01X598982Y84969D02*
X598979Y84968D01*
G01X598986Y84970D02*
X598982Y84969D01*
G01X598989Y84971D02*
X598986Y84970D01*
G01X598993Y84972D02*
X598989Y84971D01*
G01X598996Y84972D02*
X598993D01*
G01X599919Y86921D02*
X599922Y86923D01*
G01X599915Y86920D02*
X599919Y86921D01*
G01X599912Y86919D02*
X599915Y86920D01*
G01X599909Y86919D02*
X599912D01*
G01X599905Y86918D02*
X599909Y86919D01*
G01X599902Y86918D02*
X599905D01*
G01X598979Y88118D02*
X598976Y88116D01*
G01X598982Y88119D02*
X598979Y88118D01*
G01X598986Y88120D02*
X598982Y88119D01*
G01X598989Y88121D02*
X598986Y88120D01*
G01X598993Y88121D02*
X598989D01*
G01X598996D02*
X598993D01*
G01X599919Y90071D02*
X599922Y90073D01*
G01X599915Y90070D02*
X599919Y90071D01*
G01X599912Y90069D02*
X599915Y90070D01*
G01X599909Y90068D02*
X599912Y90069D01*
G01X599905Y90068D02*
X599909D01*
G01X599902Y90067D02*
X599905Y90068D01*
G01X598979Y91267D02*
X598976Y91266D01*
G01X598982Y91269D02*
X598979Y91267D01*
G01X598986Y91270D02*
X598982Y91269D01*
G01X598989Y91270D02*
X598986D01*
G01X598993Y91271D02*
X598989Y91270D01*
G01X598996Y91271D02*
X598993D01*
G01X599919Y93220D02*
X599922Y93222D01*
G01X599915Y93219D02*
X599919Y93220D01*
G01X599912Y93219D02*
X599915D01*
G01X599909Y93218D02*
X599912Y93219D01*
G01X599905Y93217D02*
X599909Y93218D01*
G01X599902Y93217D02*
X599905D01*
G01X598209Y86969D02*
X597776D01*
G01X598583D02*
X598209D01*
G01Y93268D02*
X597776D01*
G01X598583D02*
X598209D01*
G01X599931Y84959D02*
X599935Y84954D01*
G01X599927Y84963D02*
X599931Y84959D01*
G01X599921Y84967D02*
X599927Y84963D01*
G01X599915Y84970D02*
X599921Y84967D01*
G01X599908Y84971D02*
X599915Y84970D01*
G01X599902Y84972D02*
X599908Y84971D01*
G01X599931Y88109D02*
X599935Y88103D01*
G01X599927Y88113D02*
X599931Y88109D01*
G01X599921Y88117D02*
X599927Y88113D01*
G01X599915Y88119D02*
X599921Y88117D01*
G01X599908Y88121D02*
X599915Y88119D01*
G01X599902Y88121D02*
X599908D01*
G01X599931Y91258D02*
X599935Y91253D01*
G01X599927Y91263D02*
X599931Y91258D01*
G01X599921Y91266D02*
X599927Y91263D01*
G01X599915Y91269D02*
X599921Y91266D01*
G01X599908Y91270D02*
X599915Y91269D01*
G01X599902Y91271D02*
X599908Y91270D01*
G01X598957Y83798D02*
Y83805D01*
G01X598960Y83791D02*
X598957Y83798D01*
G01X598963Y83785D02*
X598960Y83791D01*
G01X598968Y83779D02*
X598963Y83785D01*
G01X598974Y83774D02*
X598968Y83779D01*
G01X598981Y83771D02*
X598974Y83774D01*
G01X598989Y83769D02*
X598981Y83771D01*
G01X598996Y83768D02*
X598989Y83769D01*
G01X598957Y86948D02*
Y86955D01*
G01X598960Y86941D02*
X598957Y86948D01*
G01X598963Y86934D02*
X598960Y86941D01*
G01X598968Y86929D02*
X598963Y86934D01*
G01X598974Y86924D02*
X598968Y86929D01*
G01X598981Y86920D02*
X598974Y86924D01*
G01X598989Y86919D02*
X598981Y86920D01*
G01X598996Y86918D02*
X598989Y86919D01*
G01X598957Y90097D02*
Y90104D01*
G01X598960Y90090D02*
X598957Y90097D01*
G01X598963Y90084D02*
X598960Y90090D01*
G01X598968Y90078D02*
X598963Y90084D01*
G01X598974Y90074D02*
X598968Y90078D01*
G01X598981Y90070D02*
X598974Y90074D01*
G01X598989Y90068D02*
X598981Y90070D01*
G01X598996Y90067D02*
X598989Y90068D01*
G01X598957Y93247D02*
Y93254D01*
G01X598960Y93240D02*
X598957Y93247D01*
G01X598963Y93233D02*
X598960Y93240D01*
G01X598968Y93228D02*
X598963Y93233D01*
G01X598974Y93223D02*
X598968Y93228D01*
G01X598981Y93220D02*
X598974Y93223D01*
G01X598989Y93218D02*
X598981Y93220D01*
G01X598996Y93217D02*
X598989Y93218D01*
G01X599911Y84959D02*
X599920Y84955D01*
G01X599900Y84961D02*
X599911Y84959D01*
G01Y88109D02*
X599920Y88105D01*
G01X599900Y88110D02*
X599911Y88109D01*
G01Y91258D02*
X599920Y91254D01*
G01X599900Y91260D02*
X599911Y91258D01*
G01X613367Y51975D02*
X613366Y51982D01*
G01X613367Y51970D02*
Y51975D01*
G01X613369Y51969D02*
X613367Y51970D01*
G01Y56975D02*
X613366Y56982D01*
G01X613367Y56970D02*
Y56975D01*
G01X613369Y56969D02*
X613367Y56970D01*
G01Y61975D02*
X613366Y61982D01*
G01X613367Y61970D02*
Y61975D01*
G01X613369Y61969D02*
X613367Y61970D01*
G01Y66975D02*
X613366Y66982D01*
G01X613367Y66970D02*
Y66975D01*
G01X613369Y66969D02*
X613367Y66970D01*
G01Y71975D02*
X613366Y71982D01*
G01X613367Y71970D02*
Y71975D01*
G01X613369Y71969D02*
X613367Y71970D01*
G01Y76975D02*
X613366Y76982D01*
G01X613367Y76970D02*
Y76975D01*
G01X613369Y76969D02*
X613367Y76970D01*
G01Y81975D02*
X613366Y81982D01*
G01X613367Y81970D02*
Y81975D01*
G01X613369Y81969D02*
X613367Y81970D01*
G01X598980Y86931D02*
X598994Y86929D01*
G01X598968Y86939D02*
X598980Y86931D01*
G01X598956Y86957D02*
X598968Y86939D01*
G01X598979Y90081D02*
X598994Y90079D01*
G01X598967Y90089D02*
X598979Y90081D01*
G01X598955Y90109D02*
X598967Y90089D01*
G01X599941Y83813D02*
Y83805D01*
G01X599940Y83817D02*
X599941Y83813D01*
G01X599939Y83819D02*
X599940Y83817D01*
G01X599941Y86963D02*
Y86955D01*
G01X599940Y86967D02*
X599941Y86963D01*
G01X599939Y86969D02*
X599940Y86967D01*
G01X599941Y90112D02*
Y90104D01*
G01X599940Y90117D02*
X599941Y90112D01*
G01X599939Y90118D02*
X599940Y90117D01*
G01X599941Y93262D02*
Y93254D01*
G01X599940Y93266D02*
X599941Y93262D01*
G01X599939Y93268D02*
X599940Y93266D01*
G01X598979Y83782D02*
X598994Y83780D01*
G01X598966Y83791D02*
X598979Y83782D01*
G01X598955Y83811D02*
X598966Y83791D01*
G01X599940Y84941D02*
X599941Y84935D01*
G01X599939Y84948D02*
X599940Y84941D01*
G01X599935Y84954D02*
X599939Y84948D01*
G01X599940Y88091D02*
X599941Y88084D01*
G01X599939Y88097D02*
X599940Y88091D01*
G01X599935Y88103D02*
X599939Y88097D01*
G01X599940Y91241D02*
X599941Y91234D01*
G01X599939Y91247D02*
X599940Y91241D01*
G01X599935Y91253D02*
X599939Y91247D01*
G01X599902Y83774D02*
Y83768D01*
G01X599901Y83778D02*
X599902Y83774D01*
G01X599900Y83780D02*
X599901Y83778D01*
G01X599902Y86924D02*
Y86918D01*
G01X599901Y86928D02*
X599902Y86924D01*
G01X599900Y86929D02*
X599901Y86928D01*
G01X599902Y90074D02*
Y90067D01*
G01X599901Y90077D02*
X599902Y90074D01*
G01X599900Y90079D02*
X599901Y90077D01*
G01X599902Y93223D02*
Y93217D01*
G01X599901Y93227D02*
X599902Y93223D01*
G01X599900Y93228D02*
X599901Y93227D01*
G01X612382Y52015D02*
Y52024D01*
G01X612383Y52009D02*
X612382Y52015D01*
G01X612383Y52008D02*
Y52009D01*
G01X612382Y57015D02*
Y57024D01*
G01X612383Y57009D02*
X612382Y57015D01*
G01X612383Y57008D02*
Y57009D01*
G01X612382Y62015D02*
Y62024D01*
G01X612383Y62009D02*
X612382Y62015D01*
G01X612383Y62008D02*
Y62009D01*
G01X612382Y67015D02*
Y67024D01*
G01X612383Y67009D02*
X612382Y67015D01*
G01X612383Y67008D02*
Y67009D01*
G01X612382Y72015D02*
Y72024D01*
G01X612383Y72009D02*
X612382Y72015D01*
G01X612383Y72008D02*
Y72009D01*
G01X612382Y77015D02*
Y77024D01*
G01X612383Y77009D02*
X612382Y77015D01*
G01X612383Y77008D02*
Y77009D01*
G01X612382Y82015D02*
Y82024D01*
G01X612383Y82009D02*
X612382Y82015D01*
G01X612383Y82008D02*
Y82009D01*
G01X613358Y52152D02*
X613366Y52125D01*
G01X613348Y52178D02*
X613358Y52152D01*
G01X613337Y52205D02*
X613348Y52178D01*
G01X613358Y57152D02*
X613366Y57125D01*
G01X613348Y57178D02*
X613358Y57152D01*
G01X613337Y57205D02*
X613348Y57178D01*
G01X613358Y62152D02*
X613366Y62125D01*
G01X613348Y62178D02*
X613358Y62152D01*
G01X613337Y62205D02*
X613348Y62178D01*
G01X613358Y67152D02*
X613366Y67125D01*
G01X613348Y67178D02*
X613358Y67152D01*
G01X613337Y67205D02*
X613348Y67178D01*
G01X613358Y72152D02*
X613366Y72125D01*
G01X613348Y72178D02*
X613358Y72152D01*
G01X613337Y72205D02*
X613348Y72178D01*
G01X613358Y77152D02*
X613366Y77125D01*
G01X613348Y77178D02*
X613358Y77152D01*
G01X613337Y77205D02*
X613348Y77178D01*
G01X613358Y82152D02*
X613366Y82125D01*
G01X613348Y82178D02*
X613358Y82152D01*
G01X613337Y82205D02*
X613348Y82178D01*
G01X598974Y93233D02*
X598994Y93228D01*
G01X598961Y93246D02*
X598974Y93233D01*
G01X598954Y93263D02*
X598961Y93246D01*
G01X598959Y84941D02*
X598954Y84921D01*
G01X598974Y84955D02*
X598959Y84941D01*
G01X598994Y84961D02*
X598974Y84955D01*
G01X598959Y88091D02*
X598954Y88071D01*
G01X598974Y88105D02*
X598959Y88091D01*
G01X598994Y88110D02*
X598974Y88105D01*
G01X598959Y91240D02*
X598954Y91220D01*
G01X598974Y91254D02*
X598959Y91240D01*
G01X598994Y91260D02*
X598974Y91254D01*
G01X599934Y83799D02*
X599939Y83819D01*
G01X599920Y83785D02*
X599934Y83799D01*
G01X599900Y83780D02*
X599920Y83785D01*
G01X599934Y86949D02*
X599939Y86969D01*
G01X599920Y86934D02*
X599934Y86949D01*
G01X599900Y86929D02*
X599920Y86934D01*
G01X599934Y90098D02*
X599939Y90118D01*
G01X599920Y90084D02*
X599934Y90098D01*
G01X599900Y90079D02*
X599920Y90084D01*
G01X599934Y93248D02*
X599939Y93268D01*
G01X599920Y93233D02*
X599934Y93248D01*
G01X599900Y93228D02*
X599920Y93233D01*
G01X613349Y52003D02*
X613330Y52008D01*
G01X613363Y51988D02*
X613349Y52003D01*
G01X613369Y51969D02*
X613363Y51988D01*
G01X613349Y57003D02*
X613330Y57008D01*
G01X613363Y56988D02*
X613349Y57003D01*
G01X613369Y56969D02*
X613363Y56988D01*
G01X613349Y62003D02*
X613330Y62008D01*
G01X613363Y61988D02*
X613349Y62003D01*
G01X613369Y61969D02*
X613363Y61988D01*
G01X613349Y67003D02*
X613330Y67008D01*
G01X613363Y66988D02*
X613349Y67003D01*
G01X613369Y66969D02*
X613363Y66988D01*
G01X613349Y72003D02*
X613330Y72008D01*
G01X613363Y71988D02*
X613349Y72003D01*
G01X613369Y71969D02*
X613363Y71988D01*
G01X613349Y77003D02*
X613330Y77008D01*
G01X613363Y76988D02*
X613349Y77003D01*
G01X613369Y76969D02*
X613363Y76988D01*
G01X613349Y82003D02*
X613330Y82008D01*
G01X613363Y81988D02*
X613349Y82003D01*
G01X613369Y81969D02*
X613363Y81988D01*
G01X613333Y52106D02*
X613337Y52205D01*
G01X613328Y52034D02*
X613333Y52106D01*
G01X613330Y52008D02*
X613328Y52034D01*
G01X613333Y57106D02*
X613337Y57205D01*
G01X613328Y57034D02*
X613333Y57106D01*
G01X613330Y57008D02*
X613328Y57034D01*
G01X613333Y62106D02*
X613337Y62205D01*
G01X613328Y62034D02*
X613333Y62106D01*
G01X613330Y62008D02*
X613328Y62034D01*
G01X613333Y67106D02*
X613337Y67205D01*
G01X613328Y67034D02*
X613333Y67106D01*
G01X613330Y67008D02*
X613328Y67034D01*
G01X613333Y72106D02*
X613337Y72205D01*
G01X613328Y72034D02*
X613333Y72106D01*
G01X613330Y72008D02*
X613328Y72034D01*
G01X613333Y77106D02*
X613337Y77205D01*
G01X613328Y77034D02*
X613333Y77106D01*
G01X613330Y77008D02*
X613328Y77034D01*
G01X613333Y82106D02*
X613337Y82205D01*
G01X613328Y82034D02*
X613333Y82106D01*
G01X613330Y82008D02*
X613328Y82034D01*
G01X599933Y91242D02*
X599926Y91250D01*
G01X599938Y91231D02*
X599933Y91242D01*
G01X599940Y91220D02*
X599938Y91231D01*
G01X599933Y84943D02*
X599926Y84951D01*
G01X599938Y84932D02*
X599933Y84943D01*
G01X599940Y84921D02*
X599938Y84932D01*
G01X599933Y88092D02*
X599926Y88100D01*
G01X599938Y88082D02*
X599933Y88092D01*
G01X599940Y88071D02*
X599938Y88082D01*
G01X598997Y91444D02*
X598996Y91457D01*
G01X598994Y91431D02*
X598997Y91444D01*
G01X598994Y91417D02*
Y91431D01*
G01X598997Y88294D02*
X598996Y88307D01*
G01X598994Y88281D02*
X598997Y88294D01*
G01X598994Y88268D02*
Y88281D01*
G01X598997Y85145D02*
X598996Y85157D01*
G01X598994Y85132D02*
X598997Y85145D01*
G01X598994Y85118D02*
Y85132D01*
G01X612383Y80628D02*
Y80630D01*
G01X612382Y80622D02*
X612383Y80628D01*
G01X612382Y80614D02*
Y80622D01*
G01X612383Y75628D02*
Y75630D01*
G01X612382Y75622D02*
X612383Y75628D01*
G01X612382Y75614D02*
Y75622D01*
G01X612383Y70628D02*
Y70630D01*
G01X612382Y70622D02*
X612383Y70628D01*
G01X612382Y70614D02*
Y70622D01*
G01X612383Y65628D02*
Y65630D01*
G01X612382Y65622D02*
X612383Y65628D01*
G01X612382Y65614D02*
Y65622D01*
G01X612383Y60628D02*
Y60630D01*
G01X612382Y60622D02*
X612383Y60628D01*
G01X612382Y60614D02*
Y60622D01*
G01X612383Y55628D02*
Y55630D01*
G01X612382Y55622D02*
X612383Y55628D01*
G01X612382Y55614D02*
Y55622D01*
G01X612383Y50628D02*
Y50630D01*
G01X612382Y50622D02*
X612383Y50628D01*
G01X612382Y50614D02*
Y50622D01*
G01X598994Y93057D02*
X598993Y93070D01*
G01X598997Y93044D02*
X598994Y93057D01*
G01X598996Y93031D02*
X598997Y93044D01*
G01X598994Y89907D02*
X598993Y89921D01*
G01X598997Y89894D02*
X598994Y89907D01*
G01X598996Y89882D02*
X598997Y89894D01*
G01X598994Y86757D02*
X598993Y86771D01*
G01X598997Y86745D02*
X598994Y86757D01*
G01X598996Y86732D02*
X598997Y86745D01*
G01X598994Y83608D02*
X598993Y83622D01*
G01X598997Y83595D02*
X598994Y83608D01*
G01X598996Y83583D02*
X598997Y83595D01*
G01X599904Y91431D02*
X599905Y91417D01*
G01X599901Y91444D02*
X599904Y91431D01*
G01X599902Y91457D02*
X599901Y91444D01*
G01X599904Y88281D02*
X599905Y88268D01*
G01X599901Y88294D02*
X599904Y88281D01*
G01X599902Y88307D02*
X599901Y88294D01*
G01X599904Y85132D02*
X599905Y85118D01*
G01X599901Y85145D02*
X599904Y85132D01*
G01X599902Y85157D02*
X599901Y85145D01*
G01X598956Y90112D02*
X598957Y90105D01*
G01X598956Y90117D02*
Y90112D01*
G01X598955Y90109D02*
X598956Y90117D01*
G01X599901Y93044D02*
X599902Y93031D01*
G01X599904Y93057D02*
X599901Y93044D01*
G01X599905Y93070D02*
X599904Y93057D01*
G01X599901Y89894D02*
X599902Y89882D01*
G01X599904Y89907D02*
X599901Y89894D01*
G01X599905Y89921D02*
X599904Y89907D01*
G01X599901Y86745D02*
X599902Y86732D01*
G01X599904Y86757D02*
X599901Y86745D01*
G01X599905Y86771D02*
X599904Y86757D01*
G01X599901Y83595D02*
X599902Y83583D01*
G01X599904Y83608D02*
X599901Y83595D01*
G01X599905Y83622D02*
X599904Y83608D01*
G01X598956Y83813D02*
X598957Y83806D01*
G01X598956Y83817D02*
Y83813D01*
G01X598955Y83811D02*
X598956Y83817D01*
G01X598970Y91251D02*
X598994Y91260D01*
G01X598959Y91237D02*
X598970Y91251D01*
G01X598957Y91230D02*
X598959Y91237D01*
G01X598970Y88102D02*
X598994Y88110D01*
G01X598959Y88087D02*
X598970Y88102D01*
G01X598957Y88080D02*
X598959Y88087D01*
G01X598970Y84952D02*
X598994Y84961D01*
G01X598959Y84937D02*
X598970Y84952D01*
G01X598957Y84931D02*
X598959Y84937D01*
G01X599941Y91227D02*
Y91234D01*
G01Y91222D02*
Y91227D01*
G01X599940Y91220D02*
X599941Y91222D01*
G01Y88077D02*
Y88084D01*
G01Y88072D02*
Y88077D01*
G01X599940Y88071D02*
X599941Y88072D01*
G01Y84928D02*
Y84935D01*
G01Y84923D02*
Y84928D01*
G01X599940Y84921D02*
X599941Y84923D01*
G01X598956Y93262D02*
X598957Y93254D01*
G01X598956Y93266D02*
Y93262D01*
G01X598954Y93263D02*
X598956Y93266D01*
G01Y86963D02*
X598957Y86955D01*
G01X598956Y86967D02*
Y86963D01*
G01X598954Y86965D02*
X598956Y86967D01*
G01X599902Y91265D02*
Y91271D01*
G01X599901Y91261D02*
X599902Y91265D01*
G01X599900Y91260D02*
X599901Y91261D01*
G01X599902Y88115D02*
Y88121D01*
G01X599901Y88111D02*
X599902Y88115D01*
G01X599900Y88110D02*
X599901Y88111D01*
G01X599902Y84966D02*
Y84972D01*
G01X599901Y84962D02*
X599902Y84966D01*
G01X599900Y84961D02*
X599901Y84962D01*
G01X613367Y80622D02*
X613366Y80613D01*
G01X613367Y80628D02*
Y80622D01*
G01X613369Y80630D02*
X613367Y80628D01*
G01Y75622D02*
X613366Y75613D01*
G01X613367Y75628D02*
Y75622D01*
G01X613369Y75630D02*
X613367Y75628D01*
G01Y70622D02*
X613366Y70613D01*
G01X613367Y70628D02*
Y70622D01*
G01X613369Y70630D02*
X613367Y70628D01*
G01Y65622D02*
X613366Y65613D01*
G01X613367Y65628D02*
Y65622D01*
G01X613369Y65630D02*
X613367Y65628D01*
G01Y60622D02*
X613366Y60613D01*
G01X613367Y60628D02*
Y60622D01*
G01X613369Y60630D02*
X613367Y60628D01*
G01Y55622D02*
X613366Y55613D01*
G01X613367Y55628D02*
Y55622D01*
G01X613369Y55630D02*
X613367Y55628D01*
G01Y50622D02*
X613366Y50613D01*
G01X613367Y50628D02*
Y50622D01*
G01X613369Y50630D02*
X613367Y50628D01*
G01X598956Y91226D02*
X598957Y91234D01*
G01X598956Y91222D02*
Y91226D01*
G01X598954Y91220D02*
X598956Y91222D01*
G01Y88077D02*
X598957Y88084D01*
G01X598956Y88072D02*
Y88077D01*
G01X598954Y88071D02*
X598956Y88072D01*
G01Y84927D02*
X598957Y84935D01*
G01X598956Y84923D02*
Y84927D01*
G01X598954Y84921D02*
X598956Y84923D01*
G01X599939Y93242D02*
X599941Y93254D01*
G01X599932Y93230D02*
X599939Y93242D01*
G01X599922Y93222D02*
X599932Y93230D01*
G01X599939Y90092D02*
X599941Y90104D01*
G01X599932Y90081D02*
X599939Y90092D01*
G01X599922Y90073D02*
X599932Y90081D01*
G01X599939Y86943D02*
X599941Y86955D01*
G01X599932Y86931D02*
X599939Y86943D01*
G01X599922Y86923D02*
X599932Y86931D01*
G01X599939Y83793D02*
X599941Y83805D01*
G01X599932Y83781D02*
X599939Y83793D01*
G01X599922Y83774D02*
X599932Y83781D01*
G01X598995Y91265D02*
Y91271D01*
G01Y91261D02*
Y91265D01*
G01X598994Y91260D02*
X598995Y91261D01*
G01Y88115D02*
Y88121D01*
G01Y88111D02*
Y88115D01*
G01X598994Y88110D02*
X598995Y88111D01*
G01Y84965D02*
Y84972D01*
G01Y84962D02*
Y84965D01*
G01X598994Y84961D02*
X598995Y84962D01*
G01X598957Y91240D02*
Y91234D01*
G01X598959Y91246D02*
X598957Y91240D01*
G01X598962Y91252D02*
X598959Y91246D01*
G01X598966Y91257D02*
X598962Y91252D01*
G01X598970Y91262D02*
X598966Y91257D01*
G01X598976Y91266D02*
X598970Y91262D01*
G01X598957Y88091D02*
Y88084D01*
G01X598959Y88097D02*
X598957Y88091D01*
G01X598962Y88103D02*
X598959Y88097D01*
G01X598966Y88108D02*
X598962Y88103D01*
G01X598970Y88113D02*
X598966Y88108D01*
G01X598976Y88116D02*
X598970Y88113D01*
G01X598957Y84941D02*
Y84935D01*
G01X598959Y84947D02*
X598957Y84941D01*
G01X598962Y84953D02*
X598959Y84947D01*
G01X598966Y84958D02*
X598962Y84953D01*
G01X598970Y84963D02*
X598966Y84958D01*
G01X598976Y84967D02*
X598970Y84963D01*
G01X599912Y93230D02*
X599900Y93228D01*
G01X599922Y93235D02*
X599912Y93230D01*
G01Y90081D02*
X599900Y90079D01*
G01X599922Y90085D02*
X599912Y90081D01*
G01Y86931D02*
X599900Y86929D01*
G01X599922Y86936D02*
X599912Y86931D01*
G01Y83781D02*
X599900Y83780D01*
G01X599922Y83786D02*
X599912Y83781D01*
G01X663091Y55118D02*
G03X677067I6988J0D01*
G01D02*
G03X663091I-6988J0D01*
G01X603937Y25138D02*
G03X604528Y24547I591J0D01*
G01X611220D02*
G03X611811Y25138I0J591D01*
G01X609055Y26319D02*
G03Y28287I0J984D01*
G01X606693D02*
G03Y26319I0J-984D01*
G01X608976Y39508D02*
G03I-1102J0D01*
G01X610433Y34232D02*
G03X611614Y35413I0J1181D01*
G01X604134D02*
G03X605315Y34232I1181J0D01*
G01X609449Y39508D02*
G03I-1575J0D01*
G01X597047Y25728D02*
G03X599016Y23760I1969J1D01*
G01X616732D02*
G03X618701Y25728I1J1968D01*
G01X677067Y55118D02*
G03I-6988J0D01*
G01X603346Y47500D02*
X602165Y46319D01*
G01X600394Y44823D02*
X597047Y41476D01*
G01X610359Y42579D02*
X609055Y40610D01*
G01X604383Y34688D02*
X606693Y38917D01*
G01X599941Y84923D02*
Y84935D01*
G01Y88073D02*
Y88084D01*
G01Y91222D02*
Y91234D01*
G01X613366Y51982D02*
X613367Y51991D01*
G01X613366Y56982D02*
X613367Y56991D01*
G01X613366Y61982D02*
X613367Y61991D01*
G01X613366Y66982D02*
X613367Y66991D01*
G01X613366Y71982D02*
X613367Y71991D01*
G01X613366Y76982D02*
X613367Y76991D01*
G01X613366Y81982D02*
X613367Y81991D01*
G01X618701Y25728D02*
Y41476D01*
G01X617717Y80630D02*
Y82008D01*
G01Y75630D02*
Y77008D01*
G01Y70630D02*
Y72008D01*
G01Y65630D02*
Y67008D01*
G01Y60630D02*
Y62008D01*
G01Y55630D02*
Y57008D01*
G01Y50630D02*
Y52008D01*
G01X615354Y182815D02*
Y44823D01*
G01X614764Y185059D02*
Y42579D01*
G01X614547Y52008D02*
Y50630D01*
G01Y57008D02*
Y55630D01*
G01Y62008D02*
Y60630D01*
G01Y67008D02*
Y65630D01*
G01Y72008D02*
Y70630D01*
G01Y77008D02*
Y75630D01*
G01Y82008D02*
Y80630D01*
G01X613976Y104862D02*
Y82776D01*
G01X613366Y51982D02*
Y52125D01*
G01Y56982D02*
Y57125D01*
G01Y61982D02*
Y62125D01*
G01Y66982D02*
Y67125D01*
G01Y71982D02*
Y72125D01*
G01Y76982D02*
Y77125D01*
G01Y81982D02*
Y82125D01*
G01Y80138D02*
Y82500D01*
G01Y75138D02*
Y77500D01*
G01Y70138D02*
Y72500D01*
G01Y65138D02*
Y67500D01*
G01Y60138D02*
Y62500D01*
G01Y55138D02*
Y57500D01*
G01Y50138D02*
Y52500D01*
G01X612795Y103681D02*
Y83957D01*
G01X612382Y52500D02*
Y50138D01*
G01Y57500D02*
Y55138D01*
G01Y62500D02*
Y60138D01*
G01Y67500D02*
Y65138D01*
G01Y72500D02*
Y70138D01*
G01Y77500D02*
Y75138D01*
G01Y82500D02*
Y80138D01*
G01X611811Y31240D02*
Y25138D01*
G01X611614Y43957D02*
Y35413D01*
G01X610039Y82776D02*
Y46319D01*
G01X609055Y40610D02*
Y38917D01*
G01X608858Y83957D02*
Y47500D01*
G01X606693Y38917D02*
Y40610D01*
G01X604134Y35413D02*
Y43957D01*
G01X603937Y31240D02*
Y25138D01*
G01X603346Y47500D02*
Y180138D01*
G01X602165Y46319D02*
Y181319D01*
G01X600394Y81614D02*
Y42579D01*
G01X599941Y93070D02*
Y94567D01*
G01Y89921D02*
Y91417D01*
G01Y86771D02*
Y88268D01*
G01Y83622D02*
Y85118D01*
G01X599902Y86918D02*
Y86771D01*
G01Y83768D02*
Y83621D01*
G01Y85119D02*
Y84972D01*
G01Y90067D02*
Y89920D01*
G01Y91418D02*
Y91271D01*
G01Y88268D02*
Y88121D01*
G01Y93217D02*
Y93070D01*
G01X598996D02*
Y93217D01*
G01Y89920D02*
Y90067D01*
G01Y91271D02*
Y91418D01*
G01Y88121D02*
Y88268D01*
G01Y86771D02*
Y86918D01*
G01Y83621D02*
Y83768D01*
G01Y84972D02*
Y85119D01*
G01X598957Y85118D02*
Y83622D01*
G01Y91417D02*
Y89921D01*
G01Y88268D02*
Y86772D01*
G01Y94567D02*
Y93071D01*
G01X597776Y88110D02*
Y86929D01*
G01Y84961D02*
Y83780D01*
G01Y91260D02*
Y90079D01*
G01Y94409D02*
Y93228D01*
G01X597441Y106024D02*
Y81614D01*
G01X597047D02*
Y106024D01*
G01Y41476D02*
Y25728D01*
G01X594016Y93228D02*
Y94409D01*
G01Y90079D02*
Y91260D01*
G01Y86929D02*
Y88110D01*
G01Y83780D02*
Y84961D01*
G01X599941Y93254D02*
Y93265D01*
G01Y90105D02*
Y90115D01*
G01Y86955D02*
Y86966D01*
G01Y83806D02*
Y83816D01*
G01X609055Y38917D02*
X611365Y34688D01*
G01X606693Y40610D02*
X605389Y42579D01*
G01X598954Y93263D02*
X598843Y93268D01*
G01X598954Y86965D02*
X598843Y86969D01*
G01X599939Y93268D02*
X594016D01*
G01X599900Y93228D02*
X594016D01*
G01X598957Y93071D02*
X599941D01*
G01X598996Y93031D02*
X599902D01*
G01Y91457D02*
X598996D01*
G01X599941Y91417D02*
X598957D01*
G01X599900Y91260D02*
X594016D01*
G01Y91220D02*
X599940D01*
G01X599939Y90118D02*
X594016D01*
G01X599900Y90079D02*
X594016D01*
G01X598957Y89921D02*
X599941D01*
G01X598996Y89882D02*
X599902D01*
G01Y88307D02*
X598996D01*
G01X599941Y88268D02*
X598957D01*
G01X599900Y88110D02*
X594016D01*
G01Y88071D02*
X599940D01*
G01X599939Y86969D02*
X594016D01*
G01X599900Y86929D02*
X594016D01*
G01X598957Y86772D02*
X599941D01*
G01X598996Y86732D02*
X599902D01*
G01Y85157D02*
X598996D01*
G01X599941Y85118D02*
X598957D01*
G01X599900Y84961D02*
X594016D01*
G01Y84921D02*
X599940D01*
G01X612795Y83957D02*
X608858D01*
G01X599939Y83819D02*
X594016D01*
G01X599900Y83780D02*
X594016D01*
G01X598957Y83622D02*
X599941D01*
G01X598996Y83583D02*
X599902D01*
G01X613976Y82776D02*
X610039D01*
G01X613366Y82500D02*
X612382D01*
G01X612383Y82008D02*
X617717D01*
G01Y81969D02*
X613369D01*
G01X600394Y81614D02*
X597047D01*
G01X617717Y80630D02*
X612383D01*
G01X612382Y80138D02*
X613366D01*
G01Y77500D02*
X612382D01*
G01X612383Y77008D02*
X617717D01*
G01Y76969D02*
X613369D01*
G01X617717Y75630D02*
X612383D01*
G01X612382Y75138D02*
X613366D01*
G01Y72500D02*
X612382D01*
G01X612383Y72008D02*
X617717D01*
G01Y71969D02*
X613369D01*
G01X617717Y70630D02*
X612383D01*
G01X612382Y70138D02*
X613366D01*
G01Y67500D02*
X612382D01*
G01X612383Y67008D02*
X617717D01*
G01Y66969D02*
X613369D01*
G01X617717Y65630D02*
X612383D01*
G01X612382Y65138D02*
X613366D01*
G01Y62500D02*
X612382D01*
G01X612383Y62008D02*
X617717D01*
G01Y61969D02*
X613369D01*
G01X617717Y60630D02*
X612383D01*
G01X612382Y60138D02*
X613366D01*
G01Y57500D02*
X612382D01*
G01X612383Y57008D02*
X617717D01*
G01Y56969D02*
X613369D01*
G01X617717Y55630D02*
X612383D01*
G01X612382Y55138D02*
X613366D01*
G01Y52500D02*
X612382D01*
G01X612383Y52008D02*
X617717D01*
G01Y51969D02*
X613369D01*
G01X617717Y50630D02*
X612383D01*
G01X612382Y50138D02*
X613366D01*
G01X608858Y47500D02*
X603346D01*
G01X610039Y46319D02*
X602165D01*
G01X615354Y44823D02*
X600394D01*
G01X611614Y43957D02*
X614764D01*
G01X604134D02*
X600394D01*
G01Y42579D02*
X614764D01*
G01X609055Y40610D02*
X606693D01*
G01X609055Y38917D02*
X606693D01*
G01X612382Y82204D02*
X613337Y82205D01*
G01X613366Y80434D02*
X612382Y80433D01*
G01Y77204D02*
X613337Y77205D01*
G01X613366Y75434D02*
X612382Y75433D01*
G01Y72204D02*
X613337Y72205D01*
G01X613366Y70434D02*
X612382Y70433D01*
G01Y67204D02*
X613337Y67205D01*
G01X613366Y65434D02*
X612382Y65433D01*
G01Y62204D02*
X613337Y62205D01*
G01X613366Y60434D02*
X612382Y60433D01*
G01Y57204D02*
X613337Y57205D01*
G01X613366Y55434D02*
X612382Y55433D01*
G01Y52204D02*
X613337Y52205D01*
G01X613366Y50434D02*
X612382Y50433D01*
G01X612795Y83957D02*
X613976Y82776D01*
G01X608858Y83957D02*
X610039Y82776D01*
G01X615354Y44823D02*
X618701Y41476D01*
G01X608858Y47500D02*
X610039Y46319D01*
G01X610433Y34232D02*
X605315D01*
G01X618701Y34193D02*
X597047D01*
G01X611811Y31240D02*
X603937D01*
G01Y29665D02*
X611811D01*
G01X609055Y28287D02*
X606693D01*
G01Y26319D02*
X609055D01*
G01X611220Y24547D02*
X604528D01*
G01X616732Y23760D02*
X599016D01*
G01X598957Y96407D02*
Y96404D01*
G01X598958Y96401D02*
X598957Y96407D01*
G01X598970Y96386D02*
X598958Y96401D01*
G01X598994Y96378D02*
X598970Y96386D01*
G01X598957Y99557D02*
Y99553D01*
G01X598958Y99551D02*
X598957Y99557D01*
G01X598970Y99536D02*
X598958Y99551D01*
G01X598994Y99528D02*
X598970Y99536D01*
G01X598957Y102707D02*
Y102703D01*
G01X598958Y102701D02*
X598957Y102707D01*
G01X598970Y102685D02*
X598958Y102701D01*
G01X598994Y102677D02*
X598970Y102685D01*
G01X613354Y106999D02*
X613365Y106984D01*
G01X613329Y107008D02*
X613354Y106999D01*
G01Y111999D02*
X613365Y111984D01*
G01X613329Y112008D02*
X613354Y111999D01*
G01X599909Y94408D02*
X599900Y94409D01*
G01X599919Y94405D02*
X599909Y94408D01*
G01X599926Y94400D02*
X599919Y94405D01*
G01X599909Y97558D02*
X599900Y97559D01*
G01X599919Y97555D02*
X599909Y97558D01*
G01X599926Y97549D02*
X599919Y97555D01*
G01X599909Y100707D02*
X599900Y100709D01*
G01X599919Y100704D02*
X599909Y100707D01*
G01X599926Y100699D02*
X599919Y100704D01*
G01X599909Y103857D02*
X599900Y103858D01*
G01X599919Y103854D02*
X599909Y103857D01*
G01X599926Y103848D02*
X599919Y103854D01*
G01X598996Y96373D02*
Y96367D01*
G01X598995Y96377D02*
X598996Y96373D01*
G01X598994Y96378D02*
X598995Y96377D01*
G01X598996Y99522D02*
Y99516D01*
G01X598995Y99526D02*
X598996Y99522D01*
G01X598994Y99528D02*
X598995Y99526D01*
G01X598996Y102672D02*
Y102666D01*
G01X598995Y102676D02*
X598996Y102672D01*
G01X598994Y102677D02*
X598995Y102676D01*
G01X598979Y94417D02*
X598976Y94415D01*
G01X598982Y94418D02*
X598979Y94417D01*
G01X598986Y94419D02*
X598982Y94418D01*
G01X598989Y94420D02*
X598986Y94419D01*
G01X598993Y94420D02*
X598989D01*
G01X598996D02*
X598993D01*
G01X599919Y96370D02*
X599922Y96372D01*
G01X599915Y96369D02*
X599919Y96370D01*
G01X599912Y96368D02*
X599915Y96369D01*
G01X599909Y96367D02*
X599912Y96368D01*
G01X599905Y96367D02*
X599909D01*
G01X599902D02*
X599905D01*
G01X598979Y97567D02*
X598976Y97565D01*
G01X598982Y97568D02*
X598979Y97567D01*
G01X598986Y97569D02*
X598982Y97568D01*
G01X598989Y97570D02*
X598986Y97569D01*
G01X598993Y97570D02*
X598989D01*
G01X598996D02*
X598993D01*
G01X598979Y100716D02*
X598976Y100715D01*
G01X598982Y100717D02*
X598979Y100716D01*
G01X598986Y100719D02*
X598982Y100717D01*
G01X598989Y100719D02*
X598986D01*
G01X598993Y100720D02*
X598989Y100719D01*
G01X598996Y100720D02*
X598993D01*
G01X598209Y96417D02*
X597776D01*
G01X598583D02*
X598209D01*
G01X599931Y94408D02*
X599935Y94402D01*
G01X599927Y94412D02*
X599931Y94408D01*
G01X599921Y94416D02*
X599927Y94412D01*
G01X599915Y94419D02*
X599921Y94416D01*
G01X599908Y94420D02*
X599915Y94419D01*
G01X599902Y94420D02*
X599908D01*
G01X599931Y97557D02*
X599935Y97552D01*
G01X599927Y97562D02*
X599931Y97557D01*
G01X599921Y97565D02*
X599927Y97562D01*
G01X599915Y97568D02*
X599921Y97565D01*
G01X599908Y97570D02*
X599915Y97568D01*
G01X599902Y97570D02*
X599908D01*
G01X599931Y100707D02*
X599935Y100702D01*
G01X599927Y100711D02*
X599931Y100707D01*
G01X599921Y100715D02*
X599927Y100711D01*
G01X599915Y100718D02*
X599921Y100715D01*
G01X599908Y100719D02*
X599915Y100718D01*
G01X599902Y100720D02*
X599908Y100719D01*
G01X599931Y103857D02*
X599935Y103851D01*
G01X599927Y103861D02*
X599931Y103857D01*
G01X599921Y103865D02*
X599927Y103861D01*
G01X599915Y103867D02*
X599921Y103865D01*
G01X599908Y103869D02*
X599915Y103867D01*
G01X599902Y103869D02*
X599908D01*
G01X598957Y96396D02*
Y96404D01*
G01X598960Y96389D02*
X598957Y96396D01*
G01X598963Y96383D02*
X598960Y96389D01*
G01X598968Y96378D02*
X598963Y96383D01*
G01X598974Y96373D02*
X598968Y96378D01*
G01X598981Y96369D02*
X598974Y96373D01*
G01X598989Y96367D02*
X598981Y96369D01*
G01X598996Y96367D02*
X598989D01*
G01X598957Y99546D02*
Y99553D01*
G01X598960Y99539D02*
X598957Y99546D01*
G01X598963Y99533D02*
X598960Y99539D01*
G01X598968Y99527D02*
X598963Y99533D01*
G01X598974Y99522D02*
X598968Y99527D01*
G01X598981Y99519D02*
X598974Y99522D01*
G01X598989Y99517D02*
X598981Y99519D01*
G01X598996Y99516D02*
X598989Y99517D01*
G01X598957Y102696D02*
Y102703D01*
G01X598960Y102689D02*
X598957Y102696D01*
G01X598963Y102682D02*
X598960Y102689D01*
G01X598968Y102677D02*
X598963Y102682D01*
G01X598974Y102672D02*
X598968Y102677D01*
G01X598981Y102669D02*
X598974Y102672D01*
G01X598989Y102667D02*
X598981Y102669D01*
G01X598996Y102666D02*
X598989Y102667D01*
G01X599911Y94408D02*
X599920Y94404D01*
G01X599900Y94409D02*
X599911Y94408D01*
G01Y97557D02*
X599920Y97554D01*
G01X599900Y97559D02*
X599911Y97557D01*
G01Y100707D02*
X599920Y100703D01*
G01X599900Y100709D02*
X599911Y100707D01*
G01Y103857D02*
X599920Y103853D01*
G01X599900Y103858D02*
X599911Y103857D01*
G01X613354Y116999D02*
X613365Y116984D01*
G01X613329Y117008D02*
X613354Y116999D01*
G01Y121999D02*
X613365Y121984D01*
G01X613329Y122008D02*
X613354Y121999D01*
G01Y126999D02*
X613365Y126984D01*
G01X613329Y127008D02*
X613354Y126999D01*
G01Y131999D02*
X613365Y131984D01*
G01X613329Y132008D02*
X613354Y131999D01*
G01Y136999D02*
X613365Y136984D01*
G01X613329Y137008D02*
X613354Y136999D01*
G01Y141999D02*
X613365Y141984D01*
G01X613329Y142008D02*
X613354Y141999D01*
G01Y146999D02*
X613365Y146984D01*
G01X613329Y147008D02*
X613354Y146999D01*
G01Y151999D02*
X613365Y151984D01*
G01X613329Y152008D02*
X613354Y151999D01*
G01Y156999D02*
X613365Y156984D01*
G01X613329Y157008D02*
X613354Y156999D01*
G01Y161999D02*
X613365Y161984D01*
G01X613329Y162008D02*
X613354Y161999D01*
G01Y166999D02*
X613365Y166984D01*
G01X613329Y167008D02*
X613354Y166999D01*
G01Y171999D02*
X613365Y171984D01*
G01X613329Y172008D02*
X613354Y171999D01*
G01Y176999D02*
X613365Y176984D01*
G01X613329Y177008D02*
X613354Y176999D01*
G01X613367Y106975D02*
X613366Y106982D01*
G01X613367Y106970D02*
Y106975D01*
G01X613369Y106969D02*
X613367Y106970D01*
G01Y111975D02*
X613366Y111982D01*
G01X613367Y111970D02*
Y111975D01*
G01X613369Y111969D02*
X613367Y111970D01*
G01Y116975D02*
X613366Y116982D01*
G01X613367Y116970D02*
Y116975D01*
G01X613369Y116969D02*
X613367Y116970D01*
G01Y121975D02*
X613366Y121982D01*
G01X613367Y121970D02*
Y121975D01*
G01X613369Y121969D02*
X613367Y121970D01*
G01Y126975D02*
X613366Y126982D01*
G01X613367Y126970D02*
Y126975D01*
G01X613369Y126969D02*
X613367Y126970D01*
G01Y131975D02*
X613366Y131982D01*
G01X613367Y131970D02*
Y131975D01*
G01X613369Y131969D02*
X613367Y131970D01*
G01Y136975D02*
X613366Y136982D01*
G01X613367Y136970D02*
Y136975D01*
G01X613369Y136969D02*
X613367Y136970D01*
G01Y141975D02*
X613366Y141982D01*
G01X613367Y141970D02*
Y141975D01*
G01X613369Y141969D02*
X613367Y141970D01*
G01Y146975D02*
X613366Y146982D01*
G01X613367Y146970D02*
Y146975D01*
G01X613369Y146969D02*
X613367Y146970D01*
G01Y151975D02*
X613366Y151982D01*
G01X613367Y151970D02*
Y151975D01*
G01X613369Y151969D02*
X613367Y151970D01*
G01Y156975D02*
X613366Y156982D01*
G01X613367Y156970D02*
Y156975D01*
G01X613369Y156969D02*
X613367Y156970D01*
G01Y161975D02*
X613366Y161982D01*
G01X613367Y161970D02*
Y161975D01*
G01X613369Y161969D02*
X613367Y161970D01*
G01X598980Y96380D02*
X598994Y96378D01*
G01X598968Y96388D02*
X598980Y96380D01*
G01X598956Y96406D02*
X598968Y96388D01*
G01X598979Y99530D02*
X598994Y99528D01*
G01X598967Y99538D02*
X598979Y99530D01*
G01X598955Y99558D02*
X598967Y99538D01*
G01X599941Y96411D02*
Y96404D01*
G01X599940Y96416D02*
X599941Y96411D01*
G01X599939Y96417D02*
X599940Y96416D01*
G01X599941Y99561D02*
Y99553D01*
G01X599940Y99565D02*
X599941Y99561D01*
G01X599939Y99567D02*
X599940Y99565D01*
G01X599941Y102711D02*
Y102703D01*
G01X599940Y102715D02*
X599941Y102711D01*
G01X599939Y102717D02*
X599940Y102715D01*
G01X598979Y102680D02*
X598994Y102677D01*
G01X598967Y102688D02*
X598979Y102680D01*
G01X598955Y102708D02*
X598967Y102688D01*
G01X599940Y99546D02*
X599941Y99553D01*
G01X599938Y99539D02*
X599940Y99546D01*
G01X599934Y99533D02*
X599938Y99539D01*
G01X599930Y99527D02*
X599934Y99533D01*
G01X599923Y99522D02*
X599930Y99527D01*
G01X599917Y99519D02*
X599923Y99522D01*
G01X599909Y99517D02*
X599917Y99519D01*
G01X599902Y99516D02*
X599909Y99517D01*
G01X599919Y102669D02*
X599922Y102671D01*
G01X599915Y102668D02*
X599919Y102669D01*
G01X599912Y102667D02*
X599915Y102668D01*
G01X599909Y102667D02*
X599912D01*
G01X599905Y102666D02*
X599909Y102667D01*
G01X599902Y102666D02*
X599905D01*
G01X598979Y103866D02*
X598976Y103864D01*
G01X598982Y103867D02*
X598979Y103866D01*
G01X598986Y103868D02*
X598982Y103867D01*
G01X598989Y103869D02*
X598986Y103868D01*
G01X598993Y103869D02*
X598989D01*
G01X598996D02*
X598993D01*
G01X613367Y166975D02*
X613366Y166982D01*
G01X613367Y166970D02*
Y166975D01*
G01X613369Y166969D02*
X613367Y166970D01*
G01Y171975D02*
X613366Y171982D01*
G01X613367Y171970D02*
Y171975D01*
G01X613369Y171969D02*
X613367Y171970D01*
G01Y176975D02*
X613366Y176982D01*
G01X613367Y176970D02*
Y176975D01*
G01X613369Y176969D02*
X613367Y176970D01*
G01X599940Y94390D02*
X599941Y94383D01*
G01X599939Y94396D02*
X599940Y94390D01*
G01X599935Y94402D02*
X599939Y94396D01*
G01X599940Y97540D02*
X599941Y97533D01*
G01X599939Y97546D02*
X599940Y97540D01*
G01X599935Y97552D02*
X599939Y97546D01*
G01X599940Y100689D02*
X599941Y100683D01*
G01X599939Y100696D02*
X599940Y100689D01*
G01X599935Y100702D02*
X599939Y100696D01*
G01X599940Y103839D02*
X599941Y103832D01*
G01X599939Y103845D02*
X599940Y103839D01*
G01X599935Y103851D02*
X599939Y103845D01*
G01X599902Y96373D02*
Y96367D01*
G01X599901Y96376D02*
X599902Y96373D01*
G01X599900Y96378D02*
X599901Y96376D01*
G01X599902Y102672D02*
Y102666D01*
G01X599901Y102676D02*
X599902Y102672D01*
G01X599900Y102677D02*
X599901Y102676D01*
G01X612382Y107015D02*
Y107024D01*
G01X612383Y107009D02*
X612382Y107015D01*
G01X612383Y107008D02*
Y107009D01*
G01X612382Y112015D02*
Y112024D01*
G01X612383Y112009D02*
X612382Y112015D01*
G01X612383Y112008D02*
Y112009D01*
G01X612382Y117015D02*
Y117024D01*
G01X612383Y117009D02*
X612382Y117015D01*
G01X612383Y117008D02*
Y117009D01*
G01X612382Y122015D02*
Y122024D01*
G01X612383Y122009D02*
X612382Y122015D01*
G01X612383Y122008D02*
Y122009D01*
G01X612382Y127015D02*
Y127024D01*
G01X612383Y127009D02*
X612382Y127015D01*
G01X612383Y127008D02*
Y127009D01*
G01X612382Y132015D02*
Y132024D01*
G01X612383Y132009D02*
X612382Y132015D01*
G01X612383Y132008D02*
Y132009D01*
G01X612382Y137015D02*
Y137024D01*
G01X612383Y137009D02*
X612382Y137015D01*
G01X612383Y137008D02*
Y137009D01*
G01X612382Y142015D02*
Y142024D01*
G01X612383Y142009D02*
X612382Y142015D01*
G01X612383Y142008D02*
Y142009D01*
G01X612382Y147015D02*
Y147024D01*
G01X612383Y147009D02*
X612382Y147015D01*
G01X612383Y147008D02*
Y147009D01*
G01X612382Y152015D02*
Y152024D01*
G01X612383Y152009D02*
X612382Y152015D01*
G01X612383Y152008D02*
Y152009D01*
G01X612382Y157015D02*
Y157024D01*
G01X612383Y157009D02*
X612382Y157015D01*
G01X612383Y157008D02*
Y157009D01*
G01X612382Y162015D02*
Y162024D01*
G01X612383Y162009D02*
X612382Y162015D01*
G01X612383Y162008D02*
Y162009D01*
G01X612382Y167015D02*
Y167024D01*
G01X612383Y167009D02*
X612382Y167015D01*
G01X612383Y167008D02*
Y167009D01*
G01X613358Y107152D02*
X613366Y107125D01*
G01X613348Y107178D02*
X613358Y107152D01*
G01X613337Y107205D02*
X613348Y107178D01*
G01X613358Y112152D02*
X613366Y112125D01*
G01X613348Y112178D02*
X613358Y112152D01*
G01X613337Y112205D02*
X613348Y112178D01*
G01X613358Y117152D02*
X613366Y117125D01*
G01X613348Y117178D02*
X613358Y117152D01*
G01X613337Y117205D02*
X613348Y117178D01*
G01X613358Y122152D02*
X613366Y122125D01*
G01X613348Y122178D02*
X613358Y122152D01*
G01X613337Y122205D02*
X613348Y122178D01*
G01X613358Y127152D02*
X613366Y127125D01*
G01X613348Y127178D02*
X613358Y127152D01*
G01X613337Y127205D02*
X613348Y127178D01*
G01X613358Y132152D02*
X613366Y132125D01*
G01X613348Y132178D02*
X613358Y132152D01*
G01X613337Y132205D02*
X613348Y132178D01*
G01X613358Y137152D02*
X613366Y137125D01*
G01X613348Y137178D02*
X613358Y137152D01*
G01X613337Y137205D02*
X613348Y137178D01*
G01X613358Y142152D02*
X613366Y142125D01*
G01X613348Y142178D02*
X613358Y142152D01*
G01X613337Y142205D02*
X613348Y142178D01*
G01X613358Y147152D02*
X613366Y147125D01*
G01X613348Y147178D02*
X613358Y147152D01*
G01X613337Y147205D02*
X613348Y147178D01*
G01X613358Y152152D02*
X613366Y152125D01*
G01X613348Y152178D02*
X613358Y152152D01*
G01X613337Y152205D02*
X613348Y152178D01*
G01X613358Y157152D02*
X613366Y157125D01*
G01X613348Y157178D02*
X613358Y157152D01*
G01X613337Y157205D02*
X613348Y157178D01*
G01X598959Y94390D02*
X598954Y94370D01*
G01X598974Y94404D02*
X598959Y94390D01*
G01X598994Y94409D02*
X598974Y94404D01*
G01X598959Y97539D02*
X598954Y97520D01*
G01X598974Y97554D02*
X598959Y97539D01*
G01X598994Y97559D02*
X598974Y97554D01*
G01X598959Y100689D02*
X598954Y100669D01*
G01X598974Y100703D02*
X598959Y100689D01*
G01X598994Y100709D02*
X598974Y100703D01*
G01X598959Y103839D02*
X598954Y103819D01*
G01X598974Y103853D02*
X598959Y103839D01*
G01X598994Y103858D02*
X598974Y103853D01*
G01X599934Y96398D02*
X599939Y96417D01*
G01X599920Y96383D02*
X599934Y96398D01*
G01X599900Y96378D02*
X599920Y96383D01*
G01X599934Y99547D02*
X599939Y99567D01*
G01X599920Y99533D02*
X599934Y99547D01*
G01X599900Y99528D02*
X599920Y99533D01*
G01X599934Y102697D02*
X599939Y102717D01*
G01X599920Y102682D02*
X599934Y102697D01*
G01X599900Y102677D02*
X599920Y102682D01*
G01X612382Y172015D02*
Y172024D01*
G01X612383Y172009D02*
X612382Y172015D01*
G01X612383Y172008D02*
Y172009D01*
G01X612382Y177015D02*
Y177024D01*
G01X612383Y177009D02*
X612382Y177015D01*
G01X612383Y177008D02*
Y177009D01*
G01X613358Y162152D02*
X613366Y162125D01*
G01X613348Y162178D02*
X613358Y162152D01*
G01X613337Y162205D02*
X613348Y162178D01*
G01X613358Y167152D02*
X613366Y167125D01*
G01X613348Y167178D02*
X613358Y167152D01*
G01X613337Y167205D02*
X613348Y167178D01*
G01X613358Y172152D02*
X613366Y172125D01*
G01X613348Y172178D02*
X613358Y172152D01*
G01X613337Y172205D02*
X613348Y172178D01*
G01X613358Y177152D02*
X613366Y177125D01*
G01X613348Y177178D02*
X613358Y177152D01*
G01X613337Y177205D02*
X613348Y177178D01*
G01X613349Y107003D02*
X613330Y107008D01*
G01X613363Y106988D02*
X613349Y107003D01*
G01X613369Y106969D02*
X613363Y106988D01*
G01X613349Y112003D02*
X613330Y112008D01*
G01X613363Y111988D02*
X613349Y112003D01*
G01X613369Y111969D02*
X613363Y111988D01*
G01X613349Y117003D02*
X613330Y117008D01*
G01X613363Y116988D02*
X613349Y117003D01*
G01X613369Y116969D02*
X613363Y116988D01*
G01X613349Y122003D02*
X613330Y122008D01*
G01X613363Y121988D02*
X613349Y122003D01*
G01X613369Y121969D02*
X613363Y121988D01*
G01X613349Y127003D02*
X613330Y127008D01*
G01X613363Y126988D02*
X613349Y127003D01*
G01X613369Y126969D02*
X613363Y126988D01*
G01X613349Y132003D02*
X613330Y132008D01*
G01X613363Y131988D02*
X613349Y132003D01*
G01X613369Y131969D02*
X613363Y131988D01*
G01X613349Y137003D02*
X613330Y137008D01*
G01X613363Y136988D02*
X613349Y137003D01*
G01X613369Y136969D02*
X613363Y136988D01*
G01X613349Y142003D02*
X613330Y142008D01*
G01X613363Y141988D02*
X613349Y142003D01*
G01X613369Y141969D02*
X613363Y141988D01*
G01X613349Y147003D02*
X613330Y147008D01*
G01X613363Y146988D02*
X613349Y147003D01*
G01X613369Y146969D02*
X613363Y146988D01*
G01X613349Y152003D02*
X613330Y152008D01*
G01X613363Y151988D02*
X613349Y152003D01*
G01X613369Y151969D02*
X613363Y151988D01*
G01X613349Y157003D02*
X613330Y157008D01*
G01X613363Y156988D02*
X613349Y157003D01*
G01X613369Y156969D02*
X613363Y156988D01*
G01X613349Y162003D02*
X613330Y162008D01*
G01X613363Y161988D02*
X613349Y162003D01*
G01X613369Y161969D02*
X613363Y161988D01*
G01X613349Y167003D02*
X613330Y167008D01*
G01X613363Y166988D02*
X613349Y167003D01*
G01X613369Y166969D02*
X613363Y166988D01*
G01X613349Y172003D02*
X613330Y172008D01*
G01X613363Y171988D02*
X613349Y172003D01*
G01X613369Y171969D02*
X613363Y171988D01*
G01X613349Y177003D02*
X613330Y177008D01*
G01X613363Y176988D02*
X613349Y177003D01*
G01X613369Y176969D02*
X613363Y176988D01*
G01X599933Y94391D02*
X599926Y94400D01*
G01X599938Y94381D02*
X599933Y94391D01*
G01X599940Y94370D02*
X599938Y94381D01*
G01X599933Y97541D02*
X599926Y97549D01*
G01X599938Y97531D02*
X599933Y97541D01*
G01X599940Y97520D02*
X599938Y97531D01*
G01X599933Y100691D02*
X599926Y100699D01*
G01X599938Y100680D02*
X599933Y100691D01*
G01X599940Y100669D02*
X599938Y100680D01*
G01X599933Y103840D02*
X599926Y103848D01*
G01X599938Y103830D02*
X599933Y103840D01*
G01X599940Y103819D02*
X599938Y103830D01*
G01X613333Y107106D02*
X613337Y107205D01*
G01X613328Y107034D02*
X613333Y107106D01*
G01X613330Y107008D02*
X613328Y107034D01*
G01X613333Y112106D02*
X613337Y112205D01*
G01X613328Y112034D02*
X613333Y112106D01*
G01X613330Y112008D02*
X613328Y112034D01*
G01X613333Y117106D02*
X613337Y117205D01*
G01X613328Y117034D02*
X613333Y117106D01*
G01X613330Y117008D02*
X613328Y117034D01*
G01X613333Y122106D02*
X613337Y122205D01*
G01X613328Y122034D02*
X613333Y122106D01*
G01X613330Y122008D02*
X613328Y122034D01*
G01X613333Y127106D02*
X613337Y127205D01*
G01X613328Y127034D02*
X613333Y127106D01*
G01X613330Y127008D02*
X613328Y127034D01*
G01X613333Y132106D02*
X613337Y132205D01*
G01X613328Y132034D02*
X613333Y132106D01*
G01X613330Y132008D02*
X613328Y132034D01*
G01X613333Y137106D02*
X613337Y137205D01*
G01X613328Y137034D02*
X613333Y137106D01*
G01X613330Y137008D02*
X613328Y137034D01*
G01X613333Y142106D02*
X613337Y142205D01*
G01X613328Y142034D02*
X613333Y142106D01*
G01X613330Y142008D02*
X613328Y142034D01*
G01X613333Y147106D02*
X613337Y147205D01*
G01X613328Y147034D02*
X613333Y147106D01*
G01X613330Y147008D02*
X613328Y147034D01*
G01X613333Y152106D02*
X613337Y152205D01*
G01X613328Y152034D02*
X613333Y152106D01*
G01X613330Y152008D02*
X613328Y152034D01*
G01X613333Y157106D02*
X613337Y157205D01*
G01X613328Y157034D02*
X613333Y157106D01*
G01X613330Y157008D02*
X613328Y157034D01*
G01X613333Y162106D02*
X613337Y162205D01*
G01X613328Y162034D02*
X613333Y162106D01*
G01X613330Y162008D02*
X613328Y162034D01*
G01X613333Y167106D02*
X613337Y167205D01*
G01X613328Y167034D02*
X613333Y167106D01*
G01X613330Y167008D02*
X613328Y167034D01*
G01X613333Y172106D02*
X613337Y172205D01*
G01X613328Y172034D02*
X613333Y172106D01*
G01X613330Y172008D02*
X613328Y172034D01*
G01X613333Y177106D02*
X613337Y177205D01*
G01X613328Y177034D02*
X613333Y177106D01*
G01X613330Y177008D02*
X613328Y177034D01*
G01X598956Y96411D02*
X598957Y96404D01*
G01X598956Y96416D02*
Y96411D01*
G01Y96406D02*
Y96416D01*
G01X598997Y104043D02*
X598996Y104055D01*
G01X598994Y104030D02*
X598997Y104043D01*
G01X598994Y104016D02*
Y104030D01*
G01X598997Y100893D02*
X598996Y100906D01*
G01X598994Y100880D02*
X598997Y100893D01*
G01X598994Y100866D02*
Y100880D01*
G01X598997Y97743D02*
X598996Y97756D01*
G01X598994Y97730D02*
X598997Y97743D01*
G01X598994Y97717D02*
Y97730D01*
G01X598997Y94594D02*
X598996Y94606D01*
G01X598994Y94581D02*
X598997Y94594D01*
G01X598994Y94567D02*
Y94581D01*
G01X612383Y175628D02*
Y175630D01*
G01X612382Y175622D02*
X612383Y175628D01*
G01X612382Y175614D02*
Y175622D01*
G01X612383Y170628D02*
Y170630D01*
G01X612382Y170622D02*
X612383Y170628D01*
G01X612382Y170614D02*
Y170622D01*
G01X612383Y165628D02*
Y165630D01*
G01X612382Y165622D02*
X612383Y165628D01*
G01X612382Y165614D02*
Y165622D01*
G01X612383Y160628D02*
Y160630D01*
G01X612382Y160622D02*
X612383Y160628D01*
G01X612382Y160614D02*
Y160622D01*
G01X612383Y155628D02*
Y155630D01*
G01X612382Y155622D02*
X612383Y155628D01*
G01X612382Y155614D02*
Y155622D01*
G01X612383Y150628D02*
Y150630D01*
G01X612382Y150622D02*
X612383Y150628D01*
G01X612382Y150614D02*
Y150622D01*
G01X612383Y145628D02*
Y145630D01*
G01X612382Y145622D02*
X612383Y145628D01*
G01X612382Y145614D02*
Y145622D01*
G01X612383Y140628D02*
Y140630D01*
G01X612382Y140622D02*
X612383Y140628D01*
G01X612382Y140614D02*
Y140622D01*
G01X612383Y135628D02*
Y135630D01*
G01X612382Y135622D02*
X612383Y135628D01*
G01X612382Y135614D02*
Y135622D01*
G01X612383Y130628D02*
Y130630D01*
G01X612382Y130622D02*
X612383Y130628D01*
G01X612382Y130614D02*
Y130622D01*
G01X612383Y125628D02*
Y125630D01*
G01X612382Y125622D02*
X612383Y125628D01*
G01X612382Y125614D02*
Y125622D01*
G01X612383Y120628D02*
Y120630D01*
G01X612382Y120622D02*
X612383Y120628D01*
G01X612382Y120614D02*
Y120622D01*
G01X612383Y115628D02*
Y115630D01*
G01X612382Y115622D02*
X612383Y115628D01*
G01X612382Y115614D02*
Y115622D01*
G01X612383Y110628D02*
Y110630D01*
G01X612382Y110622D02*
X612383Y110628D01*
G01X612382Y110614D02*
Y110622D01*
G01X612383Y105628D02*
Y105630D01*
G01X612382Y105622D02*
X612383Y105628D01*
G01X612382Y105614D02*
Y105622D01*
G01X598956Y102711D02*
X598957Y102703D01*
G01X598956Y102715D02*
Y102711D01*
G01Y102707D02*
Y102715D01*
G01X598994Y102506D02*
X598993Y102519D01*
G01X598997Y102493D02*
X598994Y102506D01*
G01X598996Y102480D02*
X598997Y102493D01*
G01X598994Y99356D02*
X598993Y99370D01*
G01X598997Y99343D02*
X598994Y99356D01*
G01X598996Y99331D02*
X598997Y99343D01*
G01X598994Y96206D02*
X598993Y96220D01*
G01X598997Y96194D02*
X598994Y96206D01*
G01X598996Y96181D02*
X598997Y96194D01*
G01X599904Y104030D02*
X599905Y104016D01*
G01X599901Y104043D02*
X599904Y104030D01*
G01X599902Y104055D02*
X599901Y104043D01*
G01X599904Y100880D02*
X599905Y100866D01*
G01X599901Y100893D02*
X599904Y100880D01*
G01X599902Y100906D02*
X599901Y100893D01*
G01X599904Y97730D02*
X599905Y97717D01*
G01X599901Y97743D02*
X599904Y97730D01*
G01X599902Y97756D02*
X599901Y97743D01*
G01X599904Y94581D02*
X599905Y94567D01*
G01X599901Y94594D02*
X599904Y94581D01*
G01X599902Y94606D02*
X599901Y94594D01*
G01X598956Y99561D02*
X598957Y99554D01*
G01X598956Y99565D02*
Y99561D01*
G01X598955Y99558D02*
X598956Y99565D01*
G01X599901Y102493D02*
X599902Y102480D01*
G01X599904Y102506D02*
X599901Y102493D01*
G01X599905Y102519D02*
X599904Y102506D01*
G01X599901Y99343D02*
X599902Y99331D01*
G01X599904Y99356D02*
X599901Y99343D01*
G01X599905Y99370D02*
X599904Y99356D01*
G01X599901Y96194D02*
X599902Y96181D01*
G01X599904Y96206D02*
X599901Y96194D01*
G01X599905Y96220D02*
X599904Y96206D01*
G01X598970Y103850D02*
X598994Y103858D01*
G01X598959Y103835D02*
X598970Y103850D01*
G01X598957Y103828D02*
X598959Y103835D01*
G01X598970Y100700D02*
X598994Y100709D01*
G01X598959Y100685D02*
X598970Y100700D01*
G01X598957Y100679D02*
X598959Y100685D01*
G01X598970Y97550D02*
X598994Y97559D01*
G01X598959Y97536D02*
X598970Y97550D01*
G01X598957Y97529D02*
X598959Y97536D01*
G01X598970Y94401D02*
X598994Y94409D01*
G01X598959Y94386D02*
X598970Y94401D01*
G01X598957Y94380D02*
X598959Y94386D01*
G01X599941Y103825D02*
Y103832D01*
G01Y103820D02*
Y103825D01*
G01X599940Y103819D02*
X599941Y103820D01*
G01Y100676D02*
Y100683D01*
G01Y100671D02*
Y100676D01*
G01X599940Y100669D02*
X599941Y100671D01*
G01Y97526D02*
Y97533D01*
G01Y97521D02*
Y97526D01*
G01X599940Y97520D02*
X599941Y97521D01*
G01Y94376D02*
Y94383D01*
G01Y94372D02*
Y94376D01*
G01X599940Y94370D02*
X599941Y94372D01*
G01X599902Y103863D02*
Y103869D01*
G01X599901Y103859D02*
X599902Y103863D01*
G01X599900Y103858D02*
X599901Y103859D01*
G01X599902Y100714D02*
Y100720D01*
G01X599901Y100710D02*
X599902Y100714D01*
G01X599900Y100709D02*
X599901Y100710D01*
G01X599902Y97564D02*
Y97570D01*
G01X599901Y97560D02*
X599902Y97564D01*
G01X599900Y97559D02*
X599901Y97560D01*
G01X599902Y94415D02*
Y94420D01*
G01X599901Y94411D02*
X599902Y94415D01*
G01X599900Y94409D02*
X599901Y94411D01*
G01X613367Y175622D02*
X613366Y175613D01*
G01X613367Y175628D02*
Y175622D01*
G01X613369Y175630D02*
X613367Y175628D01*
G01Y170622D02*
X613366Y170613D01*
G01X613367Y170628D02*
Y170622D01*
G01X613369Y170630D02*
X613367Y170628D01*
G01Y165622D02*
X613366Y165613D01*
G01X613367Y165628D02*
Y165622D01*
G01X613369Y165630D02*
X613367Y165628D01*
G01Y160622D02*
X613366Y160613D01*
G01X613367Y160628D02*
Y160622D01*
G01X613369Y160630D02*
X613367Y160628D01*
G01Y155622D02*
X613366Y155613D01*
G01X613367Y155628D02*
Y155622D01*
G01X613369Y155630D02*
X613367Y155628D01*
G01Y150622D02*
X613366Y150613D01*
G01X613367Y150628D02*
Y150622D01*
G01X613369Y150630D02*
X613367Y150628D01*
G01Y145622D02*
X613366Y145613D01*
G01X613367Y145628D02*
Y145622D01*
G01X613369Y145630D02*
X613367Y145628D01*
G01Y140622D02*
X613366Y140613D01*
G01X613367Y140628D02*
Y140622D01*
G01X613369Y140630D02*
X613367Y140628D01*
G01Y135622D02*
X613366Y135613D01*
G01X613367Y135628D02*
Y135622D01*
G01X613369Y135630D02*
X613367Y135628D01*
G01Y130622D02*
X613366Y130613D01*
G01X613367Y130628D02*
Y130622D01*
G01X613369Y130630D02*
X613367Y130628D01*
G01Y125622D02*
X613366Y125613D01*
G01X613367Y125628D02*
Y125622D01*
G01X613369Y125630D02*
X613367Y125628D01*
G01Y120622D02*
X613366Y120613D01*
G01X613367Y120628D02*
Y120622D01*
G01X613369Y120630D02*
X613367Y120628D01*
G01Y115622D02*
X613366Y115613D01*
G01X613367Y115628D02*
Y115622D01*
G01X613369Y115630D02*
X613367Y115628D01*
G01Y110622D02*
X613366Y110613D01*
G01X613367Y110628D02*
Y110622D01*
G01X613369Y110630D02*
X613367Y110628D01*
G01Y105622D02*
X613366Y105613D01*
G01X613367Y105628D02*
Y105622D01*
G01X613369Y105630D02*
X613367Y105628D01*
G01X598956Y103825D02*
X598957Y103832D01*
G01X598956Y103820D02*
Y103825D01*
G01X598954Y103819D02*
X598956Y103820D01*
G01Y100675D02*
X598957Y100683D01*
G01X598956Y100671D02*
Y100675D01*
G01X598954Y100669D02*
X598956Y100671D01*
G01Y97526D02*
X598957Y97533D01*
G01X598956Y97521D02*
Y97526D01*
G01X598954Y97520D02*
X598956Y97521D01*
G01Y94376D02*
X598957Y94383D01*
G01X598956Y94372D02*
Y94376D01*
G01X598954Y94370D02*
X598956Y94372D01*
G01X599939Y102691D02*
X599941Y102703D01*
G01X599932Y102679D02*
X599939Y102691D01*
G01X599922Y102671D02*
X599932Y102679D01*
G01X599939Y96391D02*
X599941Y96404D01*
G01X599932Y96380D02*
X599939Y96391D01*
G01X599922Y96372D02*
X599932Y96380D01*
G01X598995Y103863D02*
Y103869D01*
G01Y103859D02*
Y103863D01*
G01X598994Y103858D02*
X598995Y103859D01*
G01Y100713D02*
Y100720D01*
G01Y100710D02*
Y100713D01*
G01X598994Y100709D02*
X598995Y100710D01*
G01Y97564D02*
Y97570D01*
G01Y97560D02*
Y97564D01*
G01X598994Y97559D02*
X598995Y97560D01*
G01Y94414D02*
Y94420D01*
G01Y94411D02*
Y94414D01*
G01X598994Y94409D02*
X598995Y94411D01*
G01X598957Y103839D02*
Y103832D01*
G01X598959Y103845D02*
X598957Y103839D01*
G01X598962Y103851D02*
X598959Y103845D01*
G01X598966Y103856D02*
X598962Y103851D01*
G01X598970Y103861D02*
X598966Y103856D01*
G01X598976Y103864D02*
X598970Y103861D01*
G01X598957Y100689D02*
Y100683D01*
G01X598959Y100695D02*
X598957Y100689D01*
G01X598962Y100701D02*
X598959Y100695D01*
G01X598966Y100706D02*
X598962Y100701D01*
G01X598970Y100711D02*
X598966Y100706D01*
G01X598976Y100715D02*
X598970Y100711D01*
G01X598957Y97539D02*
Y97533D01*
G01X598959Y97546D02*
X598957Y97539D01*
G01X598962Y97552D02*
X598959Y97546D01*
G01X598966Y97557D02*
X598962Y97552D01*
G01X598970Y97561D02*
X598966Y97557D01*
G01X598976Y97565D02*
X598970Y97561D01*
G01X598957Y94390D02*
Y94383D01*
G01X598959Y94396D02*
X598957Y94390D01*
G01X598962Y94402D02*
X598959Y94396D01*
G01X598966Y94407D02*
X598962Y94402D01*
G01X598970Y94412D02*
X598966Y94407D01*
G01X598976Y94415D02*
X598970Y94412D01*
G01X599912Y102679D02*
X599900Y102677D01*
G01X599922Y102684D02*
X599912Y102679D01*
G01Y99530D02*
X599900Y99528D01*
G01X599922Y99534D02*
X599912Y99530D01*
G01Y96380D02*
X599900Y96378D01*
G01X599922Y96385D02*
X599912Y96380D01*
G01X664567Y122047D02*
G03X675591I5512J0D01*
G01D02*
G03X664567I-5512J0D01*
G01X609764Y188130D02*
G03I-1890J0D01*
G01X610236D02*
G03I-2362J0D01*
G01X675591Y122047D02*
G03I-5512J0D01*
G01X612795Y103681D02*
X613976Y104862D01*
G01X608858Y103681D02*
X610039Y104862D01*
G01X618701Y186161D02*
X615354Y182815D01*
G01X608858Y180138D02*
X610039Y181319D01*
G01X605389Y185059D02*
X606693Y187028D01*
G01X611365Y192950D02*
X609055Y188720D01*
G01X599941Y94372D02*
Y94383D01*
G01Y97522D02*
Y97533D01*
G01Y100671D02*
Y100683D01*
G01Y103821D02*
Y103832D01*
G01X613366Y106982D02*
X613367Y106991D01*
G01X613366Y111982D02*
X613367Y111991D01*
G01X613366Y116982D02*
X613367Y116991D01*
G01X613366Y121982D02*
X613367Y121991D01*
G01X613366Y126982D02*
X613367Y126991D01*
G01X613366Y131982D02*
X613367Y131991D01*
G01X613366Y136982D02*
X613367Y136991D01*
G01X613366Y141982D02*
X613367Y141991D01*
G01X613366Y146982D02*
X613367Y146991D01*
G01X613366Y151982D02*
X613367Y151991D01*
G01X613366Y156982D02*
X613367Y156991D01*
G01X613366Y161982D02*
X613367Y161991D01*
G01X613366Y166982D02*
X613367Y166991D01*
G01X613366Y171982D02*
X613367Y171991D01*
G01X613366Y176982D02*
X613367Y176991D01*
G01X618701Y186161D02*
Y201909D01*
G01X617717Y175630D02*
Y177008D01*
G01Y170630D02*
Y172008D01*
G01Y165630D02*
Y167008D01*
G01Y160630D02*
Y162008D01*
G01Y155630D02*
Y157008D01*
G01Y150630D02*
Y152008D01*
G01Y145630D02*
Y147008D01*
G01Y140630D02*
Y142008D01*
G01Y135630D02*
Y137008D01*
G01Y130630D02*
Y132008D01*
G01Y125630D02*
Y127008D01*
G01Y120630D02*
Y122008D01*
G01Y115630D02*
Y117008D01*
G01Y110630D02*
Y112008D01*
G01Y105630D02*
Y107008D01*
G01X614547D02*
Y105630D01*
G01Y112008D02*
Y110630D01*
G01Y117008D02*
Y115630D01*
G01Y122008D02*
Y120630D01*
G01Y127008D02*
Y125630D01*
G01Y132008D02*
Y130630D01*
G01Y137008D02*
Y135630D01*
G01Y142008D02*
Y140630D01*
G01Y147008D02*
Y145630D01*
G01Y152008D02*
Y150630D01*
G01Y157008D02*
Y155630D01*
G01Y162008D02*
Y160630D01*
G01Y167008D02*
Y165630D01*
G01Y172008D02*
Y170630D01*
G01Y177008D02*
Y175630D01*
G01X613366Y106982D02*
Y107125D01*
G01Y111982D02*
Y112125D01*
G01Y116982D02*
Y117125D01*
G01Y121982D02*
Y122125D01*
G01Y126982D02*
Y127125D01*
G01Y131982D02*
Y132125D01*
G01Y136982D02*
Y137125D01*
G01Y141982D02*
Y142125D01*
G01Y146982D02*
Y147125D01*
G01Y151982D02*
Y152125D01*
G01Y156982D02*
Y157125D01*
G01Y161982D02*
Y162125D01*
G01Y166982D02*
Y167125D01*
G01Y171982D02*
Y172125D01*
G01Y176982D02*
Y177125D01*
G01Y175138D02*
Y177500D01*
G01Y170138D02*
Y172500D01*
G01Y165138D02*
Y167500D01*
G01Y160138D02*
Y162500D01*
G01Y155138D02*
Y157500D01*
G01Y150138D02*
Y152500D01*
G01Y145138D02*
Y147500D01*
G01Y140138D02*
Y142500D01*
G01Y135138D02*
Y137500D01*
G01Y130138D02*
Y132500D01*
G01Y125138D02*
Y127500D01*
G01Y120138D02*
Y122500D01*
G01Y115138D02*
Y117500D01*
G01Y110138D02*
Y112500D01*
G01Y105138D02*
Y107500D01*
G01X612382D02*
Y105138D01*
G01Y112500D02*
Y110138D01*
G01Y117500D02*
Y115138D01*
G01Y122500D02*
Y120138D01*
G01Y127500D02*
Y125138D01*
G01Y132500D02*
Y130138D01*
G01Y137500D02*
Y135138D01*
G01Y142500D02*
Y140138D01*
G01Y147500D02*
Y145138D01*
G01Y152500D02*
Y150138D01*
G01Y157500D02*
Y155138D01*
G01Y162500D02*
Y160138D01*
G01Y167500D02*
Y165138D01*
G01Y172500D02*
Y170138D01*
G01Y177500D02*
Y175138D01*
G01X611614Y192224D02*
Y183681D01*
G01X610039Y181319D02*
Y104862D01*
G01X609055Y188720D02*
Y187028D01*
G01X608858Y180138D02*
Y103681D01*
G01X606693Y187028D02*
Y188720D01*
G01X604134Y183681D02*
Y192224D01*
G01X600394Y185059D02*
Y106024D01*
G01X599941Y102519D02*
Y104016D01*
G01Y99370D02*
Y100866D01*
G01Y96220D02*
Y97717D01*
G01X599902Y96367D02*
Y96220D01*
G01Y94567D02*
Y94420D01*
G01Y99516D02*
Y99369D01*
G01Y100867D02*
Y100720D01*
G01Y97717D02*
Y97570D01*
G01Y102666D02*
Y102519D01*
G01Y104016D02*
Y103869D01*
G01X598996Y102519D02*
Y102666D01*
G01Y103869D02*
Y104016D01*
G01Y99369D02*
Y99516D01*
G01Y100720D02*
Y100867D01*
G01Y97570D02*
Y97717D01*
G01Y96220D02*
Y96367D01*
G01Y94420D02*
Y94567D01*
G01X598957Y100866D02*
Y99370D01*
G01Y97717D02*
Y96220D01*
G01Y104016D02*
Y102520D01*
G01X597776Y97559D02*
Y96378D01*
G01Y100709D02*
Y99528D01*
G01Y103858D02*
Y102677D01*
G01X597047Y201909D02*
Y186161D01*
G01X594016Y102677D02*
Y103858D01*
G01Y99528D02*
Y100709D01*
G01Y96378D02*
Y97559D01*
G01X599941Y102703D02*
Y102714D01*
G01Y99554D02*
Y99564D01*
G01Y96404D02*
Y96415D01*
G01X599900Y99528D02*
X599904Y99516D01*
G01X606693Y188720D02*
X604383Y192950D01*
G01X609055Y187028D02*
X610359Y185059D01*
G01X606693Y187028D02*
X609055D01*
G01X600394Y185059D02*
X614764D01*
G01X600394Y183681D02*
X604134D01*
G01X614764D02*
X611614D01*
G01X600394Y182815D02*
X615354D01*
G01X602165Y181319D02*
X610039D01*
G01X603346Y180138D02*
X608858D01*
G01X613366Y177500D02*
X612382D01*
G01X612383Y177008D02*
X617717D01*
G01Y176969D02*
X613369D01*
G01X617717Y175630D02*
X612383D01*
G01X612382Y175138D02*
X613366D01*
G01Y172500D02*
X612382D01*
G01X612383Y172008D02*
X617717D01*
G01Y171969D02*
X613369D01*
G01X617717Y170630D02*
X612383D01*
G01X612382Y170138D02*
X613366D01*
G01Y167500D02*
X612382D01*
G01X612383Y167008D02*
X617717D01*
G01Y166969D02*
X613369D01*
G01X617717Y165630D02*
X612383D01*
G01X612382Y165138D02*
X613366D01*
G01Y162500D02*
X612382D01*
G01X612383Y162008D02*
X617717D01*
G01Y161969D02*
X613369D01*
G01X617717Y160630D02*
X612383D01*
G01X612382Y160138D02*
X613366D01*
G01Y157500D02*
X612382D01*
G01X612383Y157008D02*
X617717D01*
G01Y156969D02*
X613369D01*
G01X617717Y155630D02*
X612383D01*
G01X612382Y155138D02*
X613366D01*
G01Y152500D02*
X612382D01*
G01X612383Y152008D02*
X617717D01*
G01Y151969D02*
X613369D01*
G01X617717Y150630D02*
X612383D01*
G01X612382Y150138D02*
X613366D01*
G01Y147500D02*
X612382D01*
G01X612383Y147008D02*
X617717D01*
G01Y146969D02*
X613369D01*
G01X617717Y145630D02*
X612383D01*
G01X612382Y145138D02*
X613366D01*
G01Y142500D02*
X612382D01*
G01X612383Y142008D02*
X617717D01*
G01Y141969D02*
X613369D01*
G01X617717Y140630D02*
X612383D01*
G01X612382Y140138D02*
X613366D01*
G01Y137500D02*
X612382D01*
G01X612383Y137008D02*
X617717D01*
G01Y136969D02*
X613369D01*
G01X617717Y135630D02*
X612383D01*
G01X612382Y135138D02*
X613366D01*
G01Y132500D02*
X612382D01*
G01X612383Y132008D02*
X617717D01*
G01Y131969D02*
X613369D01*
G01X617717Y130630D02*
X612383D01*
G01X612382Y130138D02*
X613366D01*
G01Y127500D02*
X612382D01*
G01X612383Y127008D02*
X617717D01*
G01Y126969D02*
X613369D01*
G01X617717Y125630D02*
X612383D01*
G01X612382Y125138D02*
X613366D01*
G01Y122500D02*
X612382D01*
G01X612383Y122008D02*
X617717D01*
G01Y121969D02*
X613369D01*
G01X617717Y120630D02*
X612383D01*
G01X612382Y120138D02*
X613366D01*
G01Y117500D02*
X612382D01*
G01Y177204D02*
X613337Y177205D01*
G01X613366Y175434D02*
X612382Y175433D01*
G01Y172204D02*
X613337Y172205D01*
G01X613366Y170434D02*
X612382Y170433D01*
G01Y167204D02*
X613337Y167205D01*
G01X613366Y165434D02*
X612382Y165433D01*
G01Y162204D02*
X613337Y162205D01*
G01X613366Y160434D02*
X612382Y160433D01*
G01Y157204D02*
X613337Y157205D01*
G01X613366Y155434D02*
X612382Y155433D01*
G01Y152204D02*
X613337Y152205D01*
G01X613366Y150434D02*
X612382Y150433D01*
G01Y147204D02*
X613337Y147205D01*
G01X613366Y145434D02*
X612382Y145433D01*
G01Y142204D02*
X613337Y142205D01*
G01X613366Y140434D02*
X612382Y140433D01*
G01Y137204D02*
X613337Y137205D01*
G01X613366Y135434D02*
X612382Y135433D01*
G01Y132204D02*
X613337Y132205D01*
G01X613366Y130434D02*
X612382Y130433D01*
G01Y127204D02*
X613337Y127205D01*
G01X613366Y125434D02*
X612382Y125433D01*
G01Y122204D02*
X613337Y122205D01*
G01X613366Y120434D02*
X612382Y120433D01*
G01Y117204D02*
X613337Y117205D01*
G01X602165Y181319D02*
X603346Y180138D01*
G01X597047Y186161D02*
X600394Y182815D01*
G01X598843Y102717D02*
X598955Y102708D01*
G01X598954Y96414D02*
X598843Y96417D01*
G01X612383Y117008D02*
X617717D01*
G01Y116969D02*
X613369D01*
G01X617717Y115630D02*
X612383D01*
G01X612382Y115138D02*
X613366D01*
G01Y112500D02*
X612382D01*
G01X612383Y112008D02*
X617717D01*
G01Y111969D02*
X613369D01*
G01X617717Y110630D02*
X612383D01*
G01X612382Y110138D02*
X613366D01*
G01Y107500D02*
X612382D01*
G01X612383Y107008D02*
X617717D01*
G01Y106969D02*
X613369D01*
G01X600394Y106024D02*
X597047D01*
G01X617717Y105630D02*
X612383D01*
G01X612382Y105138D02*
X613366D01*
G01X610039Y104862D02*
X613976D01*
G01X599902Y104055D02*
X598996D01*
G01X599941Y104016D02*
X598957D01*
G01X599900Y103858D02*
X594016D01*
G01Y103819D02*
X599940D01*
G01X608858Y103681D02*
X612795D01*
G01X599939Y102717D02*
X594016D01*
G01X599900Y102677D02*
X594016D01*
G01X598957Y102520D02*
X599941D01*
G01X598996Y102480D02*
X599902D01*
G01Y100906D02*
X598996D01*
G01X599941Y100866D02*
X598957D01*
G01X599900Y100709D02*
X594016D01*
G01Y100669D02*
X599940D01*
G01X599939Y99567D02*
X594016D01*
G01X599900Y99528D02*
X594016D01*
G01X598957Y99370D02*
X599941D01*
G01X598996Y99331D02*
X599902D01*
G01Y97756D02*
X598996D01*
G01X599941Y97717D02*
X598957D01*
G01X599900Y97559D02*
X594016D01*
G01Y97520D02*
X599940D01*
G01X599939Y96417D02*
X594016D01*
G01X599900Y96378D02*
X594016D01*
G01X598957Y96220D02*
X599941D01*
G01X598996Y96181D02*
X599902D01*
G01Y94606D02*
X598996D01*
G01X599941Y94567D02*
X598957D01*
G01X599900Y94409D02*
X594016D01*
G01Y94370D02*
X599940D01*
G01X613366Y115434D02*
X612382Y115433D01*
G01Y112204D02*
X613337Y112205D01*
G01X613366Y110434D02*
X612382Y110433D01*
G01Y107204D02*
X613337Y107205D01*
G01X613366Y105434D02*
X612382Y105433D01*
G01X610358Y264712D02*
G03X644169I16906J-13531D01*
G01X637244Y277843D02*
G03X644169Y264712I37662J11471D01*
G01X637244Y277843D02*
G03X617283I-9980J-3040D01*
G01X610358Y264712D02*
G03X617283Y277843I-30737J24602D01*
G01X637244D02*
G03X617283I-9980J-3040D01*
G01X610358Y264712D02*
G03X644169I16906J-13531D01*
G01X637244Y277843D02*
G03X644169Y264712I37662J11471D01*
G01X611811Y202500D02*
G03X611220Y203091I-591J0D01*
G01X604528D02*
G03X603937Y202500I0J-591D01*
G01X606693Y201319D02*
G03Y199350I0J-985D01*
G01X609055D02*
G03Y201319I0J984D01*
G01X605315Y193406D02*
G03X604134Y192224I0J-1181D01*
G01X611614D02*
G03X610433Y193406I-1181J1D01*
G01X618701Y201909D02*
G03X616732Y203878I-1969J0D01*
G01X599016D02*
G03X597047Y201909I0J-1969D01*
G01X610358Y264712D02*
G03X617283Y277843I-30737J24601D01*
G01X611811Y196398D02*
Y202500D01*
G01X603937Y196398D02*
Y202500D01*
G01X616732Y203878D02*
X599016D01*
G01X611220Y203091D02*
X604528D01*
G01X609055Y201319D02*
X606693D01*
G01Y199350D02*
X609055D01*
G01X611811Y197972D02*
X603937D01*
G01Y196398D02*
X611811D01*
G01X618701Y193445D02*
X597047D01*
G01X605315Y193406D02*
X610433D01*
G01X606693Y188720D02*
X609055D01*
G01X598996Y536530D02*
Y536524D01*
G01X598995Y536534D02*
X598996Y536530D01*
G01X598994Y536535D02*
X598995Y536534D01*
G01X598996Y539680D02*
Y539674D01*
G01X598995Y539684D02*
X598996Y539680D01*
G01X598994Y539685D02*
X598995Y539684D01*
G01X598996Y542830D02*
Y542823D01*
G01X598995Y542833D02*
X598996Y542830D01*
G01X598994Y542835D02*
X598995Y542833D01*
G01X598996Y545979D02*
Y545973D01*
G01X598995Y545983D02*
X598996Y545979D01*
G01X598994Y545984D02*
X598995Y545983D01*
G01X598996Y549129D02*
Y549122D01*
G01X598995Y549133D02*
X598996Y549129D01*
G01X598994Y549134D02*
X598995Y549133D01*
G01X598996Y552278D02*
Y552272D01*
G01X598995Y552282D02*
X598996Y552278D01*
G01X598994Y552283D02*
X598995Y552282D01*
G01X613367Y504731D02*
X613366Y504738D01*
G01X613367Y504726D02*
Y504731D01*
G01X613369Y504724D02*
X613367Y504726D01*
G01Y509731D02*
X613366Y509738D01*
G01X613367Y509726D02*
Y509731D01*
G01X613369Y509724D02*
X613367Y509726D01*
G01Y514731D02*
X613366Y514738D01*
G01X613367Y514726D02*
Y514731D01*
G01X613369Y514724D02*
X613367Y514726D01*
G01Y519731D02*
X613366Y519738D01*
G01X613367Y519726D02*
Y519731D01*
G01X613369Y519724D02*
X613367Y519726D01*
G01Y524731D02*
X613366Y524738D01*
G01X613367Y524726D02*
Y524731D01*
G01X613369Y524724D02*
X613367Y524726D01*
G01Y529731D02*
X613366Y529738D01*
G01X613367Y529726D02*
Y529731D01*
G01X613369Y529724D02*
X613367Y529726D01*
G01Y534731D02*
X613366Y534738D01*
G01X613367Y534726D02*
Y534731D01*
G01X613369Y534724D02*
X613367Y534726D01*
G01Y559731D02*
X613366Y559738D01*
G01X613367Y559726D02*
Y559731D01*
G01X613369Y559724D02*
X613367Y559726D01*
G01Y564731D02*
X613366Y564738D01*
G01X613367Y564726D02*
Y564731D01*
G01X613369Y564724D02*
X613367Y564726D01*
G01X598980Y539687D02*
X598994Y539685D01*
G01X598968Y539694D02*
X598980Y539687D01*
G01X598956Y539713D02*
X598968Y539694D01*
G01X598980Y549136D02*
X598994Y549134D01*
G01X598968Y549144D02*
X598980Y549136D01*
G01X598956Y549162D02*
X598968Y549144D01*
G01X598979Y542837D02*
X598994Y542835D01*
G01X598967Y542845D02*
X598979Y542837D01*
G01X598955Y542865D02*
X598967Y542845D01*
G01X598979Y552286D02*
X598994Y552283D01*
G01X598967Y552294D02*
X598979Y552286D01*
G01X598955Y552314D02*
X598967Y552294D01*
G01X599941Y536569D02*
Y536561D01*
G01X599940Y536573D02*
X599941Y536569D01*
G01X599939Y536575D02*
X599940Y536573D01*
G01X599941Y539719D02*
Y539711D01*
G01X599940Y539723D02*
X599941Y539719D01*
G01X599939Y539724D02*
X599940Y539723D01*
G01X599941Y542868D02*
Y542860D01*
G01X599940Y542872D02*
X599941Y542868D01*
G01X599939Y542874D02*
X599940Y542872D01*
G01X599941Y546018D02*
Y546010D01*
G01X599940Y546022D02*
X599941Y546018D01*
G01X599939Y546024D02*
X599940Y546022D01*
G01X599941Y549167D02*
Y549159D01*
G01X599940Y549172D02*
X599941Y549167D01*
G01X599939Y549173D02*
X599940Y549172D01*
G01X599941Y552317D02*
Y552309D01*
G01X599940Y552321D02*
X599941Y552317D01*
G01X599939Y552323D02*
X599940Y552321D01*
G01X599941Y555467D02*
Y555459D01*
G01X599940Y555471D02*
X599941Y555467D01*
G01X599939Y555472D02*
X599940Y555471D01*
G01X598979Y555436D02*
X598994Y555433D01*
G01X598967Y555444D02*
X598979Y555436D01*
G01X598955Y555464D02*
X598967Y555444D01*
G01X598979Y536538D02*
X598994Y536535D01*
G01X598966Y536547D02*
X598979Y536538D01*
G01X598955Y536567D02*
X598966Y536547D01*
G01X599940Y537697D02*
X599941Y537691D01*
G01X599939Y537704D02*
X599940Y537697D01*
G01X599935Y537709D02*
X599939Y537704D01*
G01X599940Y540847D02*
X599941Y540840D01*
G01X599939Y540853D02*
X599940Y540847D01*
G01X599935Y540859D02*
X599939Y540853D01*
G01X599940Y543996D02*
X599941Y543990D01*
G01X599939Y544003D02*
X599940Y543996D01*
G01X599935Y544009D02*
X599939Y544003D01*
G01X599940Y547146D02*
X599941Y547139D01*
G01X599939Y547152D02*
X599940Y547146D01*
G01X599935Y547158D02*
X599939Y547152D01*
G01X599940Y550296D02*
X599941Y550289D01*
G01X599939Y550302D02*
X599940Y550296D01*
G01X599935Y550308D02*
X599939Y550302D01*
G01X599940Y553445D02*
X599941Y553439D01*
G01X599939Y553452D02*
X599940Y553445D01*
G01X599935Y553457D02*
X599939Y553452D01*
G01X599940Y556595D02*
X599941Y556588D01*
G01X599939Y556601D02*
X599940Y556595D01*
G01X599935Y556607D02*
X599939Y556601D01*
G01X599902Y536530D02*
Y536524D01*
G01X599901Y536534D02*
X599902Y536530D01*
G01X599900Y536535D02*
X599901Y536534D01*
G01X599902Y539680D02*
Y539674D01*
G01X599901Y539683D02*
X599902Y539680D01*
G01X599900Y539685D02*
X599901Y539683D01*
G01X599902Y542830D02*
Y542823D01*
G01X599901Y542833D02*
X599902Y542830D01*
G01X599900Y542835D02*
X599901Y542833D01*
G01X599902Y545979D02*
Y545973D01*
G01X599901Y545983D02*
X599902Y545979D01*
G01X599900Y545984D02*
X599901Y545983D01*
G01X599902Y549129D02*
Y549122D01*
G01X599901Y549132D02*
X599902Y549129D01*
G01X599900Y549134D02*
X599901Y549132D01*
G01X599902Y555428D02*
Y555422D01*
G01X599901Y555431D02*
X599902Y555428D01*
G01X599900Y555433D02*
X599901Y555431D01*
G01X612382Y504771D02*
Y504780D01*
G01X612383Y504765D02*
X612382Y504771D01*
G01X612383Y504764D02*
Y504765D01*
G01X612382Y509771D02*
Y509780D01*
G01X612383Y509765D02*
X612382Y509771D01*
G01X612383Y509764D02*
Y509765D01*
G01X612382Y514771D02*
Y514780D01*
G01X612383Y514765D02*
X612382Y514771D01*
G01X612383Y514764D02*
Y514765D01*
G01X612382Y519771D02*
Y519780D01*
G01X612383Y519765D02*
X612382Y519771D01*
G01X612383Y519764D02*
Y519765D01*
G01X612382Y524771D02*
Y524780D01*
G01X612383Y524765D02*
X612382Y524771D01*
G01X612383Y524764D02*
Y524765D01*
G01X612382Y529771D02*
Y529780D01*
G01X612383Y529765D02*
X612382Y529771D01*
G01X612383Y529764D02*
Y529765D01*
G01X612382Y534771D02*
Y534780D01*
G01X612383Y534765D02*
X612382Y534771D01*
G01X612383Y534764D02*
Y534765D01*
G01X612382Y559771D02*
Y559780D01*
G01X612383Y559765D02*
X612382Y559771D01*
G01X612383Y559764D02*
Y559765D01*
G01X612382Y564771D02*
Y564780D01*
G01X612383Y564765D02*
X612382Y564771D01*
G01X612383Y564764D02*
Y564765D01*
G01X612382Y569771D02*
Y569780D01*
G01X612383Y569765D02*
X612382Y569771D01*
G01X612383Y569764D02*
Y569765D01*
G01X613358Y504907D02*
X613366Y504881D01*
G01X613348Y504934D02*
X613358Y504907D01*
G01X613337Y504961D02*
X613348Y504934D01*
G01X613358Y509907D02*
X613366Y509881D01*
G01X613348Y509934D02*
X613358Y509907D01*
G01X613337Y509961D02*
X613348Y509934D01*
G01X613358Y514907D02*
X613366Y514881D01*
G01X613348Y514934D02*
X613358Y514907D01*
G01X613337Y514961D02*
X613348Y514934D01*
G01X613358Y519907D02*
X613366Y519881D01*
G01X613348Y519934D02*
X613358Y519907D01*
G01X613337Y519961D02*
X613348Y519934D01*
G01X613358Y524907D02*
X613366Y524881D01*
G01X613348Y524934D02*
X613358Y524907D01*
G01X613337Y524961D02*
X613348Y524934D01*
G01X613358Y529907D02*
X613366Y529881D01*
G01X613348Y529934D02*
X613358Y529907D01*
G01X613337Y529961D02*
X613348Y529934D01*
G01X613358Y534907D02*
X613366Y534881D01*
G01X613348Y534934D02*
X613358Y534907D01*
G01X613337Y534961D02*
X613348Y534934D01*
G01X613358Y559907D02*
X613366Y559881D01*
G01X613348Y559934D02*
X613358Y559907D01*
G01X613337Y559961D02*
X613348Y559934D01*
G01X613358Y564907D02*
X613366Y564881D01*
G01X613348Y564934D02*
X613358Y564907D01*
G01X613337Y564961D02*
X613348Y564934D01*
G01X613358Y569907D02*
X613366Y569881D01*
G01X613348Y569934D02*
X613358Y569907D01*
G01X613337Y569961D02*
X613348Y569934D01*
G01X598974Y545989D02*
X598994Y545984D01*
G01X598961Y546002D02*
X598974Y545989D01*
G01X598954Y546019D02*
X598961Y546002D01*
G01X613349Y504759D02*
X613330Y504764D01*
G01X613363Y504744D02*
X613349Y504759D01*
G01X613369Y504724D02*
X613363Y504744D01*
G01X613349Y509759D02*
X613330Y509764D01*
G01X613363Y509744D02*
X613349Y509759D01*
G01X613369Y509724D02*
X613363Y509744D01*
G01X613349Y514759D02*
X613330Y514764D01*
G01X613363Y514744D02*
X613349Y514759D01*
G01X613369Y514724D02*
X613363Y514744D01*
G01X613349Y519759D02*
X613330Y519764D01*
G01X613363Y519744D02*
X613349Y519759D01*
G01X613369Y519724D02*
X613363Y519744D01*
G01X613349Y524759D02*
X613330Y524764D01*
G01X613363Y524744D02*
X613349Y524759D01*
G01X613369Y524724D02*
X613363Y524744D01*
G01X613349Y529759D02*
X613330Y529764D01*
G01X613363Y529744D02*
X613349Y529759D01*
G01X613369Y529724D02*
X613363Y529744D01*
G01X613349Y534759D02*
X613330Y534764D01*
G01X613363Y534744D02*
X613349Y534759D01*
G01X613369Y534724D02*
X613363Y534744D01*
G01X613333Y504862D02*
X613337Y504961D01*
G01X613328Y504790D02*
X613333Y504862D01*
G01X613330Y504764D02*
X613328Y504790D01*
G01X613333Y509862D02*
X613337Y509961D01*
G01X613328Y509790D02*
X613333Y509862D01*
G01X613330Y509764D02*
X613328Y509790D01*
G01X613333Y514862D02*
X613337Y514961D01*
G01X613328Y514790D02*
X613333Y514862D01*
G01X613330Y514764D02*
X613328Y514790D01*
G01X613333Y519862D02*
X613337Y519961D01*
G01X613328Y519790D02*
X613333Y519862D01*
G01X613330Y519764D02*
X613328Y519790D01*
G01X613333Y524862D02*
X613337Y524961D01*
G01X613328Y524790D02*
X613333Y524862D01*
G01X613330Y524764D02*
X613328Y524790D01*
G01X613333Y529862D02*
X613337Y529961D01*
G01X613328Y529790D02*
X613333Y529862D01*
G01X613330Y529764D02*
X613328Y529790D01*
G01X613333Y534862D02*
X613337Y534961D01*
G01X613328Y534790D02*
X613333Y534862D01*
G01X613330Y534764D02*
X613328Y534790D01*
G01X613333Y559862D02*
X613337Y559961D01*
G01X613328Y559790D02*
X613333Y559862D01*
G01X613330Y559764D02*
X613328Y559790D01*
G01X613333Y564862D02*
X613337Y564961D01*
G01X613328Y564790D02*
X613333Y564862D01*
G01X613330Y564764D02*
X613328Y564790D01*
G01X613333Y569862D02*
X613337Y569961D01*
G01X613328Y569790D02*
X613333Y569862D01*
G01X613330Y569764D02*
X613328Y569790D01*
G01X598956Y549167D02*
X598957Y549160D01*
G01X598956Y549172D02*
Y549167D01*
G01Y549162D02*
Y549172D01*
G01X598997Y556798D02*
X598996Y556811D01*
G01X598994Y556785D02*
X598997Y556798D01*
G01X598994Y556772D02*
Y556785D01*
G01X598997Y553649D02*
X598996Y553661D01*
G01X598994Y553636D02*
X598997Y553649D01*
G01X598994Y553622D02*
Y553636D01*
G01X598997Y550499D02*
X598996Y550512D01*
G01X598994Y550486D02*
X598997Y550499D01*
G01X598994Y550472D02*
Y550486D01*
G01X598997Y547350D02*
X598996Y547362D01*
G01X598994Y547337D02*
X598997Y547350D01*
G01X598994Y547323D02*
Y547337D01*
G01X598997Y544200D02*
X598996Y544213D01*
G01X598994Y544187D02*
X598997Y544200D01*
G01X598994Y544173D02*
Y544187D01*
G01X598997Y541050D02*
X598996Y541063D01*
G01X598994Y541037D02*
X598997Y541050D01*
G01X598994Y541024D02*
Y541037D01*
G01X598997Y537901D02*
X598996Y537913D01*
G01X598994Y537888D02*
X598997Y537901D01*
G01X598994Y537874D02*
Y537888D01*
G01X612383Y568384D02*
Y568386D01*
G01X612382Y568378D02*
X612383Y568384D01*
G01X612382Y568370D02*
Y568378D01*
G01X612383Y563384D02*
Y563386D01*
G01X612382Y563378D02*
X612383Y563384D01*
G01X612382Y563370D02*
Y563378D01*
G01X612383Y558384D02*
Y558386D01*
G01X612382Y558378D02*
X612383Y558384D01*
G01X612382Y558370D02*
Y558378D01*
G01X612383Y533384D02*
Y533386D01*
G01X612382Y533378D02*
X612383Y533384D01*
G01X612382Y533370D02*
Y533378D01*
G01X612383Y528384D02*
Y528386D01*
G01X612382Y528378D02*
X612383Y528384D01*
G01X612382Y528370D02*
Y528378D01*
G01X612383Y523384D02*
Y523386D01*
G01X612382Y523378D02*
X612383Y523384D01*
G01X612382Y523370D02*
Y523378D01*
G01X612383Y518384D02*
Y518386D01*
G01X612382Y518378D02*
X612383Y518384D01*
G01X612382Y518370D02*
Y518378D01*
G01X612383Y513384D02*
Y513386D01*
G01X612382Y513378D02*
X612383Y513384D01*
G01X612382Y513370D02*
Y513378D01*
G01X612383Y508384D02*
Y508386D01*
G01X612382Y508378D02*
X612383Y508384D01*
G01X612382Y508370D02*
Y508378D01*
G01X612383Y503384D02*
Y503386D01*
G01X612382Y503378D02*
X612383Y503384D01*
G01X612382Y503370D02*
Y503378D01*
G01X598956Y555467D02*
X598957Y555459D01*
G01X598956Y555471D02*
Y555467D01*
G01Y555463D02*
Y555471D01*
G01X598994Y555261D02*
X598993Y555275D01*
G01X598997Y555249D02*
X598994Y555261D01*
G01X598996Y555236D02*
X598997Y555249D01*
G01X598994Y552112D02*
X598993Y552126D01*
G01X598997Y552099D02*
X598994Y552112D01*
G01X598996Y552087D02*
X598997Y552099D01*
G01X598994Y548962D02*
X598993Y548976D01*
G01X598997Y548950D02*
X598994Y548962D01*
G01X598996Y548937D02*
X598997Y548950D01*
G01X598994Y545813D02*
X598993Y545826D01*
G01X598997Y545800D02*
X598994Y545813D01*
G01X598996Y545787D02*
X598997Y545800D01*
G01X598994Y542663D02*
X598993Y542677D01*
G01X598997Y542650D02*
X598994Y542663D01*
G01X598996Y542638D02*
X598997Y542650D01*
G01X598994Y539513D02*
X598993Y539527D01*
G01X598997Y539501D02*
X598994Y539513D01*
G01X598996Y539488D02*
X598997Y539501D01*
G01X598994Y536364D02*
X598993Y536378D01*
G01X598997Y536351D02*
X598994Y536364D01*
G01X598996Y536339D02*
X598997Y536351D01*
G01X599904Y556785D02*
X599905Y556772D01*
G01X599901Y556798D02*
X599904Y556785D01*
G01X599902Y556811D02*
X599901Y556798D01*
G01X599904Y553636D02*
X599905Y553622D01*
G01X599901Y553649D02*
X599904Y553636D01*
G01X599902Y553661D02*
X599901Y553649D01*
G01X599904Y550486D02*
X599905Y550472D01*
G01X599901Y550499D02*
X599904Y550486D01*
G01X599902Y550512D02*
X599901Y550499D01*
G01X599904Y547337D02*
X599905Y547323D01*
G01X599901Y547350D02*
X599904Y547337D01*
G01X599902Y547362D02*
X599901Y547350D01*
G01X599904Y544187D02*
X599905Y544173D01*
G01X599901Y544200D02*
X599904Y544187D01*
G01X599902Y544213D02*
X599901Y544200D01*
G01X599904Y541037D02*
X599905Y541024D01*
G01X599901Y541050D02*
X599904Y541037D01*
G01X599902Y541063D02*
X599901Y541050D01*
G01X599904Y537888D02*
X599905Y537874D01*
G01X599901Y537901D02*
X599904Y537888D01*
G01X599902Y537913D02*
X599901Y537901D01*
G01X598956Y542868D02*
X598957Y542861D01*
G01X598956Y542872D02*
Y542868D01*
G01X598955Y542865D02*
X598956Y542872D01*
G01Y552317D02*
X598957Y552309D01*
G01X598956Y552321D02*
Y552317D01*
G01X598955Y552314D02*
X598956Y552321D01*
G01X599901Y555249D02*
X599902Y555236D01*
G01X599904Y555261D02*
X599901Y555249D01*
G01X599905Y555275D02*
X599904Y555261D01*
G01X599901Y552099D02*
X599902Y552087D01*
G01X599904Y552112D02*
X599901Y552099D01*
G01X599905Y552126D02*
X599904Y552112D01*
G01X599901Y548950D02*
X599902Y548937D01*
G01X599904Y548962D02*
X599901Y548950D01*
G01X599905Y548976D02*
X599904Y548962D01*
G01X599901Y545800D02*
X599902Y545787D01*
G01X599904Y545813D02*
X599901Y545800D01*
G01X599905Y545826D02*
X599904Y545813D01*
G01X599901Y542650D02*
X599902Y542638D01*
G01X599904Y542663D02*
X599901Y542650D01*
G01X599905Y542677D02*
X599904Y542663D01*
G01X599901Y539501D02*
X599902Y539488D01*
G01X599904Y539513D02*
X599901Y539501D01*
G01X599905Y539527D02*
X599904Y539513D01*
G01X599901Y536351D02*
X599902Y536339D01*
G01X599904Y536364D02*
X599901Y536351D01*
G01X599905Y536378D02*
X599904Y536364D01*
G01X598956Y536569D02*
X598957Y536561D01*
G01X598956Y536573D02*
Y536569D01*
G01X598955Y536567D02*
X598956Y536573D01*
G01X598957Y539715D02*
Y539711D01*
G01X598958Y539708D02*
X598957Y539715D01*
G01X598970Y539693D02*
X598958Y539708D01*
G01X598995Y539685D02*
X598970Y539693D01*
G01X598957Y542864D02*
Y542860D01*
G01X598958Y542858D02*
X598957Y542864D01*
G01X598970Y542843D02*
X598958Y542858D01*
G01X598994Y542835D02*
X598970Y542843D01*
G01X598957Y549163D02*
Y549159D01*
G01X598958Y549157D02*
X598957Y549163D01*
G01X598970Y549142D02*
X598958Y549157D01*
G01X598994Y549134D02*
X598970Y549142D01*
G01X598957Y536565D02*
Y536561D01*
G01X598958Y536559D02*
X598957Y536565D01*
G01X598970Y536544D02*
X598958Y536559D01*
G01X598994Y536535D02*
X598970Y536544D01*
G01X613354Y504755D02*
X613365Y504740D01*
G01X613329Y504764D02*
X613354Y504755D01*
G01Y509755D02*
X613365Y509740D01*
G01X613329Y509764D02*
X613354Y509755D01*
G01Y514755D02*
X613365Y514740D01*
G01X613329Y514764D02*
X613354Y514755D01*
G01Y519755D02*
X613365Y519740D01*
G01X613329Y519764D02*
X613354Y519755D01*
G01Y524755D02*
X613365Y524740D01*
G01X613329Y524764D02*
X613354Y524755D01*
G01Y529755D02*
X613365Y529740D01*
G01X613329Y529764D02*
X613354Y529755D01*
G01Y534755D02*
X613365Y534740D01*
G01X613329Y534764D02*
X613354Y534755D01*
G01X598957Y546014D02*
Y546010D01*
G01X598958Y546008D02*
X598957Y546014D01*
G01X598969Y545994D02*
X598958Y546008D01*
G01X598991Y545984D02*
X598969Y545994D01*
G01X599909Y544015D02*
X599900Y544016D01*
G01X599918Y544011D02*
X599909Y544015D01*
G01X599926Y544006D02*
X599918Y544011D01*
G01X599909Y537715D02*
X599900Y537717D01*
G01X599919Y537712D02*
X599909Y537715D01*
G01X599926Y537707D02*
X599919Y537712D01*
G01X599909Y540865D02*
X599900Y540866D01*
G01X599919Y540862D02*
X599909Y540865D01*
G01X599926Y540856D02*
X599919Y540862D01*
G01X599909Y547164D02*
X599900Y547165D01*
G01X599919Y547161D02*
X599909Y547164D01*
G01X599926Y547156D02*
X599919Y547161D01*
G01X599909Y550314D02*
X599900Y550315D01*
G01X599919Y550311D02*
X599909Y550314D01*
G01X599926Y550305D02*
X599919Y550311D01*
G01X599909Y553463D02*
X599900Y553465D01*
G01X599919Y553460D02*
X599909Y553463D01*
G01X599926Y553455D02*
X599919Y553460D01*
G01X599909Y556613D02*
X599900Y556614D01*
G01X599919Y556610D02*
X599909Y556613D01*
G01X599926Y556604D02*
X599919Y556610D01*
G01X598996Y555428D02*
Y555422D01*
G01X598995Y555432D02*
X598996Y555428D01*
G01X598994Y555433D02*
X598995Y555432D01*
G01X613367Y569731D02*
X613366Y569738D01*
G01X613367Y569726D02*
Y569731D01*
G01X613369Y569724D02*
X613367Y569726D01*
G01X613349Y559759D02*
X613330Y559764D01*
G01X613363Y559744D02*
X613349Y559759D01*
G01X613369Y559724D02*
X613363Y559744D01*
G01X613349Y564759D02*
X613330Y564764D01*
G01X613363Y564744D02*
X613349Y564759D01*
G01X613369Y564724D02*
X613363Y564744D01*
G01X613349Y569759D02*
X613330Y569764D01*
G01X613363Y569744D02*
X613349Y569759D01*
G01X613369Y569724D02*
X613363Y569744D01*
G01X599933Y543998D02*
X599926Y544006D01*
G01X599938Y543987D02*
X599933Y543998D01*
G01X599940Y543976D02*
X599938Y543987D01*
G01X599933Y537698D02*
X599926Y537707D01*
G01X599938Y537688D02*
X599933Y537698D01*
G01X599940Y537677D02*
X599938Y537688D01*
G01X599933Y540848D02*
X599926Y540856D01*
G01X599938Y540838D02*
X599933Y540848D01*
G01X599940Y540827D02*
X599938Y540838D01*
G01X599933Y547147D02*
X599926Y547156D01*
G01X599938Y547137D02*
X599933Y547147D01*
G01X599940Y547126D02*
X599938Y547137D01*
G01X599933Y550297D02*
X599926Y550305D01*
G01X599938Y550287D02*
X599933Y550297D01*
G01X599940Y550276D02*
X599938Y550287D01*
G01X599933Y553446D02*
X599926Y553455D01*
G01X599938Y553436D02*
X599933Y553446D01*
G01X599940Y553425D02*
X599938Y553436D01*
G01X599933Y556596D02*
X599926Y556604D01*
G01X599938Y556586D02*
X599933Y556596D01*
G01X599940Y556575D02*
X599938Y556586D01*
G01X598970Y556606D02*
X598994Y556614D01*
G01X598959Y556591D02*
X598970Y556606D01*
G01X598957Y556584D02*
X598959Y556591D01*
G01X598970Y553456D02*
X598994Y553465D01*
G01X598959Y553441D02*
X598970Y553456D01*
G01X598957Y553435D02*
X598959Y553441D01*
G01X598970Y550306D02*
X598994Y550315D01*
G01X598959Y550292D02*
X598970Y550306D01*
G01X598957Y550285D02*
X598959Y550292D01*
G01X598970Y547157D02*
X598994Y547165D01*
G01X598959Y547142D02*
X598970Y547157D01*
G01X598957Y547135D02*
X598959Y547142D01*
G01X598970Y544007D02*
X598994Y544016D01*
G01X598959Y543993D02*
X598970Y544007D01*
G01X598957Y543986D02*
X598959Y543993D01*
G01X598970Y540857D02*
X598994Y540866D01*
G01X598959Y540843D02*
X598970Y540857D01*
G01X598957Y540836D02*
X598959Y540843D01*
G01X598970Y537708D02*
X598994Y537717D01*
G01X598959Y537693D02*
X598970Y537708D01*
G01X598957Y537687D02*
X598959Y537693D01*
G01X599941Y556581D02*
Y556588D01*
G01Y556576D02*
Y556581D01*
G01X599940Y556575D02*
X599941Y556576D01*
G01Y553431D02*
Y553439D01*
G01Y553427D02*
Y553431D01*
G01X599940Y553425D02*
X599941Y553427D01*
G01Y550282D02*
Y550289D01*
G01Y550277D02*
Y550282D01*
G01X599940Y550276D02*
X599941Y550277D01*
G01Y547132D02*
Y547139D01*
G01Y547128D02*
Y547132D01*
G01X599940Y547126D02*
X599941Y547128D01*
G01Y543983D02*
Y543990D01*
G01Y543978D02*
Y543983D01*
G01X599940Y543976D02*
X599941Y543978D01*
G01Y540833D02*
Y540840D01*
G01Y540828D02*
Y540833D01*
G01X599940Y540827D02*
X599941Y540828D01*
G01Y537683D02*
Y537691D01*
G01Y537679D02*
Y537683D01*
G01X599940Y537677D02*
X599941Y537679D01*
G01X598956Y546018D02*
X598957Y546010D01*
G01X598956Y546022D02*
Y546018D01*
G01X598954Y546019D02*
X598956Y546022D01*
G01X599931Y537715D02*
X599935Y537709D01*
G01X599927Y537719D02*
X599931Y537715D01*
G01X599921Y537723D02*
X599927Y537719D01*
G01X599915Y537726D02*
X599921Y537723D01*
G01X599908Y537727D02*
X599915Y537726D01*
G01X599902Y537728D02*
X599908Y537727D01*
G01X599931Y540865D02*
X599935Y540859D01*
G01X599927Y540869D02*
X599931Y540865D01*
G01X599921Y540872D02*
X599927Y540869D01*
G01X599915Y540875D02*
X599921Y540872D01*
G01X599908Y540877D02*
X599915Y540875D01*
G01X599902Y540877D02*
X599908D01*
G01X599931Y544014D02*
X599935Y544009D01*
G01X599927Y544019D02*
X599931Y544014D01*
G01X599921Y544022D02*
X599927Y544019D01*
G01X599915Y544025D02*
X599921Y544022D01*
G01X599908Y544026D02*
X599915Y544025D01*
G01X599902Y544027D02*
X599908Y544026D01*
G01X599931Y547164D02*
X599935Y547158D01*
G01X599927Y547168D02*
X599931Y547164D01*
G01X599921Y547172D02*
X599927Y547168D01*
G01X599915Y547174D02*
X599921Y547172D01*
G01X599908Y547176D02*
X599915Y547174D01*
G01X599902Y547176D02*
X599908D01*
G01X599931Y550313D02*
X599935Y550308D01*
G01X599927Y550318D02*
X599931Y550313D01*
G01X599921Y550321D02*
X599927Y550318D01*
G01X599915Y550324D02*
X599921Y550321D01*
G01X599908Y550326D02*
X599915Y550324D01*
G01X599902Y550326D02*
X599908D01*
G01X599931Y553463D02*
X599935Y553457D01*
G01X599927Y553467D02*
X599931Y553463D01*
G01X599921Y553471D02*
X599927Y553467D01*
G01X599915Y553474D02*
X599921Y553471D01*
G01X599908Y553475D02*
X599915Y553474D01*
G01X599902Y553476D02*
X599908Y553475D01*
G01X599931Y556613D02*
X599935Y556607D01*
G01X599927Y556617D02*
X599931Y556613D01*
G01X599921Y556620D02*
X599927Y556617D01*
G01X599915Y556623D02*
X599921Y556620D01*
G01X599908Y556625D02*
X599915Y556623D01*
G01X599902Y556625D02*
X599908D01*
G01X598957Y536554D02*
Y536561D01*
G01X598960Y536547D02*
X598957Y536554D01*
G01X598963Y536541D02*
X598960Y536547D01*
G01X598968Y536535D02*
X598963Y536541D01*
G01X598974Y536530D02*
X598968Y536535D01*
G01X598981Y536527D02*
X598974Y536530D01*
G01X598989Y536525D02*
X598981Y536527D01*
G01X598996Y536524D02*
X598989Y536525D01*
G01X598957Y539704D02*
Y539711D01*
G01X598960Y539696D02*
X598957Y539704D01*
G01X598963Y539690D02*
X598960Y539696D01*
G01X598968Y539685D02*
X598963Y539690D01*
G01X598974Y539680D02*
X598968Y539685D01*
G01X598981Y539676D02*
X598974Y539680D01*
G01X598989Y539674D02*
X598981Y539676D01*
G01X598996Y539674D02*
X598989D01*
G01X598957Y542853D02*
Y542860D01*
G01X598960Y542846D02*
X598957Y542853D01*
G01X598963Y542840D02*
X598960Y542846D01*
G01X598968Y542834D02*
X598963Y542840D01*
G01X598974Y542830D02*
X598968Y542834D01*
G01X598981Y542826D02*
X598974Y542830D01*
G01X598989Y542824D02*
X598981Y542826D01*
G01X598996Y542823D02*
X598989Y542824D01*
G01X598957Y546003D02*
Y546010D01*
G01X598960Y545996D02*
X598957Y546003D01*
G01X598963Y545989D02*
X598960Y545996D01*
G01X598968Y545984D02*
X598963Y545989D01*
G01X598974Y545979D02*
X598968Y545984D01*
G01X598981Y545976D02*
X598974Y545979D01*
G01X598989Y545974D02*
X598981Y545976D01*
G01X598996Y545973D02*
X598989Y545974D01*
G01X598957Y549152D02*
Y549159D01*
G01X598960Y549145D02*
X598957Y549152D01*
G01X598963Y549139D02*
X598960Y549145D01*
G01X598968Y549133D02*
X598963Y549139D01*
G01X598974Y549129D02*
X598968Y549133D01*
G01X598981Y549125D02*
X598974Y549129D01*
G01X598989Y549123D02*
X598981Y549125D01*
G01X598996Y549122D02*
X598989Y549123D01*
G01X598957Y552302D02*
Y552309D01*
G01X598960Y552295D02*
X598957Y552302D01*
G01X598963Y552289D02*
X598960Y552295D01*
G01X598968Y552283D02*
X598963Y552289D01*
G01X598974Y552278D02*
X598968Y552283D01*
G01X598981Y552275D02*
X598974Y552278D01*
G01X598989Y552273D02*
X598981Y552275D01*
G01X598996Y552272D02*
X598989Y552273D01*
G01X598957Y555452D02*
Y555459D01*
G01X598960Y555444D02*
X598957Y555452D01*
G01X598963Y555438D02*
X598960Y555444D01*
G01X598968Y555433D02*
X598963Y555438D01*
G01X598974Y555428D02*
X598968Y555433D01*
G01X598981Y555424D02*
X598974Y555428D01*
G01X598989Y555422D02*
X598981Y555424D01*
G01X598996Y555422D02*
X598989D01*
G01X599911Y537715D02*
X599920Y537711D01*
G01X599900Y537717D02*
X599911Y537715D01*
G01Y540865D02*
X599920Y540861D01*
G01X599900Y540866D02*
X599911Y540865D01*
G01Y544014D02*
X599920Y544010D01*
G01X599900Y544016D02*
X599911Y544014D01*
G01Y547164D02*
X599920Y547160D01*
G01X599900Y547165D02*
X599911Y547164D01*
G01Y550313D02*
X599920Y550309D01*
G01X599900Y550315D02*
X599911Y550313D01*
G01Y553463D02*
X599920Y553459D01*
G01X599900Y553465D02*
X599911Y553463D01*
G01Y556613D02*
X599920Y556609D01*
G01X599900Y556614D02*
X599911Y556613D01*
G01X598957Y552313D02*
Y552309D01*
G01X598958Y552307D02*
X598957Y552313D01*
G01X598970Y552292D02*
X598958Y552307D01*
G01X598994Y552283D02*
X598970Y552292D01*
G01X598957Y555463D02*
Y555459D01*
G01X598958Y555457D02*
X598957Y555463D01*
G01X598970Y555441D02*
X598958Y555457D01*
G01X598994Y555433D02*
X598970Y555441D01*
G01X613354Y559755D02*
X613365Y559740D01*
G01X613329Y559764D02*
X613354Y559755D01*
G01Y564755D02*
X613365Y564740D01*
G01X613329Y564764D02*
X613354Y564755D01*
G01Y569755D02*
X613365Y569740D01*
G01X613329Y569764D02*
X613354Y569755D01*
G01X598956Y539719D02*
X598957Y539711D01*
G01X598956Y539723D02*
Y539719D01*
G01X598954Y539721D02*
X598956Y539723D01*
G01X599902Y556619D02*
Y556625D01*
G01X599901Y556615D02*
X599902Y556619D01*
G01X599900Y556614D02*
X599901Y556615D01*
G01X599902Y553470D02*
Y553476D01*
G01X599901Y553466D02*
X599902Y553470D01*
G01X599900Y553465D02*
X599901Y553466D01*
G01X599902Y550320D02*
Y550326D01*
G01X599901Y550316D02*
X599902Y550320D01*
G01X599900Y550315D02*
X599901Y550316D01*
G01X599902Y547170D02*
Y547176D01*
G01X599901Y547167D02*
X599902Y547170D01*
G01X599900Y547165D02*
X599901Y547167D01*
G01X599902Y544021D02*
Y544027D01*
G01X599901Y544017D02*
X599902Y544021D01*
G01X599900Y544016D02*
X599901Y544017D01*
G01X599902Y540871D02*
Y540877D01*
G01X599901Y540867D02*
X599902Y540871D01*
G01X599900Y540866D02*
X599901Y540867D01*
G01X599902Y537722D02*
Y537728D01*
G01X599901Y537718D02*
X599902Y537722D01*
G01X599900Y537717D02*
X599901Y537718D01*
G01X613367Y568378D02*
X613366Y568369D01*
G01X613367Y568384D02*
Y568378D01*
G01X613369Y568386D02*
X613367Y568384D01*
G01X599940Y552302D02*
X599941Y552309D01*
G01X599938Y552295D02*
X599940Y552302D01*
G01X599934Y552289D02*
X599938Y552295D01*
G01X599930Y552283D02*
X599934Y552289D01*
G01X599923Y552278D02*
X599930Y552283D01*
G01X599917Y552275D02*
X599923Y552278D01*
G01X599909Y552273D02*
X599917Y552275D01*
G01X599902Y552272D02*
X599909Y552273D01*
G01X599919Y536528D02*
X599922Y536530D01*
G01X599915Y536526D02*
X599919Y536528D01*
G01X599912Y536526D02*
X599915D01*
G01X599909Y536525D02*
X599912Y536526D01*
G01X599905Y536524D02*
X599909Y536525D01*
G01X599902Y536524D02*
X599905D01*
G01X598979Y537724D02*
X598976Y537722D01*
G01X598982Y537725D02*
X598979Y537724D01*
G01X598986Y537726D02*
X598982Y537725D01*
G01X598989Y537727D02*
X598986Y537726D01*
G01X598993Y537728D02*
X598989Y537727D01*
G01X598996Y537728D02*
X598993D01*
G01X599919Y539677D02*
X599922Y539679D01*
G01X599915Y539676D02*
X599919Y539677D01*
G01X599912Y539675D02*
X599915Y539676D01*
G01X599909Y539674D02*
X599912Y539675D01*
G01X599905Y539674D02*
X599909D01*
G01X599902D02*
X599905D01*
G01X598979Y540874D02*
X598976Y540872D01*
G01X598982Y540875D02*
X598979Y540874D01*
G01X598986Y540876D02*
X598982Y540875D01*
G01X598989Y540877D02*
X598986Y540876D01*
G01X598993Y540877D02*
X598989D01*
G01X598996D02*
X598993D01*
G01X599919Y542827D02*
X599922Y542829D01*
G01X599915Y542826D02*
X599919Y542827D01*
G01X599912Y542825D02*
X599915Y542826D01*
G01X599909Y542824D02*
X599912Y542825D01*
G01X599905Y542824D02*
X599909D01*
G01X599902Y542823D02*
X599905Y542824D01*
G01X598979Y544023D02*
X598976Y544022D01*
G01X598982Y544024D02*
X598979Y544023D01*
G01X598986Y544026D02*
X598982Y544024D01*
G01X598989Y544026D02*
X598986D01*
G01X598993Y544027D02*
X598989Y544026D01*
G01X598996Y544027D02*
X598993D01*
G01X599919Y545976D02*
X599922Y545978D01*
G01X599915Y545975D02*
X599919Y545976D01*
G01X599912Y545974D02*
X599915Y545975D01*
G01X599909Y545974D02*
X599912D01*
G01X599905Y545973D02*
X599909Y545974D01*
G01X599902Y545973D02*
X599905D01*
G01X598979Y547173D02*
X598976Y547171D01*
G01X598982Y547174D02*
X598979Y547173D01*
G01X598986Y547175D02*
X598982Y547174D01*
G01X598989Y547176D02*
X598986Y547175D01*
G01X598993Y547176D02*
X598989D01*
G01X598996D02*
X598993D01*
G01X599919Y549126D02*
X599922Y549128D01*
G01X599915Y549125D02*
X599919Y549126D01*
G01X599912Y549124D02*
X599915Y549125D01*
G01X599909Y549123D02*
X599912Y549124D01*
G01X599905Y549123D02*
X599909D01*
G01X599902Y549122D02*
X599905Y549123D01*
G01X598979Y550322D02*
X598976Y550321D01*
G01X598982Y550324D02*
X598979Y550322D01*
G01X598986Y550325D02*
X598982Y550324D01*
G01X598989Y550326D02*
X598986Y550325D01*
G01X598993Y550326D02*
X598989D01*
G01X598996D02*
X598993D01*
G01X598979Y553472D02*
X598976Y553470D01*
G01X598982Y553473D02*
X598979Y553472D01*
G01X598986Y553474D02*
X598982Y553473D01*
G01X598989Y553475D02*
X598986Y553474D01*
G01X598993Y553476D02*
X598989Y553475D01*
G01X598996Y553476D02*
X598993D01*
G01X599919Y555425D02*
X599922Y555427D01*
G01X599915Y555424D02*
X599919Y555425D01*
G01X599912Y555423D02*
X599915Y555424D01*
G01X599909Y555422D02*
X599912Y555423D01*
G01X599905Y555422D02*
X599909D01*
G01X599902D02*
X599905D01*
G01X598979Y556622D02*
X598976Y556620D01*
G01X598982Y556623D02*
X598979Y556622D01*
G01X598986Y556624D02*
X598982Y556623D01*
G01X598989Y556625D02*
X598986Y556624D01*
G01X598993Y556625D02*
X598989D01*
G01X598996D02*
X598993D01*
G01X598209Y539724D02*
X597776D01*
G01X598583D02*
X598209D01*
G01Y546024D02*
X597776D01*
G01X598583D02*
X598209D01*
G01Y549173D02*
X597776D01*
G01X598583D02*
X598209D01*
G01X613367Y563378D02*
X613366Y563369D01*
G01X613367Y563384D02*
Y563378D01*
G01X613369Y563386D02*
X613367Y563384D01*
G01Y558378D02*
X613366Y558369D01*
G01X613367Y558384D02*
Y558378D01*
G01X613369Y558386D02*
X613367Y558384D01*
G01Y533378D02*
X613366Y533369D01*
G01X613367Y533384D02*
Y533378D01*
G01X613369Y533386D02*
X613367Y533384D01*
G01Y528378D02*
X613366Y528369D01*
G01X613367Y528384D02*
Y528378D01*
G01X613369Y528386D02*
X613367Y528384D01*
G01Y523378D02*
X613366Y523369D01*
G01X613367Y523384D02*
Y523378D01*
G01X613369Y523386D02*
X613367Y523384D01*
G01Y518378D02*
X613366Y518369D01*
G01X613367Y518384D02*
Y518378D01*
G01X613369Y518386D02*
X613367Y518384D01*
G01Y513378D02*
X613366Y513369D01*
G01X613367Y513384D02*
Y513378D01*
G01X613369Y513386D02*
X613367Y513384D01*
G01Y508378D02*
X613366Y508369D01*
G01X613367Y508384D02*
Y508378D01*
G01X613369Y508386D02*
X613367Y508384D01*
G01Y503378D02*
X613366Y503369D01*
G01X613367Y503384D02*
Y503378D01*
G01X613369Y503386D02*
X613367Y503384D01*
G01X598956Y556581D02*
X598957Y556588D01*
G01X598956Y556576D02*
Y556581D01*
G01X598954Y556575D02*
X598956Y556576D01*
G01Y553431D02*
X598957Y553439D01*
G01X598956Y553427D02*
Y553431D01*
G01X598954Y553425D02*
X598956Y553427D01*
G01Y550281D02*
X598957Y550289D01*
G01X598956Y550277D02*
Y550281D01*
G01X598954Y550276D02*
X598956Y550277D01*
G01Y547132D02*
X598957Y547139D01*
G01X598956Y547128D02*
Y547132D01*
G01X598954Y547126D02*
X598956Y547128D01*
G01Y543982D02*
X598957Y543990D01*
G01X598956Y543978D02*
Y543982D01*
G01X598954Y543976D02*
X598956Y543978D01*
G01Y540833D02*
X598957Y540840D01*
G01X598956Y540828D02*
Y540833D01*
G01X598954Y540827D02*
X598956Y540828D01*
G01Y537683D02*
X598957Y537691D01*
G01X598956Y537679D02*
Y537683D01*
G01X598954Y537677D02*
X598956Y537679D01*
G01X598959Y537697D02*
X598954Y537677D01*
G01X598974Y537711D02*
X598959Y537697D01*
G01X598994Y537717D02*
X598974Y537711D01*
G01X598959Y540846D02*
X598954Y540827D01*
G01X598974Y540861D02*
X598959Y540846D01*
G01X598994Y540866D02*
X598974Y540861D01*
G01X598959Y543996D02*
X598954Y543976D01*
G01X598974Y544010D02*
X598959Y543996D01*
G01X598994Y544016D02*
X598974Y544010D01*
G01X598959Y547146D02*
X598954Y547126D01*
G01X598974Y547160D02*
X598959Y547146D01*
G01X598994Y547165D02*
X598974Y547160D01*
G01X598959Y550295D02*
X598954Y550276D01*
G01X598974Y550309D02*
X598959Y550295D01*
G01X598994Y550315D02*
X598974Y550309D01*
G01X598959Y553445D02*
X598954Y553425D01*
G01X598974Y553459D02*
X598959Y553445D01*
G01X598994Y553465D02*
X598974Y553459D01*
G01X598959Y556594D02*
X598954Y556575D01*
G01X598974Y556609D02*
X598959Y556594D01*
G01X598994Y556614D02*
X598974Y556609D01*
G01X599934Y536555D02*
X599939Y536575D01*
G01X599920Y536541D02*
X599934Y536555D01*
G01X599900Y536535D02*
X599920Y536541D01*
G01X599934Y539705D02*
X599939Y539724D01*
G01X599920Y539690D02*
X599934Y539705D01*
G01X599900Y539685D02*
X599920Y539690D01*
G01X599934Y542854D02*
X599939Y542874D01*
G01X599920Y542840D02*
X599934Y542854D01*
G01X599900Y542835D02*
X599920Y542840D01*
G01X599934Y546004D02*
X599939Y546024D01*
G01X599920Y545989D02*
X599934Y546004D01*
G01X599900Y545984D02*
X599920Y545989D01*
G01X599934Y549154D02*
X599939Y549173D01*
G01X599920Y549139D02*
X599934Y549154D01*
G01X599900Y549134D02*
X599920Y549139D01*
G01X599934Y552303D02*
X599939Y552323D01*
G01X599920Y552289D02*
X599934Y552303D01*
G01X599900Y552283D02*
X599920Y552289D01*
G01X599934Y555453D02*
X599939Y555472D01*
G01X599920Y555438D02*
X599934Y555453D01*
G01X599900Y555433D02*
X599920Y555438D01*
G01X599939Y555446D02*
X599941Y555459D01*
G01X599932Y555435D02*
X599939Y555446D01*
G01X599922Y555427D02*
X599932Y555435D01*
G01X599939Y549147D02*
X599941Y549159D01*
G01X599932Y549136D02*
X599939Y549147D01*
G01X599922Y549128D02*
X599932Y549136D01*
G01X599939Y545998D02*
X599941Y546010D01*
G01X599932Y545986D02*
X599939Y545998D01*
G01X599922Y545978D02*
X599932Y545986D01*
G01X599939Y542848D02*
X599941Y542860D01*
G01X599932Y542837D02*
X599939Y542848D01*
G01X599922Y542829D02*
X599932Y542837D01*
G01X599939Y539698D02*
X599941Y539711D01*
G01X599932Y539687D02*
X599939Y539698D01*
G01X599922Y539679D02*
X599932Y539687D01*
G01X599939Y536549D02*
X599941Y536561D01*
G01X599932Y536537D02*
X599939Y536549D01*
G01X599922Y536530D02*
X599932Y536537D01*
G01X598995Y556619D02*
Y556625D01*
G01Y556615D02*
Y556619D01*
G01X598994Y556614D02*
X598995Y556615D01*
G01Y553469D02*
Y553476D01*
G01Y553466D02*
Y553469D01*
G01X598994Y553465D02*
X598995Y553466D01*
G01Y550320D02*
Y550326D01*
G01Y550316D02*
Y550320D01*
G01X598994Y550315D02*
X598995Y550316D01*
G01Y547170D02*
Y547176D01*
G01Y547167D02*
Y547170D01*
G01X598994Y547165D02*
X598995Y547167D01*
G01Y544020D02*
Y544027D01*
G01Y544017D02*
Y544020D01*
G01X598994Y544016D02*
X598995Y544017D01*
G01Y540871D02*
Y540877D01*
G01Y540867D02*
Y540871D01*
G01X598994Y540866D02*
X598995Y540867D01*
G01Y537721D02*
Y537728D01*
G01Y537718D02*
Y537721D01*
G01X598994Y537717D02*
X598995Y537718D01*
G01X598957Y556594D02*
Y556588D01*
G01X598959Y556601D02*
X598957Y556594D01*
G01X598962Y556607D02*
X598959Y556601D01*
G01X598966Y556612D02*
X598962Y556607D01*
G01X598970Y556617D02*
X598966Y556612D01*
G01X598976Y556620D02*
X598970Y556617D01*
G01X598957Y553445D02*
Y553439D01*
G01X598959Y553451D02*
X598957Y553445D01*
G01X598962Y553457D02*
X598959Y553451D01*
G01X598966Y553462D02*
X598962Y553457D01*
G01X598970Y553467D02*
X598966Y553462D01*
G01X598976Y553470D02*
X598970Y553467D01*
G01X598957Y550295D02*
Y550289D01*
G01X598959Y550302D02*
X598957Y550295D01*
G01X598962Y550307D02*
X598959Y550302D01*
G01X598966Y550313D02*
X598962Y550307D01*
G01X598970Y550317D02*
X598966Y550313D01*
G01X598976Y550321D02*
X598970Y550317D01*
G01X598957Y547146D02*
Y547139D01*
G01X598959Y547152D02*
X598957Y547146D01*
G01X598962Y547158D02*
X598959Y547152D01*
G01X598966Y547163D02*
X598962Y547158D01*
G01X598970Y547168D02*
X598966Y547163D01*
G01X598976Y547171D02*
X598970Y547168D01*
G01X598957Y543996D02*
Y543990D01*
G01X598959Y544002D02*
X598957Y543996D01*
G01X598962Y544008D02*
X598959Y544002D01*
G01X598966Y544013D02*
X598962Y544008D01*
G01X598970Y544018D02*
X598966Y544013D01*
G01X598976Y544022D02*
X598970Y544018D01*
G01X598957Y540846D02*
Y540840D01*
G01X598959Y540853D02*
X598957Y540846D01*
G01X598962Y540859D02*
X598959Y540853D01*
G01X598966Y540864D02*
X598962Y540859D01*
G01X598970Y540869D02*
X598966Y540864D01*
G01X598976Y540872D02*
X598970Y540869D01*
G01X598957Y537697D02*
Y537691D01*
G01X598959Y537703D02*
X598957Y537697D01*
G01X598962Y537709D02*
X598959Y537703D01*
G01X598966Y537714D02*
X598962Y537709D01*
G01X598970Y537719D02*
X598966Y537714D01*
G01X598976Y537722D02*
X598970Y537719D01*
G01X599912Y555435D02*
X599900Y555433D01*
G01X599922Y555440D02*
X599912Y555435D01*
G01Y552285D02*
X599900Y552283D01*
G01X599922Y552290D02*
X599912Y552285D01*
G01Y549136D02*
X599900Y549134D01*
G01X599922Y549141D02*
X599912Y549136D01*
G01Y545986D02*
X599900Y545984D01*
G01X599922Y545991D02*
X599912Y545986D01*
G01Y542837D02*
X599900Y542835D01*
G01X599922Y542841D02*
X599912Y542837D01*
G01Y539687D02*
X599900Y539685D01*
G01X599922Y539692D02*
X599912Y539687D01*
G01Y536537D02*
X599900Y536535D01*
G01X599922Y536542D02*
X599912Y536537D01*
G01X603937Y477894D02*
G03X604528Y477303I591J0D01*
G01X611220D02*
G03X611811Y477894I0J591D01*
G01X609055Y479075D02*
G03Y481043I0J984D01*
G01X606693D02*
G03Y479075I0J-984D01*
G01X608976Y492264D02*
G03I-1102J0D01*
G01X610433Y486988D02*
G03X611614Y488169I0J1181D01*
G01X604134D02*
G03X605315Y486988I1181J0D01*
G01X609449Y492264D02*
G03I-1575J0D01*
G01X597047Y478484D02*
G03X599016Y476516I1968J0D01*
G01X616732D02*
G03X618701Y478484I1J1968D01*
G01X603346Y500256D02*
X602165Y499075D01*
G01X600394Y497579D02*
X597047Y494232D01*
G01X612795Y556437D02*
X613976Y557618D01*
G01X608858Y556437D02*
X610039Y557618D01*
G01X610359Y495335D02*
X609055Y493366D01*
G01X598843Y555472D02*
X598955Y555464D01*
G01X598954Y546019D02*
X598843Y546024D01*
G01X598954Y549170D02*
X598843Y549173D01*
G01X613366Y570256D02*
X612382D01*
G01X612383Y569764D02*
X617717D01*
G01Y569724D02*
X613369D01*
G01X617717Y568386D02*
X612383D01*
G01X612382Y567894D02*
X613366D01*
G01Y565256D02*
X612382D01*
G01X612383Y564764D02*
X617717D01*
G01Y564724D02*
X613369D01*
G01X617717Y563386D02*
X612383D01*
G01X612382Y562894D02*
X613366D01*
G01Y560256D02*
X612382D01*
G01X612383Y559764D02*
X617717D01*
G01Y559724D02*
X613369D01*
G01X600394Y558780D02*
X597047D01*
G01X617717Y558386D02*
X612383D01*
G01X612382Y557894D02*
X613366D01*
G01X610039Y557618D02*
X613976D01*
G01X599902Y556811D02*
X598996D01*
G01X599941Y556772D02*
X598957D01*
G01X599900Y556614D02*
X594016D01*
G01Y556575D02*
X599940D01*
G01X608858Y556437D02*
X612795D01*
G01X599939Y555472D02*
X594016D01*
G01X599900Y555433D02*
X594016D01*
G01X598957Y555276D02*
X599941D01*
G01X598996Y555236D02*
X599902D01*
G01Y553661D02*
X598996D01*
G01X599941Y553622D02*
X598957D01*
G01X599900Y553465D02*
X594016D01*
G01Y553425D02*
X599940D01*
G01X599939Y552323D02*
X594016D01*
G01X599900Y552283D02*
X594016D01*
G01X598957Y552126D02*
X599941D01*
G01X598996Y552087D02*
X599902D01*
G01Y550512D02*
X598996D01*
G01X599941Y550472D02*
X598957D01*
G01X599900Y550315D02*
X594016D01*
G01Y550276D02*
X599940D01*
G01X599939Y549173D02*
X594016D01*
G01X599900Y549134D02*
X594016D01*
G01X598957Y548976D02*
X599941D01*
G01X598996Y548937D02*
X599902D01*
G01Y547362D02*
X598996D01*
G01X599941Y547323D02*
X598957D01*
G01X599900Y547165D02*
X594016D01*
G01Y547126D02*
X599940D01*
G01X599939Y546024D02*
X594016D01*
G01X599900Y545984D02*
X594016D01*
G01X598957Y545827D02*
X599941D01*
G01X598996Y545787D02*
X599902D01*
G01Y544213D02*
X598996D01*
G01X599941Y544173D02*
X598957D01*
G01X599900Y544016D02*
X594016D01*
G01Y543976D02*
X599940D01*
G01X599939Y542874D02*
X594016D01*
G01X599900Y542835D02*
X594016D01*
G01X598957Y542677D02*
X599941D01*
G01X598996Y542638D02*
X599902D01*
G01Y541063D02*
X598996D01*
G01X599941Y541024D02*
X598957D01*
G01X599900Y540866D02*
X594016D01*
G01Y540827D02*
X599940D01*
G01X599939Y539724D02*
X594016D01*
G01X599900Y539685D02*
X594016D01*
G01X598957Y539528D02*
X599941D01*
G01X598996Y539488D02*
X599902D01*
G01Y537913D02*
X598996D01*
G01X599941Y537874D02*
X598957D01*
G01X599900Y537717D02*
X594016D01*
G01Y537677D02*
X599940D01*
G01X612795Y536713D02*
X608858D01*
G01X599939Y536575D02*
X594016D01*
G01X599900Y536535D02*
X594016D01*
G01X598957Y536378D02*
X599941D01*
G01X598996Y536339D02*
X599902D01*
G01X613976Y535531D02*
X610039D01*
G01X613366Y535256D02*
X612382D01*
G01X612383Y534764D02*
X617717D01*
G01Y534724D02*
X613369D01*
G01X600394Y534370D02*
X597047D01*
G01X617717Y533386D02*
X612383D01*
G01X612382Y532894D02*
X613366D01*
G01Y530256D02*
X612382D01*
G01X612383Y529764D02*
X617717D01*
G01Y529724D02*
X613369D01*
G01X617717Y528386D02*
X612383D01*
G01X612382Y569959D02*
X613337Y569961D01*
G01X613366Y568190D02*
X612382Y568189D01*
G01Y564959D02*
X613337Y564961D01*
G01X613366Y563190D02*
X612382Y563189D01*
G01Y559959D02*
X613337Y559961D01*
G01X613366Y558190D02*
X612382Y558189D01*
G01Y534959D02*
X613337Y534961D01*
G01X613366Y533190D02*
X612382Y533189D01*
G01Y529959D02*
X613337Y529961D01*
G01X613366Y528190D02*
X612382Y528189D01*
G01X604383Y487444D02*
X606693Y491673D01*
G01X598954Y539721D02*
X598843Y539724D01*
G01X612382Y527894D02*
X613366D01*
G01Y525256D02*
X612382D01*
G01X612383Y524764D02*
X617717D01*
G01Y524724D02*
X613369D01*
G01X617717Y523386D02*
X612383D01*
G01X612382Y522894D02*
X613366D01*
G01Y520256D02*
X612382D01*
G01X612383Y519764D02*
X617717D01*
G01Y519724D02*
X613369D01*
G01X617717Y518386D02*
X612383D01*
G01X612382Y517894D02*
X613366D01*
G01Y515256D02*
X612382D01*
G01X612383Y514764D02*
X617717D01*
G01Y514724D02*
X613369D01*
G01X617717Y513386D02*
X612383D01*
G01X612382Y512894D02*
X613366D01*
G01Y510256D02*
X612382D01*
G01X612383Y509764D02*
X617717D01*
G01Y509724D02*
X613369D01*
G01X617717Y508386D02*
X612383D01*
G01X612382Y507894D02*
X613366D01*
G01Y505256D02*
X612382D01*
G01X612383Y504764D02*
X617717D01*
G01Y504724D02*
X613369D01*
G01X617717Y503386D02*
X612383D01*
G01X612382Y502894D02*
X613366D01*
G01X608858Y500256D02*
X603346D01*
G01X610039Y499075D02*
X602165D01*
G01X615354Y497579D02*
X600394D01*
G01X611614Y496713D02*
X614764D01*
G01X604134D02*
X600394D01*
G01Y495335D02*
X614764D01*
G01X609055Y493366D02*
X606693D01*
G01X609055Y491673D02*
X606693D01*
G01X610433Y486988D02*
X605315D01*
G01X618701Y486949D02*
X597047D01*
G01X611811Y483996D02*
X603937D01*
G01Y482421D02*
X611811D01*
G01X609055Y481043D02*
X606693D01*
G01Y479075D02*
X609055D01*
G01X611220Y477303D02*
X604528D01*
G01X616732Y476516D02*
X599016D01*
G01X612382Y524959D02*
X613337Y524961D01*
G01X613366Y523190D02*
X612382Y523189D01*
G01Y519959D02*
X613337Y519961D01*
G01X613366Y518190D02*
X612382Y518189D01*
G01Y514959D02*
X613337Y514961D01*
G01X613366Y513190D02*
X612382Y513189D01*
G01Y509959D02*
X613337Y509961D01*
G01X613366Y508190D02*
X612382Y508189D01*
G01Y504959D02*
X613337Y504961D01*
G01X613366Y503190D02*
X612382Y503189D01*
G01X599941Y537679D02*
Y537691D01*
G01Y540829D02*
Y540840D01*
G01Y543978D02*
Y543990D01*
G01Y547128D02*
Y547139D01*
G01Y550278D02*
Y550289D01*
G01Y553427D02*
Y553439D01*
G01Y556577D02*
Y556588D01*
G01X613366Y504738D02*
X613367Y504746D01*
G01X613366Y509738D02*
X613367Y509746D01*
G01X613366Y514738D02*
X613367Y514746D01*
G01X613366Y519738D02*
X613367Y519746D01*
G01X613366Y524738D02*
X613367Y524746D01*
G01X613366Y529738D02*
X613367Y529746D01*
G01X613366Y534738D02*
X613367Y534746D01*
G01X613366Y559738D02*
X613367Y559746D01*
G01X613366Y564738D02*
X613367Y564746D01*
G01X613366Y569738D02*
X613367Y569746D01*
G01X618701Y478484D02*
Y494232D01*
G01X617717Y568386D02*
Y569764D01*
G01Y563386D02*
Y564764D01*
G01Y558386D02*
Y559764D01*
G01Y533386D02*
Y534764D01*
G01Y528386D02*
Y529764D01*
G01Y523386D02*
Y524764D01*
G01Y518386D02*
Y519764D01*
G01Y513386D02*
Y514764D01*
G01Y508386D02*
Y509764D01*
G01Y503386D02*
Y504764D01*
G01X615354Y635571D02*
Y497579D01*
G01X614764Y637815D02*
Y495335D01*
G01X614547Y504764D02*
Y503386D01*
G01Y509764D02*
Y508386D01*
G01Y514764D02*
Y513386D01*
G01Y519764D02*
Y518386D01*
G01Y524764D02*
Y523386D01*
G01Y529764D02*
Y528386D01*
G01Y534764D02*
Y533386D01*
G01Y559764D02*
Y558386D01*
G01Y564764D02*
Y563386D01*
G01Y569764D02*
Y568386D01*
G01X613976Y557618D02*
Y535531D01*
G01X613366Y504738D02*
Y504881D01*
G01Y509738D02*
Y509881D01*
G01Y514738D02*
Y514881D01*
G01Y519738D02*
Y519881D01*
G01Y524738D02*
Y524881D01*
G01Y529738D02*
Y529881D01*
G01Y534738D02*
Y534881D01*
G01Y559738D02*
Y559881D01*
G01Y564738D02*
Y564881D01*
G01Y567894D02*
Y570256D01*
G01Y562894D02*
Y565256D01*
G01Y557894D02*
Y560256D01*
G01Y532894D02*
Y535256D01*
G01Y527894D02*
Y530256D01*
G01Y522894D02*
Y525256D01*
G01Y517894D02*
Y520256D01*
G01Y512894D02*
Y515256D01*
G01Y507894D02*
Y510256D01*
G01Y502894D02*
Y505256D01*
G01X612795Y556437D02*
Y536713D01*
G01X612382Y505256D02*
Y502894D01*
G01Y510256D02*
Y507894D01*
G01Y515256D02*
Y512894D01*
G01Y520256D02*
Y517894D01*
G01Y525256D02*
Y522894D01*
G01Y530256D02*
Y527894D01*
G01Y535256D02*
Y532894D01*
G01Y560256D02*
Y557894D01*
G01Y565256D02*
Y562894D01*
G01Y570256D02*
Y567894D01*
G01X611811Y483996D02*
Y477894D01*
G01X611614Y496713D02*
Y488169D01*
G01X610039Y535531D02*
Y499075D01*
G01Y634075D02*
Y557618D01*
G01X609055Y493366D02*
Y491673D01*
G01X608858Y536713D02*
Y500256D01*
G01Y632894D02*
Y556437D01*
G01X606693Y491673D02*
Y493366D01*
G01X604134Y488169D02*
Y496713D01*
G01X603937Y483996D02*
Y477894D01*
G01X603346Y500256D02*
Y632894D01*
G01X602165Y499075D02*
Y634075D01*
G01X600394Y534370D02*
Y495335D01*
G01Y637815D02*
Y558780D01*
G01X599941Y555275D02*
Y556772D01*
G01Y552126D02*
Y553622D01*
G01Y548976D02*
Y550472D01*
G01Y545826D02*
Y547323D01*
G01Y542677D02*
Y544173D01*
G01Y539527D02*
Y541024D01*
G01Y536378D02*
Y537874D01*
G01X599902Y536524D02*
Y536377D01*
G01Y539674D02*
Y539527D01*
G01Y541024D02*
Y540877D01*
G01Y537874D02*
Y537728D01*
G01Y545973D02*
Y545826D01*
G01Y542823D02*
Y542676D01*
G01Y544174D02*
Y544027D01*
G01Y549122D02*
Y548976D01*
G01Y550473D02*
Y550326D01*
G01Y547323D02*
Y547176D01*
G01Y555422D02*
Y555275D01*
G01Y552272D02*
Y552125D01*
G01Y553622D02*
Y553476D01*
G01Y556772D02*
Y556625D01*
G01X598996D02*
Y556772D01*
G01Y555275D02*
Y555422D01*
G01Y552125D02*
Y552272D01*
G01Y553476D02*
Y553622D01*
G01Y548976D02*
Y549122D01*
G01Y550326D02*
Y550473D01*
G01Y547176D02*
Y547323D01*
G01Y545826D02*
Y545973D01*
G01Y542676D02*
Y542823D01*
G01Y544027D02*
Y544174D01*
G01Y539527D02*
Y539674D01*
G01Y540877D02*
Y541024D01*
G01Y537728D02*
Y537874D01*
G01Y536377D02*
Y536524D01*
G01X598957Y541024D02*
Y539528D01*
G01Y537874D02*
Y536378D01*
G01Y544173D02*
Y542677D01*
G01Y550472D02*
Y548976D01*
G01Y547323D02*
Y545827D01*
G01Y553622D02*
Y552126D01*
G01Y556772D02*
Y555276D01*
G01X597776Y537717D02*
Y536535D01*
G01Y540866D02*
Y539685D01*
G01Y547165D02*
Y545984D01*
G01Y544016D02*
Y542835D01*
G01Y550315D02*
Y549134D01*
G01Y556614D02*
Y555433D01*
G01Y553465D02*
Y552283D01*
G01X597441Y558780D02*
Y534370D01*
G01X597047D02*
Y558780D01*
G01Y494232D02*
Y478484D01*
G01X594016Y555433D02*
Y556614D01*
G01Y552283D02*
Y553465D01*
G01Y549134D02*
Y550315D01*
G01Y545984D02*
Y547165D01*
G01Y542835D02*
Y544016D01*
G01Y539685D02*
Y540866D01*
G01Y536535D02*
Y537717D01*
G01X599941Y555459D02*
Y555470D01*
G01Y552309D02*
Y552320D01*
G01Y549160D02*
Y549170D01*
G01Y546010D02*
Y546021D01*
G01Y542861D02*
Y542871D01*
G01Y539711D02*
Y539722D01*
G01Y536561D02*
Y536572D01*
G01X599900Y552283D02*
X599904Y552272D01*
G01X609055Y491673D02*
X611365Y487444D01*
G01X606693Y493366D02*
X605389Y495335D01*
G01X612795Y536713D02*
X613976Y535531D01*
G01X608858Y536713D02*
X610039Y535531D01*
G01X615354Y497579D02*
X618701Y494232D01*
G01X608858Y500256D02*
X610039Y499075D01*
G01X612382Y574771D02*
Y574780D01*
G01X612383Y574765D02*
X612382Y574771D01*
G01X612383Y574764D02*
Y574765D01*
G01X613333Y574862D02*
X613337Y574961D01*
G01X613328Y574790D02*
X613333Y574862D01*
G01X613330Y574764D02*
X613328Y574790D01*
G01X613333Y579862D02*
X613337Y579961D01*
G01X613328Y579790D02*
X613333Y579862D01*
G01X613330Y579764D02*
X613328Y579790D01*
G01X613333Y584862D02*
X613337Y584961D01*
G01X613328Y584790D02*
X613333Y584862D01*
G01X613330Y584764D02*
X613328Y584790D01*
G01X613333Y589862D02*
X613337Y589961D01*
G01X613328Y589790D02*
X613333Y589862D01*
G01X613330Y589764D02*
X613328Y589790D01*
G01X613333Y594862D02*
X613337Y594961D01*
G01X613328Y594790D02*
X613333Y594862D01*
G01X613330Y594764D02*
X613328Y594790D01*
G01X613333Y599862D02*
X613337Y599961D01*
G01X613328Y599790D02*
X613333Y599862D01*
G01X613330Y599764D02*
X613328Y599790D01*
G01X613333Y604862D02*
X613337Y604961D01*
G01X613328Y604790D02*
X613333Y604862D01*
G01X613330Y604764D02*
X613328Y604790D01*
G01X613333Y609862D02*
X613337Y609961D01*
G01X613328Y609790D02*
X613333Y609862D01*
G01X613330Y609764D02*
X613328Y609790D01*
G01X613333Y614862D02*
X613337Y614961D01*
G01X613328Y614790D02*
X613333Y614862D01*
G01X613330Y614764D02*
X613328Y614790D01*
G01X613333Y619862D02*
X613337Y619961D01*
G01X613328Y619790D02*
X613333Y619862D01*
G01X613330Y619764D02*
X613328Y619790D01*
G01X613333Y624862D02*
X613337Y624961D01*
G01X613328Y624790D02*
X613333Y624862D01*
G01X613330Y624764D02*
X613328Y624790D01*
G01X613333Y629862D02*
X613337Y629961D01*
G01X613328Y629790D02*
X613333Y629862D01*
G01X613330Y629764D02*
X613328Y629790D01*
G01X612383Y628384D02*
Y628386D01*
G01X612382Y628378D02*
X612383Y628384D01*
G01X612382Y628370D02*
Y628378D01*
G01X612383Y623384D02*
Y623386D01*
G01X612382Y623378D02*
X612383Y623384D01*
G01X612382Y623370D02*
Y623378D01*
G01X612383Y618384D02*
Y618386D01*
G01X612382Y618378D02*
X612383Y618384D01*
G01X612382Y618370D02*
Y618378D01*
G01X612383Y613384D02*
Y613386D01*
G01X612382Y613378D02*
X612383Y613384D01*
G01X612382Y613370D02*
Y613378D01*
G01X612383Y608384D02*
Y608386D01*
G01X612382Y608378D02*
X612383Y608384D01*
G01X612382Y608370D02*
Y608378D01*
G01X612383Y603384D02*
Y603386D01*
G01X612382Y603378D02*
X612383Y603384D01*
G01X612382Y603370D02*
Y603378D01*
G01X612383Y598384D02*
Y598386D01*
G01X612382Y598378D02*
X612383Y598384D01*
G01X612382Y598370D02*
Y598378D01*
G01X612383Y593384D02*
Y593386D01*
G01X612382Y593378D02*
X612383Y593384D01*
G01X612382Y593370D02*
Y593378D01*
G01X612383Y588384D02*
Y588386D01*
G01X612382Y588378D02*
X612383Y588384D01*
G01X612382Y588370D02*
Y588378D01*
G01X612383Y583384D02*
Y583386D01*
G01X612382Y583378D02*
X612383Y583384D01*
G01X612382Y583370D02*
Y583378D01*
G01X612383Y578384D02*
Y578386D01*
G01X612382Y578378D02*
X612383Y578384D01*
G01X612382Y578370D02*
Y578378D01*
G01X612383Y573384D02*
Y573386D01*
G01X612382Y573378D02*
X612383Y573384D01*
G01X612382Y573370D02*
Y573378D01*
G01X613367Y574731D02*
X613366Y574738D01*
G01X613367Y574726D02*
Y574731D01*
G01X613369Y574724D02*
X613367Y574726D01*
G01Y579731D02*
X613366Y579738D01*
G01X613367Y579726D02*
Y579731D01*
G01X613369Y579724D02*
X613367Y579726D01*
G01Y584731D02*
X613366Y584738D01*
G01X613367Y584726D02*
Y584731D01*
G01X613369Y584724D02*
X613367Y584726D01*
G01Y589731D02*
X613366Y589738D01*
G01X613367Y589726D02*
Y589731D01*
G01X613369Y589724D02*
X613367Y589726D01*
G01Y594731D02*
X613366Y594738D01*
G01X613367Y594726D02*
Y594731D01*
G01X613369Y594724D02*
X613367Y594726D01*
G01Y599731D02*
X613366Y599738D01*
G01X613367Y599726D02*
Y599731D01*
G01X613369Y599724D02*
X613367Y599726D01*
G01Y604731D02*
X613366Y604738D01*
G01X613367Y604726D02*
Y604731D01*
G01X613369Y604724D02*
X613367Y604726D01*
G01Y609731D02*
X613366Y609738D01*
G01X613367Y609726D02*
Y609731D01*
G01X613369Y609724D02*
X613367Y609726D01*
G01Y614731D02*
X613366Y614738D01*
G01X613367Y614726D02*
Y614731D01*
G01X613369Y614724D02*
X613367Y614726D01*
G01Y619731D02*
X613366Y619738D01*
G01X613367Y619726D02*
Y619731D01*
G01X613369Y619724D02*
X613367Y619726D01*
G01Y624731D02*
X613366Y624738D01*
G01X613367Y624726D02*
Y624731D01*
G01X613369Y624724D02*
X613367Y624726D01*
G01Y629731D02*
X613366Y629738D01*
G01X613367Y629726D02*
Y629731D01*
G01X613369Y629724D02*
X613367Y629726D01*
G01X612382Y579771D02*
Y579780D01*
G01X612383Y579765D02*
X612382Y579771D01*
G01X612383Y579764D02*
Y579765D01*
G01X612382Y584771D02*
Y584780D01*
G01X612383Y584765D02*
X612382Y584771D01*
G01X612383Y584764D02*
Y584765D01*
G01X612382Y589771D02*
Y589780D01*
G01X612383Y589765D02*
X612382Y589771D01*
G01X612383Y589764D02*
Y589765D01*
G01X612382Y594771D02*
Y594780D01*
G01X612383Y594765D02*
X612382Y594771D01*
G01X612383Y594764D02*
Y594765D01*
G01X612382Y599771D02*
Y599780D01*
G01X612383Y599765D02*
X612382Y599771D01*
G01X612383Y599764D02*
Y599765D01*
G01X612382Y604771D02*
Y604780D01*
G01X612383Y604765D02*
X612382Y604771D01*
G01X612383Y604764D02*
Y604765D01*
G01X612382Y609771D02*
Y609780D01*
G01X612383Y609765D02*
X612382Y609771D01*
G01X612383Y609764D02*
Y609765D01*
G01X612382Y614771D02*
Y614780D01*
G01X612383Y614765D02*
X612382Y614771D01*
G01X612383Y614764D02*
Y614765D01*
G01X612382Y619771D02*
Y619780D01*
G01X612383Y619765D02*
X612382Y619771D01*
G01X612383Y619764D02*
Y619765D01*
G01X612382Y624771D02*
Y624780D01*
G01X612383Y624765D02*
X612382Y624771D01*
G01X612383Y624764D02*
Y624765D01*
G01X612382Y629771D02*
Y629780D01*
G01X612383Y629765D02*
X612382Y629771D01*
G01X612383Y629764D02*
Y629765D01*
G01X613358Y574907D02*
X613366Y574881D01*
G01X613348Y574934D02*
X613358Y574907D01*
G01X613337Y574961D02*
X613348Y574934D01*
G01X613358Y579907D02*
X613366Y579881D01*
G01X613348Y579934D02*
X613358Y579907D01*
G01X613337Y579961D02*
X613348Y579934D01*
G01X613358Y584907D02*
X613366Y584881D01*
G01X613348Y584934D02*
X613358Y584907D01*
G01X613337Y584961D02*
X613348Y584934D01*
G01X613358Y589907D02*
X613366Y589881D01*
G01X613348Y589934D02*
X613358Y589907D01*
G01X613337Y589961D02*
X613348Y589934D01*
G01X613358Y594907D02*
X613366Y594881D01*
G01X613348Y594934D02*
X613358Y594907D01*
G01X613337Y594961D02*
X613348Y594934D01*
G01X613358Y599907D02*
X613366Y599881D01*
G01X613348Y599934D02*
X613358Y599907D01*
G01X613337Y599961D02*
X613348Y599934D01*
G01X613358Y604907D02*
X613366Y604881D01*
G01X613348Y604934D02*
X613358Y604907D01*
G01X613337Y604961D02*
X613348Y604934D01*
G01X613358Y609907D02*
X613366Y609881D01*
G01X613348Y609934D02*
X613358Y609907D01*
G01X613337Y609961D02*
X613348Y609934D01*
G01X613358Y614907D02*
X613366Y614881D01*
G01X613348Y614934D02*
X613358Y614907D01*
G01X613337Y614961D02*
X613348Y614934D01*
G01X613358Y619907D02*
X613366Y619881D01*
G01X613348Y619934D02*
X613358Y619907D01*
G01X613337Y619961D02*
X613348Y619934D01*
G01X613358Y624907D02*
X613366Y624881D01*
G01X613348Y624934D02*
X613358Y624907D01*
G01X613337Y624961D02*
X613348Y624934D01*
G01X613358Y629907D02*
X613366Y629881D01*
G01X613348Y629934D02*
X613358Y629907D01*
G01X613337Y629961D02*
X613348Y629934D01*
G01X613349Y574759D02*
X613330Y574764D01*
G01X613363Y574744D02*
X613349Y574759D01*
G01X613369Y574724D02*
X613363Y574744D01*
G01X613349Y579759D02*
X613330Y579764D01*
G01X613363Y579744D02*
X613349Y579759D01*
G01X613369Y579724D02*
X613363Y579744D01*
G01X613349Y584759D02*
X613330Y584764D01*
G01X613363Y584744D02*
X613349Y584759D01*
G01X613369Y584724D02*
X613363Y584744D01*
G01X613349Y589759D02*
X613330Y589764D01*
G01X613363Y589744D02*
X613349Y589759D01*
G01X613369Y589724D02*
X613363Y589744D01*
G01X613349Y594759D02*
X613330Y594764D01*
G01X613363Y594744D02*
X613349Y594759D01*
G01X613369Y594724D02*
X613363Y594744D01*
G01X613349Y599759D02*
X613330Y599764D01*
G01X613363Y599744D02*
X613349Y599759D01*
G01X613369Y599724D02*
X613363Y599744D01*
G01X613349Y604759D02*
X613330Y604764D01*
G01X613363Y604744D02*
X613349Y604759D01*
G01X613369Y604724D02*
X613363Y604744D01*
G01X613349Y609759D02*
X613330Y609764D01*
G01X613363Y609744D02*
X613349Y609759D01*
G01X613369Y609724D02*
X613363Y609744D01*
G01X613349Y614759D02*
X613330Y614764D01*
G01X613363Y614744D02*
X613349Y614759D01*
G01X613369Y614724D02*
X613363Y614744D01*
G01X613349Y619759D02*
X613330Y619764D01*
G01X613363Y619744D02*
X613349Y619759D01*
G01X613369Y619724D02*
X613363Y619744D01*
G01X613349Y624759D02*
X613330Y624764D01*
G01X613363Y624744D02*
X613349Y624759D01*
G01X613369Y624724D02*
X613363Y624744D01*
G01X613349Y629759D02*
X613330Y629764D01*
G01X613363Y629744D02*
X613349Y629759D01*
G01X613369Y629724D02*
X613363Y629744D01*
G01X613354Y574755D02*
X613365Y574740D01*
G01X613329Y574764D02*
X613354Y574755D01*
G01Y579755D02*
X613365Y579740D01*
G01X613329Y579764D02*
X613354Y579755D01*
G01Y584755D02*
X613365Y584740D01*
G01X613329Y584764D02*
X613354Y584755D01*
G01Y589755D02*
X613365Y589740D01*
G01X613329Y589764D02*
X613354Y589755D01*
G01Y594755D02*
X613365Y594740D01*
G01X613329Y594764D02*
X613354Y594755D01*
G01Y599755D02*
X613365Y599740D01*
G01X613329Y599764D02*
X613354Y599755D01*
G01Y604755D02*
X613365Y604740D01*
G01X613329Y604764D02*
X613354Y604755D01*
G01Y609755D02*
X613365Y609740D01*
G01X613329Y609764D02*
X613354Y609755D01*
G01Y614755D02*
X613365Y614740D01*
G01X613329Y614764D02*
X613354Y614755D01*
G01Y619755D02*
X613365Y619740D01*
G01X613329Y619764D02*
X613354Y619755D01*
G01Y624755D02*
X613365Y624740D01*
G01X613329Y624764D02*
X613354Y624755D01*
G01Y629755D02*
X613365Y629740D01*
G01X613329Y629764D02*
X613354Y629755D01*
G01X613367Y628378D02*
X613366Y628369D01*
G01X613367Y628384D02*
Y628378D01*
G01X613369Y628386D02*
X613367Y628384D01*
G01Y623378D02*
X613366Y623369D01*
G01X613367Y623384D02*
Y623378D01*
G01X613369Y623386D02*
X613367Y623384D01*
G01Y618378D02*
X613366Y618369D01*
G01X613367Y618384D02*
Y618378D01*
G01X613369Y618386D02*
X613367Y618384D01*
G01Y613378D02*
X613366Y613369D01*
G01X613367Y613384D02*
Y613378D01*
G01X613369Y613386D02*
X613367Y613384D01*
G01Y608378D02*
X613366Y608369D01*
G01X613367Y608384D02*
Y608378D01*
G01X613369Y608386D02*
X613367Y608384D01*
G01Y603378D02*
X613366Y603369D01*
G01X613367Y603384D02*
Y603378D01*
G01X613369Y603386D02*
X613367Y603384D01*
G01Y598378D02*
X613366Y598369D01*
G01X613367Y598384D02*
Y598378D01*
G01X613369Y598386D02*
X613367Y598384D01*
G01Y593378D02*
X613366Y593369D01*
G01X613367Y593384D02*
Y593378D01*
G01X613369Y593386D02*
X613367Y593384D01*
G01Y588378D02*
X613366Y588369D01*
G01X613367Y588384D02*
Y588378D01*
G01X613369Y588386D02*
X613367Y588384D01*
G01Y583378D02*
X613366Y583369D01*
G01X613367Y583384D02*
Y583378D01*
G01X613369Y583386D02*
X613367Y583384D01*
G01Y578378D02*
X613366Y578369D01*
G01X613367Y578384D02*
Y578378D01*
G01X613369Y578386D02*
X613367Y578384D01*
G01Y573378D02*
X613366Y573369D01*
G01X613367Y573384D02*
Y573378D01*
G01X613369Y573386D02*
X613367Y573384D01*
G01X611811Y655256D02*
G03X611220Y655846I-590J0D01*
G01X604528D02*
G03X603937Y655256I-1J-590D01*
G01X606693Y654075D02*
G03Y652106I0J-985D01*
G01X609055D02*
G03Y654075I0J984D01*
G01X605315Y646161D02*
G03X604134Y644980I0J-1181D01*
G01X611614D02*
G03X610433Y646161I-1181J0D01*
G01X609764Y640886D02*
G03I-1890J0D01*
G01X618701Y654665D02*
G03X616732Y656634I-1969J0D01*
G01X599016D02*
G03X597047Y654665I0J-1969D01*
G01X610236Y640886D02*
G03I-2362J0D01*
G01X616732Y656634D02*
X599016D01*
G01X611220Y655846D02*
X604528D01*
G01X609055Y654075D02*
X606693D01*
G01Y652106D02*
X609055D01*
G01X611811Y650728D02*
X603937D01*
G01Y649154D02*
X611811D01*
G01X618701Y646201D02*
X597047D01*
G01X605315Y646161D02*
X610433D01*
G01X606693Y641476D02*
X609055D01*
G01X606693Y639783D02*
X609055D01*
G01X600394Y637815D02*
X614764D01*
G01X600394Y636437D02*
X604134D01*
G01X614764D02*
X611614D01*
G01X600394Y635571D02*
X615354D01*
G01X602165Y634075D02*
X610039D01*
G01X603346Y632894D02*
X608858D01*
G01X613366Y630256D02*
X612382D01*
G01X612383Y629764D02*
X617717D01*
G01Y629724D02*
X613369D01*
G01X617717Y628386D02*
X612383D01*
G01X612382Y627894D02*
X613366D01*
G01Y625256D02*
X612382D01*
G01X612383Y624764D02*
X617717D01*
G01Y624724D02*
X613369D01*
G01X617717Y623386D02*
X612383D01*
G01X612382Y622894D02*
X613366D01*
G01Y620256D02*
X612382D01*
G01X612383Y619764D02*
X617717D01*
G01Y619724D02*
X613369D01*
G01X617717Y618386D02*
X612383D01*
G01X612382Y617894D02*
X613366D01*
G01Y615256D02*
X612382D01*
G01X612383Y614764D02*
X617717D01*
G01Y614724D02*
X613369D01*
G01X617717Y613386D02*
X612383D01*
G01X612382Y612894D02*
X613366D01*
G01Y610256D02*
X612382D01*
G01Y629959D02*
X613337Y629961D01*
G01X613366Y628190D02*
X612382Y628189D01*
G01Y624959D02*
X613337Y624961D01*
G01X613366Y623190D02*
X612382Y623189D01*
G01Y619959D02*
X613337Y619961D01*
G01X613366Y618190D02*
X612382Y618189D01*
G01Y614959D02*
X613337Y614961D01*
G01X613366Y613190D02*
X612382Y613189D01*
G01Y609959D02*
X613337Y609961D01*
G01X612383Y609764D02*
X617717D01*
G01Y609724D02*
X613369D01*
G01X617717Y608386D02*
X612383D01*
G01X612382Y607894D02*
X613366D01*
G01Y605256D02*
X612382D01*
G01X612383Y604764D02*
X617717D01*
G01Y604724D02*
X613369D01*
G01X617717Y603386D02*
X612383D01*
G01X612382Y602894D02*
X613366D01*
G01Y600256D02*
X612382D01*
G01X612383Y599764D02*
X617717D01*
G01Y599724D02*
X613369D01*
G01X617717Y598386D02*
X612383D01*
G01X612382Y597894D02*
X613366D01*
G01Y595256D02*
X612382D01*
G01X612383Y594764D02*
X617717D01*
G01Y594724D02*
X613369D01*
G01X617717Y593386D02*
X612383D01*
G01X612382Y592894D02*
X613366D01*
G01Y590256D02*
X612382D01*
G01X612383Y589764D02*
X617717D01*
G01Y589724D02*
X613369D01*
G01X617717Y588386D02*
X612383D01*
G01X612382Y587894D02*
X613366D01*
G01Y585256D02*
X612382D01*
G01X612383Y584764D02*
X617717D01*
G01Y584724D02*
X613369D01*
G01X617717Y583386D02*
X612383D01*
G01X612382Y582894D02*
X613366D01*
G01Y580256D02*
X612382D01*
G01X612383Y579764D02*
X617717D01*
G01Y579724D02*
X613369D01*
G01X617717Y578386D02*
X612383D01*
G01X612382Y577894D02*
X613366D01*
G01Y575256D02*
X612382D01*
G01X612383Y574764D02*
X617717D01*
G01Y574724D02*
X613369D01*
G01X617717Y573386D02*
X612383D01*
G01X612382Y572894D02*
X613366D01*
G01Y608190D02*
X612382Y608189D01*
G01Y604959D02*
X613337Y604961D01*
G01X613366Y603190D02*
X612382Y603189D01*
G01Y599959D02*
X613337Y599961D01*
G01X613366Y598190D02*
X612382Y598189D01*
G01Y594959D02*
X613337Y594961D01*
G01X613366Y593190D02*
X612382Y593189D01*
G01Y589959D02*
X613337Y589961D01*
G01X613366Y588190D02*
X612382Y588189D01*
G01Y584959D02*
X613337Y584961D01*
G01X613366Y583190D02*
X612382Y583189D01*
G01Y579959D02*
X613337Y579961D01*
G01X613366Y578190D02*
X612382Y578189D01*
G01Y574959D02*
X613337Y574961D01*
G01X613366Y573190D02*
X612382Y573189D01*
G01X618701Y638917D02*
X615354Y635571D01*
G01X608858Y632894D02*
X610039Y634075D01*
G01X605389Y637815D02*
X606693Y639783D01*
G01X611365Y645706D02*
X609055Y641476D01*
G01X606693D02*
X604383Y645706D01*
G01X609055Y639783D02*
X610359Y637815D01*
G01X602165Y634075D02*
X603346Y632894D01*
G01X597047Y638917D02*
X600394Y635571D01*
G01X613366Y574738D02*
X613367Y574746D01*
G01X613366Y579738D02*
X613367Y579746D01*
G01X613366Y584738D02*
X613367Y584746D01*
G01X613366Y589738D02*
X613367Y589746D01*
G01X613366Y594738D02*
X613367Y594746D01*
G01X613366Y599738D02*
X613367Y599746D01*
G01X613366Y604738D02*
X613367Y604746D01*
G01X613366Y609738D02*
X613367Y609746D01*
G01X613366Y614738D02*
X613367Y614746D01*
G01X613366Y619738D02*
X613367Y619746D01*
G01X613366Y624738D02*
X613367Y624746D01*
G01X613366Y629738D02*
X613367Y629746D01*
G01X618701Y638917D02*
Y654665D01*
G01X617717Y628386D02*
Y629764D01*
G01Y623386D02*
Y624764D01*
G01Y618386D02*
Y619764D01*
G01Y613386D02*
Y614764D01*
G01Y608386D02*
Y609764D01*
G01Y603386D02*
Y604764D01*
G01Y598386D02*
Y599764D01*
G01Y593386D02*
Y594764D01*
G01Y588386D02*
Y589764D01*
G01Y583386D02*
Y584764D01*
G01Y578386D02*
Y579764D01*
G01Y573386D02*
Y574764D01*
G01X614547D02*
Y573386D01*
G01Y579764D02*
Y578386D01*
G01Y584764D02*
Y583386D01*
G01Y589764D02*
Y588386D01*
G01Y594764D02*
Y593386D01*
G01Y599764D02*
Y598386D01*
G01Y604764D02*
Y603386D01*
G01Y609764D02*
Y608386D01*
G01Y614764D02*
Y613386D01*
G01Y619764D02*
Y618386D01*
G01Y624764D02*
Y623386D01*
G01Y629764D02*
Y628386D01*
G01X613366Y627894D02*
Y630256D01*
G01Y622894D02*
Y625256D01*
G01Y617894D02*
Y620256D01*
G01Y612894D02*
Y615256D01*
G01Y607894D02*
Y610256D01*
G01Y602894D02*
Y605256D01*
G01Y597894D02*
Y600256D01*
G01Y592894D02*
Y595256D01*
G01Y587894D02*
Y590256D01*
G01Y582894D02*
Y585256D01*
G01Y577894D02*
Y580256D01*
G01Y572894D02*
Y575256D01*
G01X612382D02*
Y572894D01*
G01Y580256D02*
Y577894D01*
G01Y585256D02*
Y582894D01*
G01Y590256D02*
Y587894D01*
G01Y595256D02*
Y592894D01*
G01Y600256D02*
Y597894D01*
G01Y605256D02*
Y602894D01*
G01Y610256D02*
Y607894D01*
G01Y615256D02*
Y612894D01*
G01Y620256D02*
Y617894D01*
G01Y625256D02*
Y622894D01*
G01Y630256D02*
Y627894D01*
G01X611811Y649154D02*
Y655256D01*
G01X611614Y644980D02*
Y636437D01*
G01X609055Y641476D02*
Y639783D01*
G01X606693D02*
Y641476D01*
G01X604134Y636437D02*
Y644980D01*
G01X603937Y649154D02*
Y655256D01*
G01X597047Y654665D02*
Y638917D01*
G01X610358Y717468D02*
G03X644169I16906J-13531D01*
G01X637244Y730599D02*
G03X644169Y717468I37662J11471D01*
G01X637244Y730599D02*
G03X617283I-9980J-3040D01*
G01X610358Y717468D02*
G03X617283Y730599I-30737J24601D01*
G01X637244D02*
G03X617283I-9980J-3040D01*
G01X610358Y717468D02*
G03X644169I16906J-13531D01*
G01X637244Y730599D02*
G03X644169Y717468I37662J11471D01*
G01X610358D02*
G03X617283Y730599I-30737J24601D01*
G01X603937Y930650D02*
G03X604528Y930059I591J0D01*
G01X611220D02*
G03X611811Y930650I0J591D01*
G01X609055Y931831D02*
G03Y933799I0J984D01*
G01X606693D02*
G03Y931831I0J-984D01*
G01X608976Y945020D02*
G03I-1102J0D01*
G01X610433Y939744D02*
G03X611614Y940925I0J1181D01*
G01X604134D02*
G03X605315Y939744I1181J0D01*
G01X609449Y945020D02*
G03I-1575J0D01*
G01X597047Y931240D02*
G03X599016Y929272I1968J0D01*
G01X616732D02*
G03X618701Y931240I1J1968D01*
G01X610039Y951831D02*
X602165D01*
G01X615354Y950335D02*
X600394D01*
G01X611614Y949469D02*
X614764D01*
G01X604134D02*
X600394D01*
G01Y948091D02*
X614764D01*
G01X609055Y946122D02*
X606693D01*
G01X609055Y944429D02*
X606693D01*
G01X610433Y939744D02*
X605315D01*
G01X618701Y939705D02*
X597047D01*
G01X611811Y936752D02*
X603937D01*
G01Y935177D02*
X611811D01*
G01X609055Y933799D02*
X606693D01*
G01Y931831D02*
X609055D01*
G01X611220Y930059D02*
X604528D01*
G01X616732Y929272D02*
X599016D01*
G01X615354Y950335D02*
X618701Y946988D01*
G01X608858Y953012D02*
X610039Y951831D01*
G01X609055Y944429D02*
X611365Y940200D01*
G01X606693Y946122D02*
X605389Y948091D01*
G01X603346Y953012D02*
X602165Y951831D01*
G01X600394Y950335D02*
X597047Y946988D01*
G01X610359Y948091D02*
X609055Y946122D01*
G01X618701Y931240D02*
Y946988D01*
G01X615354Y1088327D02*
Y950335D01*
G01X614764Y1090571D02*
Y948091D01*
G01X611811Y936752D02*
Y930650D01*
G01X611614Y949469D02*
Y940925D01*
G01X610039Y988287D02*
Y951831D01*
G01X609055Y946122D02*
Y944429D01*
G01X606693D02*
Y946122D01*
G01X604134Y940925D02*
Y949469D01*
G01X603937Y936752D02*
Y930650D01*
G01X602165Y951831D02*
Y1086831D01*
G01X600394Y987126D02*
Y948091D01*
G01X597047Y946988D02*
Y931240D01*
G01X604383Y940200D02*
X606693Y944429D01*
G01X598970Y1009361D02*
X598994Y1009370D01*
G01X598959Y1009347D02*
X598970Y1009361D01*
G01X598957Y1009340D02*
X598959Y1009347D01*
G01X598970Y1006212D02*
X598994Y1006220D01*
G01X598959Y1006197D02*
X598970Y1006212D01*
G01X598957Y1006191D02*
X598959Y1006197D01*
G01X598970Y1003062D02*
X598994Y1003071D01*
G01X598959Y1003048D02*
X598970Y1003062D01*
G01X598957Y1003041D02*
X598959Y1003048D01*
G01X598970Y999913D02*
X598994Y999921D01*
G01X598959Y999898D02*
X598970Y999913D01*
G01X598957Y999891D02*
X598959Y999898D01*
G01X598970Y996763D02*
X598994Y996772D01*
G01X598959Y996748D02*
X598970Y996763D01*
G01X598957Y996742D02*
X598959Y996748D01*
G01X598970Y993613D02*
X598994Y993622D01*
G01X598959Y993599D02*
X598970Y993613D01*
G01X598957Y993592D02*
X598959Y993599D01*
G01X598970Y990464D02*
X598994Y990472D01*
G01X598959Y990449D02*
X598970Y990464D01*
G01X598957Y990443D02*
X598959Y990449D01*
G01X599941Y1009337D02*
Y1009344D01*
G01Y1009332D02*
Y1009337D01*
G01X599940Y1009331D02*
X599941Y1009332D01*
G01Y1006187D02*
Y1006194D01*
G01Y1006183D02*
Y1006187D01*
G01X599940Y1006181D02*
X599941Y1006183D01*
G01Y1003038D02*
Y1003045D01*
G01Y1003033D02*
Y1003038D01*
G01X599940Y1003031D02*
X599941Y1003033D01*
G01Y999888D02*
Y999895D01*
G01Y999883D02*
Y999888D01*
G01X599940Y999882D02*
X599941Y999883D01*
G01Y996739D02*
Y996746D01*
G01Y996734D02*
Y996739D01*
G01X599940Y996732D02*
X599941Y996734D01*
G01Y993589D02*
Y993596D01*
G01Y993584D02*
Y993589D01*
G01X599940Y993583D02*
X599941Y993584D01*
G01Y990439D02*
Y990446D01*
G01Y990435D02*
Y990439D01*
G01X599940Y990433D02*
X599941Y990435D01*
G01X598956Y998774D02*
X598957Y998766D01*
G01X598956Y998778D02*
Y998774D01*
G01X598954Y998775D02*
X598956Y998778D01*
G01Y992474D02*
X598957Y992467D01*
G01X598956Y992479D02*
Y992474D01*
G01X598954Y992477D02*
X598956Y992479D01*
G01X599902Y1009375D02*
Y1009381D01*
G01X599901Y1009371D02*
X599902Y1009375D01*
G01X599900Y1009370D02*
X599901Y1009371D01*
G01X599902Y1006226D02*
Y1006231D01*
G01X599901Y1006222D02*
X599902Y1006226D01*
G01X599900Y1006220D02*
X599901Y1006222D01*
G01X599902Y1003076D02*
Y1003082D01*
G01X599901Y1003072D02*
X599902Y1003076D01*
G01X599900Y1003071D02*
X599901Y1003072D01*
G01X599902Y999926D02*
Y999932D01*
G01X599901Y999922D02*
X599902Y999926D01*
G01X599900Y999921D02*
X599901Y999922D01*
G01X599902Y996777D02*
Y996783D01*
G01X599901Y996773D02*
X599902Y996777D01*
G01X599900Y996772D02*
X599901Y996773D01*
G01X599902Y993627D02*
Y993633D01*
G01X599901Y993623D02*
X599902Y993627D01*
G01X599900Y993622D02*
X599901Y993623D01*
G01X599902Y990478D02*
Y990483D01*
G01X599901Y990474D02*
X599902Y990478D01*
G01X599900Y990472D02*
X599901Y990474D01*
G01X613367Y1046134D02*
X613366Y1046125D01*
G01X613367Y1046140D02*
Y1046134D01*
G01X613369Y1046142D02*
X613367Y1046140D01*
G01Y1041134D02*
X613366Y1041125D01*
G01X613367Y1041140D02*
Y1041134D01*
G01X613369Y1041142D02*
X613367Y1041140D01*
G01Y1036134D02*
X613366Y1036125D01*
G01X613367Y1036140D02*
Y1036134D01*
G01X613369Y1036142D02*
X613367Y1036140D01*
G01Y1031134D02*
X613366Y1031125D01*
G01X613367Y1031140D02*
Y1031134D01*
G01X613369Y1031142D02*
X613367Y1031140D01*
G01Y1026134D02*
X613366Y1026125D01*
G01X613367Y1026140D02*
Y1026134D01*
G01X613369Y1026142D02*
X613367Y1026140D01*
G01Y1021134D02*
X613366Y1021125D01*
G01X613367Y1021140D02*
Y1021134D01*
G01X613369Y1021142D02*
X613367Y1021140D01*
G01Y1016134D02*
X613366Y1016125D01*
G01X613367Y1016140D02*
Y1016134D01*
G01X613369Y1016142D02*
X613367Y1016140D01*
G01Y1011134D02*
X613366Y1011125D01*
G01X613367Y1011140D02*
Y1011134D01*
G01X613369Y1011142D02*
X613367Y1011140D01*
G01Y986134D02*
X613366Y986125D01*
G01X613367Y986140D02*
Y986134D01*
G01X613369Y986142D02*
X613367Y986140D01*
G01Y981134D02*
X613366Y981125D01*
G01X613367Y981140D02*
Y981134D01*
G01X613369Y981142D02*
X613367Y981140D01*
G01Y976134D02*
X613366Y976125D01*
G01X613367Y976140D02*
Y976134D01*
G01X613369Y976142D02*
X613367Y976140D01*
G01Y971134D02*
X613366Y971125D01*
G01X613367Y971140D02*
Y971134D01*
G01X613369Y971142D02*
X613367Y971140D01*
G01Y966134D02*
X613366Y966125D01*
G01X613367Y966140D02*
Y966134D01*
G01X613369Y966142D02*
X613367Y966140D01*
G01Y961134D02*
X613366Y961125D01*
G01X613367Y961140D02*
Y961134D01*
G01X613369Y961142D02*
X613367Y961140D01*
G01X598956Y1009337D02*
X598957Y1009344D01*
G01X598956Y1009332D02*
Y1009337D01*
G01X598954Y1009331D02*
X598956Y1009332D01*
G01Y1006187D02*
X598957Y1006194D01*
G01X598956Y1006183D02*
Y1006187D01*
G01X598954Y1006181D02*
X598956Y1006183D01*
G01Y1003037D02*
X598957Y1003045D01*
G01X598956Y1003033D02*
Y1003037D01*
G01X598954Y1003031D02*
X598956Y1003033D01*
G01Y999888D02*
X598957Y999895D01*
G01X598956Y999883D02*
Y999888D01*
G01X598954Y999882D02*
X598956Y999883D01*
G01Y996738D02*
X598957Y996746D01*
G01X598956Y996734D02*
Y996738D01*
G01X598954Y996732D02*
X598956Y996734D01*
G01Y993589D02*
X598957Y993596D01*
G01X598956Y993584D02*
Y993589D01*
G01X598954Y993583D02*
X598956Y993584D01*
G01Y990439D02*
X598957Y990446D01*
G01X598956Y990435D02*
Y990439D01*
G01X598954Y990433D02*
X598956Y990435D01*
G01X599939Y1008202D02*
X599941Y1008215D01*
G01X599932Y1008191D02*
X599939Y1008202D01*
G01X599922Y1008183D02*
X599932Y1008191D01*
G01X599939Y1001903D02*
X599941Y1001915D01*
G01X599932Y1001892D02*
X599939Y1001903D01*
G01X599922Y1001884D02*
X599932Y1001892D01*
G01X599939Y998754D02*
X599941Y998766D01*
G01X599932Y998742D02*
X599939Y998754D01*
G01X599922Y998734D02*
X599932Y998742D01*
G01X599939Y995604D02*
X599941Y995616D01*
G01X599932Y995593D02*
X599939Y995604D01*
G01X599922Y995585D02*
X599932Y995593D01*
G01X599939Y992454D02*
X599941Y992467D01*
G01X599932Y992443D02*
X599939Y992454D01*
G01X599922Y992435D02*
X599932Y992443D01*
G01X599939Y989305D02*
X599941Y989317D01*
G01X599932Y989293D02*
X599939Y989305D01*
G01X599922Y989285D02*
X599932Y989293D01*
G01X598995Y1009375D02*
Y1009381D01*
G01Y1009371D02*
Y1009375D01*
G01X598994Y1009370D02*
X598995Y1009371D01*
G01Y1006225D02*
Y1006231D01*
G01Y1006222D02*
Y1006225D01*
G01X598994Y1006220D02*
X598995Y1006222D01*
G01Y1003076D02*
Y1003082D01*
G01Y1003072D02*
Y1003076D01*
G01X598994Y1003071D02*
X598995Y1003072D01*
G01Y999926D02*
Y999932D01*
G01Y999922D02*
Y999926D01*
G01X598994Y999921D02*
X598995Y999922D01*
G01Y996776D02*
Y996783D01*
G01Y996773D02*
Y996776D01*
G01X598994Y996772D02*
X598995Y996773D01*
G01Y993627D02*
Y993633D01*
G01Y993623D02*
Y993627D01*
G01X598994Y993622D02*
X598995Y993623D01*
G01X598957Y1009350D02*
Y1009344D01*
G01X598959Y1009357D02*
X598957Y1009350D01*
G01X598962Y1009363D02*
X598959Y1009357D01*
G01X598966Y1009368D02*
X598962Y1009363D01*
G01X598970Y1009372D02*
X598966Y1009368D01*
G01X598976Y1009376D02*
X598970Y1009372D01*
G01X598957Y1006201D02*
Y1006194D01*
G01X598959Y1006207D02*
X598957Y1006201D01*
G01X598962Y1006213D02*
X598959Y1006207D01*
G01X598966Y1006218D02*
X598962Y1006213D01*
G01X598970Y1006223D02*
X598966Y1006218D01*
G01X598976Y1006226D02*
X598970Y1006223D01*
G01X598957Y1003051D02*
Y1003045D01*
G01X598959Y1003057D02*
X598957Y1003051D01*
G01X598962Y1003063D02*
X598959Y1003057D01*
G01X598966Y1003069D02*
X598962Y1003063D01*
G01X598970Y1003073D02*
X598966Y1003069D01*
G01X598976Y1003077D02*
X598970Y1003073D01*
G01X598957Y999902D02*
Y999895D01*
G01X598959Y999908D02*
X598957Y999902D01*
G01X598962Y999914D02*
X598959Y999908D01*
G01X598966Y999919D02*
X598962Y999914D01*
G01X598970Y999924D02*
X598966Y999919D01*
G01X598976Y999927D02*
X598970Y999924D01*
G01X598957Y996752D02*
Y996746D01*
G01X598959Y996758D02*
X598957Y996752D01*
G01X598962Y996764D02*
X598959Y996758D01*
G01X598966Y996769D02*
X598962Y996764D01*
G01X598970Y996774D02*
X598966Y996769D01*
G01X598976Y996778D02*
X598970Y996774D01*
G01X613333Y957618D02*
X613337Y957717D01*
G01X613328Y957546D02*
X613333Y957618D01*
G01X613330Y957520D02*
X613328Y957546D01*
G01X613333Y962618D02*
X613337Y962717D01*
G01X613328Y962546D02*
X613333Y962618D01*
G01X613330Y962520D02*
X613328Y962546D01*
G01X613333Y967618D02*
X613337Y967717D01*
G01X613328Y967546D02*
X613333Y967618D01*
G01X613330Y967520D02*
X613328Y967546D01*
G01X613333Y972618D02*
X613337Y972717D01*
G01X613328Y972546D02*
X613333Y972618D01*
G01X613330Y972520D02*
X613328Y972546D01*
G01X613333Y977618D02*
X613337Y977717D01*
G01X613328Y977546D02*
X613333Y977618D01*
G01X613330Y977520D02*
X613328Y977546D01*
G01X613333Y982618D02*
X613337Y982717D01*
G01X613328Y982546D02*
X613333Y982618D01*
G01X613330Y982520D02*
X613328Y982546D01*
G01X613333Y987618D02*
X613337Y987717D01*
G01X613328Y987546D02*
X613333Y987618D01*
G01X613330Y987520D02*
X613328Y987546D01*
G01X613333Y1012618D02*
X613337Y1012717D01*
G01X613328Y1012546D02*
X613333Y1012618D01*
G01X613330Y1012520D02*
X613328Y1012546D01*
G01X613333Y1017618D02*
X613337Y1017717D01*
G01X613328Y1017546D02*
X613333Y1017618D01*
G01X613330Y1017520D02*
X613328Y1017546D01*
G01X613333Y1022618D02*
X613337Y1022717D01*
G01X613328Y1022546D02*
X613333Y1022618D01*
G01X613330Y1022520D02*
X613328Y1022546D01*
G01X613333Y1027618D02*
X613337Y1027717D01*
G01X613328Y1027546D02*
X613333Y1027618D01*
G01X613330Y1027520D02*
X613328Y1027546D01*
G01X613333Y1032618D02*
X613337Y1032717D01*
G01X613328Y1032546D02*
X613333Y1032618D01*
G01X613330Y1032520D02*
X613328Y1032546D01*
G01X613333Y1037618D02*
X613337Y1037717D01*
G01X613328Y1037546D02*
X613333Y1037618D01*
G01X613330Y1037520D02*
X613328Y1037546D01*
G01X613333Y1042618D02*
X613337Y1042717D01*
G01X613328Y1042546D02*
X613333Y1042618D01*
G01X613330Y1042520D02*
X613328Y1042546D01*
G01X598956Y1001923D02*
X598957Y1001916D01*
G01X598956Y1001928D02*
Y1001923D01*
G01Y1001918D02*
Y1001928D01*
G01X598997Y1009554D02*
X598996Y1009567D01*
G01X598994Y1009541D02*
X598997Y1009554D01*
G01X598994Y1009528D02*
Y1009541D01*
G01X598997Y1006405D02*
X598996Y1006417D01*
G01X598994Y1006392D02*
X598997Y1006405D01*
G01X598994Y1006378D02*
Y1006392D01*
G01X598997Y1003255D02*
X598996Y1003268D01*
G01X598994Y1003242D02*
X598997Y1003255D01*
G01X598994Y1003228D02*
Y1003242D01*
G01X598997Y1000106D02*
X598996Y1000118D01*
G01X598994Y1000093D02*
X598997Y1000106D01*
G01X598994Y1000079D02*
Y1000093D01*
G01X598997Y996956D02*
X598996Y996969D01*
G01X598994Y996943D02*
X598997Y996956D01*
G01X598994Y996929D02*
Y996943D01*
G01X598997Y993806D02*
X598996Y993819D01*
G01X598994Y993793D02*
X598997Y993806D01*
G01X598994Y993780D02*
Y993793D01*
G01X598997Y990657D02*
X598996Y990669D01*
G01X598994Y990644D02*
X598997Y990657D01*
G01X598994Y990630D02*
Y990644D01*
G01X612383Y1046140D02*
Y1046142D01*
G01X612382Y1046134D02*
X612383Y1046140D01*
G01X612382Y1046126D02*
Y1046134D01*
G01X612383Y1041140D02*
Y1041142D01*
G01X612382Y1041134D02*
X612383Y1041140D01*
G01X612382Y1041126D02*
Y1041134D01*
G01X612383Y1036140D02*
Y1036142D01*
G01X612382Y1036134D02*
X612383Y1036140D01*
G01X612382Y1036126D02*
Y1036134D01*
G01X612383Y1031140D02*
Y1031142D01*
G01X612382Y1031134D02*
X612383Y1031140D01*
G01X612382Y1031126D02*
Y1031134D01*
G01X612383Y1026140D02*
Y1026142D01*
G01X612382Y1026134D02*
X612383Y1026140D01*
G01X612382Y1026126D02*
Y1026134D01*
G01X612383Y1021140D02*
Y1021142D01*
G01X612382Y1021134D02*
X612383Y1021140D01*
G01X612382Y1021126D02*
Y1021134D01*
G01X612383Y1016140D02*
Y1016142D01*
G01X612382Y1016134D02*
X612383Y1016140D01*
G01X612382Y1016126D02*
Y1016134D01*
G01X612383Y1011140D02*
Y1011142D01*
G01X612382Y1011134D02*
X612383Y1011140D01*
G01X612382Y1011126D02*
Y1011134D01*
G01X612383Y986140D02*
Y986142D01*
G01X612382Y986134D02*
X612383Y986140D01*
G01X612382Y986126D02*
Y986134D01*
G01X612383Y981140D02*
Y981142D01*
G01X612382Y981134D02*
X612383Y981140D01*
G01X612382Y981126D02*
Y981134D01*
G01X612383Y976140D02*
Y976142D01*
G01X612382Y976134D02*
X612383Y976140D01*
G01X612382Y976126D02*
Y976134D01*
G01X612383Y971140D02*
Y971142D01*
G01X612382Y971134D02*
X612383Y971140D01*
G01X612382Y971126D02*
Y971134D01*
G01X612383Y966140D02*
Y966142D01*
G01X612382Y966134D02*
X612383Y966140D01*
G01X612382Y966126D02*
Y966134D01*
G01X612383Y961140D02*
Y961142D01*
G01X612382Y961134D02*
X612383Y961140D01*
G01X612382Y961126D02*
Y961134D01*
G01X612383Y956140D02*
Y956142D01*
G01X612382Y956134D02*
X612383Y956140D01*
G01X612382Y956126D02*
Y956134D01*
G01X598956Y1008222D02*
X598957Y1008215D01*
G01X598956Y1008227D02*
Y1008222D01*
G01Y1008219D02*
Y1008227D01*
G01X598994Y1008017D02*
X598993Y1008031D01*
G01X598997Y1008005D02*
X598994Y1008017D01*
G01X598996Y1007992D02*
X598997Y1008005D01*
G01X598994Y1004868D02*
X598993Y1004881D01*
G01X598997Y1004855D02*
X598994Y1004868D01*
G01X598996Y1004843D02*
X598997Y1004855D01*
G01X598994Y1001718D02*
X598993Y1001732D01*
G01X598997Y1001706D02*
X598994Y1001718D01*
G01X598996Y1001693D02*
X598997Y1001706D01*
G01X598994Y998569D02*
X598993Y998582D01*
G01X598997Y998556D02*
X598994Y998569D01*
G01X598996Y998543D02*
X598997Y998556D01*
G01X598994Y995419D02*
X598993Y995433D01*
G01X598997Y995406D02*
X598994Y995419D01*
G01X598996Y995394D02*
X598997Y995406D01*
G01X598994Y992269D02*
X598993Y992283D01*
G01X598997Y992257D02*
X598994Y992269D01*
G01X598996Y992244D02*
X598997Y992257D01*
G01X598994Y989120D02*
X598993Y989133D01*
G01X598997Y989107D02*
X598994Y989120D01*
G01X598996Y989094D02*
X598997Y989107D01*
G01X599904Y1009541D02*
X599905Y1009528D01*
G01X599901Y1009554D02*
X599904Y1009541D01*
G01X599902Y1009567D02*
X599901Y1009554D01*
G01X599904Y1006392D02*
X599905Y1006378D01*
G01X599901Y1006405D02*
X599904Y1006392D01*
G01X599902Y1006417D02*
X599901Y1006405D01*
G01X599904Y1003242D02*
X599905Y1003228D01*
G01X599901Y1003255D02*
X599904Y1003242D01*
G01X599902Y1003268D02*
X599901Y1003255D01*
G01X599904Y1000093D02*
X599905Y1000079D01*
G01X599901Y1000106D02*
X599904Y1000093D01*
G01X599902Y1000118D02*
X599901Y1000106D01*
G01X599904Y996943D02*
X599905Y996929D01*
G01X599901Y996956D02*
X599904Y996943D01*
G01X599902Y996969D02*
X599901Y996956D01*
G01X599904Y993793D02*
X599905Y993780D01*
G01X599901Y993806D02*
X599904Y993793D01*
G01X599902Y993819D02*
X599901Y993806D01*
G01X599904Y990644D02*
X599905Y990630D01*
G01X599901Y990657D02*
X599904Y990644D01*
G01X599902Y990669D02*
X599901Y990657D01*
G01X598956Y995624D02*
X598957Y995617D01*
G01X598956Y995628D02*
Y995624D01*
G01X598955Y995621D02*
X598956Y995628D01*
G01Y1005073D02*
X598957Y1005065D01*
G01X598956Y1005077D02*
Y1005073D01*
G01X598955Y1005070D02*
X598956Y1005077D01*
G01X599901Y1008005D02*
X599902Y1007992D01*
G01X599904Y1008017D02*
X599901Y1008005D01*
G01X599905Y1008031D02*
X599904Y1008017D01*
G01X599901Y1004855D02*
X599902Y1004843D01*
G01X599904Y1004868D02*
X599901Y1004855D01*
G01X599905Y1004881D02*
X599904Y1004868D01*
G01X599901Y1001706D02*
X599902Y1001693D01*
G01X599904Y1001718D02*
X599901Y1001706D01*
G01X599905Y1001732D02*
X599904Y1001718D01*
G01X599901Y998556D02*
X599902Y998543D01*
G01X599904Y998569D02*
X599901Y998556D01*
G01X599905Y998582D02*
X599904Y998569D01*
G01X599901Y995406D02*
X599902Y995394D01*
G01X599904Y995419D02*
X599901Y995406D01*
G01X599905Y995433D02*
X599904Y995419D01*
G01X599901Y992257D02*
X599902Y992244D01*
G01X599904Y992269D02*
X599901Y992257D01*
G01X599905Y992283D02*
X599904Y992269D01*
G01X599901Y989107D02*
X599902Y989094D01*
G01X599904Y989120D02*
X599901Y989107D01*
G01X599905Y989133D02*
X599904Y989120D01*
G01X598956Y989325D02*
X598957Y989317D01*
G01X598956Y989329D02*
Y989325D01*
G01X598955Y989323D02*
X598956Y989329D01*
G01X613367Y956134D02*
X613366Y956125D01*
G01X613367Y956140D02*
Y956134D01*
G01X613369Y956142D02*
X613367Y956140D01*
G01X598995Y990477D02*
Y990483D01*
G01Y990474D02*
Y990477D01*
G01X598994Y990472D02*
X598995Y990474D01*
G01X598957Y993602D02*
Y993596D01*
G01X598959Y993609D02*
X598957Y993602D01*
G01X598962Y993615D02*
X598959Y993609D01*
G01X598966Y993620D02*
X598962Y993615D01*
G01X598970Y993624D02*
X598966Y993620D01*
G01X598976Y993628D02*
X598970Y993624D01*
G01X598957Y990453D02*
Y990446D01*
G01X598959Y990459D02*
X598957Y990453D01*
G01X598962Y990465D02*
X598959Y990459D01*
G01X598966Y990470D02*
X598962Y990465D01*
G01X598970Y990475D02*
X598966Y990470D01*
G01X598976Y990478D02*
X598970Y990475D01*
G01X599912Y1008191D02*
X599900Y1008189D01*
G01X599922Y1008196D02*
X599912Y1008191D01*
G01Y1005041D02*
X599900Y1005039D01*
G01X599922Y1005046D02*
X599912Y1005041D01*
G01Y1001892D02*
X599900Y1001890D01*
G01X599922Y1001896D02*
X599912Y1001892D01*
G01Y998742D02*
X599900Y998740D01*
G01X599922Y998747D02*
X599912Y998742D01*
G01Y995593D02*
X599900Y995591D01*
G01X599922Y995597D02*
X599912Y995593D01*
G01Y992443D02*
X599900Y992441D01*
G01X599922Y992448D02*
X599912Y992443D01*
G01Y989293D02*
X599900Y989291D01*
G01X599922Y989298D02*
X599912Y989293D01*
G01X599933Y996754D02*
X599926Y996762D01*
G01X599938Y996743D02*
X599933Y996754D01*
G01X599940Y996732D02*
X599938Y996743D01*
G01X599933Y990454D02*
X599926Y990463D01*
G01X599938Y990444D02*
X599933Y990454D01*
G01X599940Y990433D02*
X599938Y990444D01*
G01X599933Y993604D02*
X599926Y993612D01*
G01X599938Y993594D02*
X599933Y993604D01*
G01X599940Y993583D02*
X599938Y993594D01*
G01X599933Y999903D02*
X599926Y999911D01*
G01X599938Y999893D02*
X599933Y999903D01*
G01X599940Y999882D02*
X599938Y999893D01*
G01X599933Y1003053D02*
X599926Y1003061D01*
G01X599938Y1003043D02*
X599933Y1003053D01*
G01X599940Y1003031D02*
X599938Y1003043D01*
G01X599933Y1006202D02*
X599926Y1006211D01*
G01X599938Y1006192D02*
X599933Y1006202D01*
G01X599940Y1006181D02*
X599938Y1006192D01*
G01X599933Y1009352D02*
X599926Y1009360D01*
G01X599938Y1009342D02*
X599933Y1009352D01*
G01X599940Y1009331D02*
X599938Y1009342D01*
G01X599902Y989286D02*
Y989280D01*
G01X599901Y989290D02*
X599902Y989286D01*
G01X599900Y989291D02*
X599901Y989290D01*
G01X599902Y992436D02*
Y992430D01*
G01X599901Y992439D02*
X599902Y992436D01*
G01X599900Y992441D02*
X599901Y992439D01*
G01X612382Y957527D02*
Y957536D01*
G01X612383Y957521D02*
X612382Y957527D01*
G01X612383Y957520D02*
Y957521D01*
G01X612382Y962527D02*
Y962536D01*
G01X612383Y962521D02*
X612382Y962527D01*
G01X612383Y962520D02*
Y962521D01*
G01X612382Y967527D02*
Y967536D01*
G01X612383Y967521D02*
X612382Y967527D01*
G01X612383Y967520D02*
Y967521D01*
G01X612382Y972527D02*
Y972536D01*
G01X612383Y972521D02*
X612382Y972527D01*
G01X612383Y972520D02*
Y972521D01*
G01X612382Y977527D02*
Y977536D01*
G01X612383Y977521D02*
X612382Y977527D01*
G01X612383Y977520D02*
Y977521D01*
G01X612382Y982527D02*
Y982536D01*
G01X612383Y982521D02*
X612382Y982527D01*
G01X612383Y982520D02*
Y982521D01*
G01X613358Y957663D02*
X613366Y957637D01*
G01X613348Y957690D02*
X613358Y957663D01*
G01X613337Y957717D02*
X613348Y957690D01*
G01X613358Y962663D02*
X613366Y962637D01*
G01X613348Y962690D02*
X613358Y962663D01*
G01X613337Y962717D02*
X613348Y962690D01*
G01X613358Y967663D02*
X613366Y967637D01*
G01X613348Y967690D02*
X613358Y967663D01*
G01X613337Y967717D02*
X613348Y967690D01*
G01X613358Y972663D02*
X613366Y972637D01*
G01X613348Y972690D02*
X613358Y972663D01*
G01X613337Y972717D02*
X613348Y972690D01*
G01X613358Y977663D02*
X613366Y977637D01*
G01X613348Y977690D02*
X613358Y977663D01*
G01X613337Y977717D02*
X613348Y977690D01*
G01X613358Y982663D02*
X613366Y982637D01*
G01X613348Y982690D02*
X613358Y982663D01*
G01X613337Y982717D02*
X613348Y982690D01*
G01X613358Y987663D02*
X613366Y987637D01*
G01X613348Y987690D02*
X613358Y987663D01*
G01X613337Y987717D02*
X613348Y987690D01*
G01X598974Y998745D02*
X598994Y998740D01*
G01X598961Y998757D02*
X598974Y998745D01*
G01X598954Y998775D02*
X598961Y998757D01*
G01X613349Y957515D02*
X613330Y957520D01*
G01X613363Y957500D02*
X613349Y957515D01*
G01X613369Y957480D02*
X613363Y957500D01*
G01X613349Y962515D02*
X613330Y962520D01*
G01X613363Y962500D02*
X613349Y962515D01*
G01X613369Y962480D02*
X613363Y962500D01*
G01X613349Y967515D02*
X613330Y967520D01*
G01X613363Y967500D02*
X613349Y967515D01*
G01X613369Y967480D02*
X613363Y967500D01*
G01X613349Y972515D02*
X613330Y972520D01*
G01X613363Y972500D02*
X613349Y972515D01*
G01X613369Y972480D02*
X613363Y972500D01*
G01X613349Y977515D02*
X613330Y977520D01*
G01X613363Y977500D02*
X613349Y977515D01*
G01X613369Y977480D02*
X613363Y977500D01*
G01X613349Y982515D02*
X613330Y982520D01*
G01X613363Y982500D02*
X613349Y982515D01*
G01X613369Y982480D02*
X613363Y982500D01*
G01X613349Y987515D02*
X613330Y987520D01*
G01X613363Y987500D02*
X613349Y987515D01*
G01X613369Y987480D02*
X613363Y987500D01*
G01X613349Y1012515D02*
X613330Y1012520D01*
G01X613363Y1012500D02*
X613349Y1012515D01*
G01X613369Y1012480D02*
X613363Y1012500D01*
G01X613349Y1017515D02*
X613330Y1017520D01*
G01X613363Y1017500D02*
X613349Y1017515D01*
G01X613369Y1017480D02*
X613363Y1017500D01*
G01X613349Y1022515D02*
X613330Y1022520D01*
G01X613363Y1022500D02*
X613349Y1022515D01*
G01X613369Y1022480D02*
X613363Y1022500D01*
G01X613349Y1027515D02*
X613330Y1027520D01*
G01X613363Y1027500D02*
X613349Y1027515D01*
G01X613369Y1027480D02*
X613363Y1027500D01*
G01X613349Y1032515D02*
X613330Y1032520D01*
G01X613363Y1032500D02*
X613349Y1032515D01*
G01X613369Y1032480D02*
X613363Y1032500D01*
G01X613349Y1037515D02*
X613330Y1037520D01*
G01X613363Y1037500D02*
X613349Y1037515D01*
G01X613369Y1037480D02*
X613363Y1037500D01*
G01X613349Y1042515D02*
X613330Y1042520D01*
G01X613363Y1042500D02*
X613349Y1042515D01*
G01X613369Y1042480D02*
X613363Y1042500D01*
G01X613349Y1047515D02*
X613330Y1047520D01*
G01X613363Y1047500D02*
X613349Y1047515D01*
G01X613369Y1047480D02*
X613363Y1047500D01*
G01X613367Y957487D02*
X613366Y957494D01*
G01X613367Y957482D02*
Y957487D01*
G01X613369Y957480D02*
X613367Y957482D01*
G01Y962487D02*
X613366Y962494D01*
G01X613367Y962482D02*
Y962487D01*
G01X613369Y962480D02*
X613367Y962482D01*
G01Y967487D02*
X613366Y967494D01*
G01X613367Y967482D02*
Y967487D01*
G01X613369Y967480D02*
X613367Y967482D01*
G01Y972487D02*
X613366Y972494D01*
G01X613367Y972482D02*
Y972487D01*
G01X613369Y972480D02*
X613367Y972482D01*
G01X598980Y992443D02*
X598994Y992441D01*
G01X598968Y992450D02*
X598980Y992443D01*
G01X598956Y992469D02*
X598968Y992450D01*
G01X598980Y1001892D02*
X598994Y1001890D01*
G01X598968Y1001900D02*
X598980Y1001892D01*
G01X598956Y1001918D02*
X598968Y1001900D01*
G01X598979Y995593D02*
X598994Y995591D01*
G01X598967Y995601D02*
X598979Y995593D01*
G01X598955Y995621D02*
X598967Y995601D01*
G01X598979Y1005042D02*
X598994Y1005039D01*
G01X598967Y1005050D02*
X598979Y1005042D01*
G01X598955Y1005070D02*
X598967Y1005050D01*
G01X599941Y989325D02*
Y989317D01*
G01X599940Y989329D02*
X599941Y989325D01*
G01X599939Y989331D02*
X599940Y989329D01*
G01X599941Y992474D02*
Y992467D01*
G01X599940Y992479D02*
X599941Y992474D01*
G01X599939Y992480D02*
X599940Y992479D01*
G01X599941Y995624D02*
Y995616D01*
G01X599940Y995628D02*
X599941Y995624D01*
G01X599939Y995630D02*
X599940Y995628D01*
G01X599941Y998774D02*
Y998766D01*
G01X599940Y998778D02*
X599941Y998774D01*
G01X599939Y998780D02*
X599940Y998778D01*
G01X599941Y1001923D02*
Y1001915D01*
G01X599940Y1001928D02*
X599941Y1001923D01*
G01X599939Y1001929D02*
X599940Y1001928D01*
G01X599941Y1005073D02*
Y1005065D01*
G01X599940Y1005077D02*
X599941Y1005073D01*
G01X599939Y1005079D02*
X599940Y1005077D01*
G01X599941Y1008222D02*
Y1008215D01*
G01X599940Y1008227D02*
X599941Y1008222D01*
G01X599939Y1008228D02*
X599940Y1008227D01*
G01X598979Y1008192D02*
X598994Y1008189D01*
G01X598967Y1008200D02*
X598979Y1008192D01*
G01X598955Y1008220D02*
X598967Y1008200D01*
G01X598979Y989294D02*
X598994Y989291D01*
G01X598966Y989303D02*
X598979Y989294D01*
G01X598955Y989323D02*
X598966Y989303D01*
G01X599940Y990453D02*
X599941Y990446D01*
G01X599939Y990459D02*
X599940Y990453D01*
G01X599935Y990465D02*
X599939Y990459D01*
G01X599940Y993603D02*
X599941Y993596D01*
G01X599939Y993609D02*
X599940Y993603D01*
G01X599935Y993615D02*
X599939Y993609D01*
G01X599940Y996752D02*
X599941Y996746D01*
G01X599939Y996759D02*
X599940Y996752D01*
G01X599935Y996765D02*
X599939Y996759D01*
G01X599940Y999902D02*
X599941Y999895D01*
G01X599939Y999908D02*
X599940Y999902D01*
G01X599935Y999914D02*
X599939Y999908D01*
G01X599940Y1003052D02*
X599941Y1003045D01*
G01X599939Y1003058D02*
X599940Y1003052D01*
G01X599935Y1003064D02*
X599939Y1003058D01*
G01X599940Y1006201D02*
X599941Y1006194D01*
G01X599939Y1006207D02*
X599940Y1006201D01*
G01X599935Y1006213D02*
X599939Y1006207D01*
G01X599940Y1009351D02*
X599941Y1009344D01*
G01X599939Y1009357D02*
X599940Y1009351D01*
G01X599935Y1009363D02*
X599939Y1009357D01*
G01X599902Y995585D02*
Y995579D01*
G01X599901Y995589D02*
X599902Y995585D01*
G01X599900Y995591D02*
X599901Y995589D01*
G01X599902Y998735D02*
Y998729D01*
G01X599901Y998739D02*
X599902Y998735D01*
G01X599900Y998740D02*
X599901Y998739D01*
G01X599902Y1001885D02*
Y1001878D01*
G01X599901Y1001888D02*
X599902Y1001885D01*
G01X599900Y1001890D02*
X599901Y1001888D01*
G01X599902Y1008184D02*
Y1008178D01*
G01X599901Y1008187D02*
X599902Y1008184D01*
G01X599900Y1008189D02*
X599901Y1008187D01*
G01X612382Y987527D02*
Y987536D01*
G01X612383Y987521D02*
X612382Y987527D01*
G01X612383Y987520D02*
Y987521D01*
G01X612382Y1012527D02*
Y1012536D01*
G01X612383Y1012521D02*
X612382Y1012527D01*
G01X612383Y1012520D02*
Y1012521D01*
G01X612382Y1017527D02*
Y1017536D01*
G01X612383Y1017521D02*
X612382Y1017527D01*
G01X612383Y1017520D02*
Y1017521D01*
G01X612382Y1022527D02*
Y1022536D01*
G01X612383Y1022521D02*
X612382Y1022527D01*
G01X612383Y1022520D02*
Y1022521D01*
G01X612382Y1027527D02*
Y1027536D01*
G01X612383Y1027521D02*
X612382Y1027527D01*
G01X612383Y1027520D02*
Y1027521D01*
G01X612382Y1032527D02*
Y1032536D01*
G01X612383Y1032521D02*
X612382Y1032527D01*
G01X612383Y1032520D02*
Y1032521D01*
G01X612382Y1037527D02*
Y1037536D01*
G01X612383Y1037521D02*
X612382Y1037527D01*
G01X612383Y1037520D02*
Y1037521D01*
G01X612382Y1042527D02*
Y1042536D01*
G01X612383Y1042521D02*
X612382Y1042527D01*
G01X612383Y1042520D02*
Y1042521D01*
G01X613358Y1012663D02*
X613366Y1012637D01*
G01X613348Y1012690D02*
X613358Y1012663D01*
G01X613337Y1012717D02*
X613348Y1012690D01*
G01X613358Y1017663D02*
X613366Y1017637D01*
G01X613348Y1017690D02*
X613358Y1017663D01*
G01X613337Y1017717D02*
X613348Y1017690D01*
G01X613358Y1022663D02*
X613366Y1022637D01*
G01X613348Y1022690D02*
X613358Y1022663D01*
G01X613337Y1022717D02*
X613348Y1022690D01*
G01X613358Y1027663D02*
X613366Y1027637D01*
G01X613348Y1027690D02*
X613358Y1027663D01*
G01X613337Y1027717D02*
X613348Y1027690D01*
G01X613358Y1032663D02*
X613366Y1032637D01*
G01X613348Y1032690D02*
X613358Y1032663D01*
G01X613337Y1032717D02*
X613348Y1032690D01*
G01X613358Y1037663D02*
X613366Y1037637D01*
G01X613348Y1037690D02*
X613358Y1037663D01*
G01X613337Y1037717D02*
X613348Y1037690D01*
G01X613358Y1042663D02*
X613366Y1042637D01*
G01X613348Y1042690D02*
X613358Y1042663D01*
G01X613337Y1042717D02*
X613348Y1042690D01*
G01X598996Y989286D02*
Y989280D01*
G01X598995Y989290D02*
X598996Y989286D01*
G01X598994Y989291D02*
X598995Y989290D01*
G01X613367Y977487D02*
X613366Y977494D01*
G01X613367Y977482D02*
Y977487D01*
G01X613369Y977480D02*
X613367Y977482D01*
G01Y982487D02*
X613366Y982494D01*
G01X613367Y982482D02*
Y982487D01*
G01X613369Y982480D02*
X613367Y982482D01*
G01Y987487D02*
X613366Y987494D01*
G01X613367Y987482D02*
Y987487D01*
G01X613369Y987480D02*
X613367Y987482D01*
G01Y1012487D02*
X613366Y1012494D01*
G01X613367Y1012482D02*
Y1012487D01*
G01X613369Y1012480D02*
X613367Y1012482D01*
G01Y1017487D02*
X613366Y1017494D01*
G01X613367Y1017482D02*
Y1017487D01*
G01X613369Y1017480D02*
X613367Y1017482D01*
G01Y1022487D02*
X613366Y1022494D01*
G01X613367Y1022482D02*
Y1022487D01*
G01X613369Y1022480D02*
X613367Y1022482D01*
G01Y1027487D02*
X613366Y1027494D01*
G01X613367Y1027482D02*
Y1027487D01*
G01X613369Y1027480D02*
X613367Y1027482D01*
G01Y1032487D02*
X613366Y1032494D01*
G01X613367Y1032482D02*
Y1032487D01*
G01X613369Y1032480D02*
X613367Y1032482D01*
G01Y1037487D02*
X613366Y1037494D01*
G01X613367Y1037482D02*
Y1037487D01*
G01X613369Y1037480D02*
X613367Y1037482D01*
G01Y1042487D02*
X613366Y1042494D01*
G01X613367Y1042482D02*
Y1042487D01*
G01X613369Y1042480D02*
X613367Y1042482D01*
G01Y1047487D02*
X613366Y1047494D01*
G01X613369Y1047480D02*
X613367Y1047482D01*
G01X599909Y996770D02*
X599900Y996772D01*
G01X599918Y996767D02*
X599909Y996770D01*
G01X599926Y996762D02*
X599918Y996767D01*
G01X599909Y990471D02*
X599900Y990472D01*
G01X599919Y990468D02*
X599909Y990471D01*
G01X599926Y990463D02*
X599919Y990468D01*
G01X599909Y993621D02*
X599900Y993622D01*
G01X599919Y993618D02*
X599909Y993621D01*
G01X599926Y993612D02*
X599919Y993618D01*
G01X599909Y999920D02*
X599900Y999921D01*
G01X599919Y999917D02*
X599909Y999920D01*
G01X599926Y999911D02*
X599919Y999917D01*
G01X599909Y1003070D02*
X599900Y1003071D01*
G01X599919Y1003067D02*
X599909Y1003070D01*
G01X599926Y1003061D02*
X599919Y1003067D01*
G01X599909Y1006219D02*
X599900Y1006220D01*
G01X599919Y1006216D02*
X599909Y1006219D01*
G01X599926Y1006211D02*
X599919Y1006216D01*
G01X599909Y1009369D02*
X599900Y1009370D01*
G01X599919Y1009366D02*
X599909Y1009369D01*
G01X599926Y1009360D02*
X599919Y1009366D01*
G01X598996Y992436D02*
Y992430D01*
G01X598995Y992440D02*
X598996Y992436D01*
G01X598994Y992441D02*
X598995Y992440D01*
G01X598996Y995585D02*
Y995579D01*
G01X598995Y995589D02*
X598996Y995585D01*
G01X598994Y995591D02*
X598995Y995589D01*
G01X598996Y998735D02*
Y998729D01*
G01X598995Y998739D02*
X598996Y998735D01*
G01X598994Y998740D02*
X598995Y998739D01*
G01X598996Y1001885D02*
Y1001878D01*
G01X598995Y1001889D02*
X598996Y1001885D01*
G01X598994Y1001890D02*
X598995Y1001889D01*
G01X598996Y1005034D02*
Y1005028D01*
G01X598995Y1005038D02*
X598996Y1005034D01*
G01X598994Y1005039D02*
X598995Y1005038D01*
G01X598996Y1008184D02*
Y1008178D01*
G01X598995Y1008188D02*
X598996Y1008184D01*
G01X598994Y1008189D02*
X598995Y1008188D01*
G01X613354Y957511D02*
X613365Y957496D01*
G01X613329Y957520D02*
X613354Y957511D01*
G01Y962511D02*
X613365Y962496D01*
G01X613329Y962520D02*
X613354Y962511D01*
G01Y967511D02*
X613365Y967496D01*
G01X613329Y967520D02*
X613354Y967511D01*
G01Y972511D02*
X613365Y972496D01*
G01X613329Y972520D02*
X613354Y972511D01*
G01Y977511D02*
X613365Y977496D01*
G01X613329Y977520D02*
X613354Y977511D01*
G01Y982511D02*
X613365Y982496D01*
G01X613329Y982520D02*
X613354Y982511D01*
G01X598957Y998770D02*
Y998766D01*
G01X598958Y998764D02*
X598957Y998770D01*
G01X598969Y998750D02*
X598958Y998764D01*
G01X598991Y998740D02*
X598969Y998750D01*
G01X599911Y990471D02*
X599920Y990467D01*
G01X599900Y990472D02*
X599911Y990471D01*
G01X598957Y992470D02*
Y992467D01*
G01X598958Y992464D02*
X598957Y992470D01*
G01X598970Y992449D02*
X598958Y992464D01*
G01X598995Y992441D02*
X598970Y992449D01*
G01X598957Y995620D02*
Y995616D01*
G01X598958Y995614D02*
X598957Y995620D01*
G01X598970Y995599D02*
X598958Y995614D01*
G01X598994Y995591D02*
X598970Y995599D01*
G01X598957Y1001919D02*
Y1001915D01*
G01X598958Y1001913D02*
X598957Y1001919D01*
G01X598970Y1001898D02*
X598958Y1001913D01*
G01X598994Y1001890D02*
X598970Y1001898D01*
G01X598957Y1005069D02*
Y1005065D01*
G01X598958Y1005063D02*
X598957Y1005069D01*
G01X598970Y1005048D02*
X598958Y1005063D01*
G01X598994Y1005039D02*
X598970Y1005048D01*
G01X598957Y989321D02*
Y989317D01*
G01X598958Y989315D02*
X598957Y989321D01*
G01X598970Y989300D02*
X598958Y989315D01*
G01X598994Y989291D02*
X598970Y989300D01*
G01X598957Y1008219D02*
Y1008215D01*
G01X598958Y1008213D02*
X598957Y1008219D01*
G01X598970Y1008197D02*
X598958Y1008213D01*
G01X598994Y1008189D02*
X598970Y1008197D01*
G01X613354Y987511D02*
X613365Y987496D01*
G01X613329Y987520D02*
X613354Y987511D01*
G01Y1012511D02*
X613365Y1012496D01*
G01X613329Y1012520D02*
X613354Y1012511D01*
G01Y1017511D02*
X613365Y1017496D01*
G01X613329Y1017520D02*
X613354Y1017511D01*
G01Y1022511D02*
X613365Y1022496D01*
G01X613329Y1022520D02*
X613354Y1022511D01*
G01Y1027511D02*
X613365Y1027496D01*
G01X613329Y1027520D02*
X613354Y1027511D01*
G01Y1032511D02*
X613365Y1032496D01*
G01X613329Y1032520D02*
X613354Y1032511D01*
G01Y1037511D02*
X613365Y1037496D01*
G01X613329Y1037520D02*
X613354Y1037511D01*
G01Y1042511D02*
X613365Y1042496D01*
G01X613329Y1042520D02*
X613354Y1042511D01*
G01Y1047511D02*
X613365Y1047496D01*
G01X613329Y1047520D02*
X613354Y1047511D01*
G01X599919Y989283D02*
X599922Y989285D01*
G01X599915Y989282D02*
X599919Y989283D01*
G01X599912Y989281D02*
X599915Y989282D01*
G01X599909Y989281D02*
X599912D01*
G01X599905Y989280D02*
X599909Y989281D01*
G01X599902Y989280D02*
X599905D01*
G01X598979Y990480D02*
X598976Y990478D01*
G01X598982Y990481D02*
X598979Y990480D01*
G01X598986Y990482D02*
X598982Y990481D01*
G01X598989Y990483D02*
X598986Y990482D01*
G01X598993Y990483D02*
X598989D01*
G01X598996D02*
X598993D01*
G01X599919Y992433D02*
X599922Y992435D01*
G01X599915Y992432D02*
X599919Y992433D01*
G01X599912Y992431D02*
X599915Y992432D01*
G01X599909Y992430D02*
X599912Y992431D01*
G01X599905Y992430D02*
X599909D01*
G01X599902D02*
X599905D01*
G01X598979Y993630D02*
X598976Y993628D01*
G01X598982Y993631D02*
X598979Y993630D01*
G01X598986Y993632D02*
X598982Y993631D01*
G01X598989Y993633D02*
X598986Y993632D01*
G01X598993Y993633D02*
X598989D01*
G01X598996D02*
X598993D01*
G01X599919Y995583D02*
X599922Y995585D01*
G01X599915Y995581D02*
X599919Y995583D01*
G01X599912Y995581D02*
X599915D01*
G01X599909Y995580D02*
X599912Y995581D01*
G01X599905Y995580D02*
X599909D01*
G01X599902Y995579D02*
X599905Y995580D01*
G01X598979Y996779D02*
X598976Y996778D01*
G01X598982Y996780D02*
X598979Y996779D01*
G01X598986Y996781D02*
X598982Y996780D01*
G01X598989Y996782D02*
X598986Y996781D01*
G01X598993Y996783D02*
X598989Y996782D01*
G01X598996Y996783D02*
X598993D01*
G01X599919Y998732D02*
X599922Y998734D01*
G01X599915Y998731D02*
X599919Y998732D01*
G01X599912Y998730D02*
X599915Y998731D01*
G01X599909Y998730D02*
X599912D01*
G01X599905Y998729D02*
X599909Y998730D01*
G01X599902Y998729D02*
X599905D01*
G01X598979Y999929D02*
X598976Y999927D01*
G01X598982Y999930D02*
X598979Y999929D01*
G01X598986Y999931D02*
X598982Y999930D01*
G01X598989Y999932D02*
X598986Y999931D01*
G01X598993Y999932D02*
X598989D01*
G01X598996D02*
X598993D01*
G01X599919Y1001882D02*
X599922Y1001884D01*
G01X599915Y1001881D02*
X599919Y1001882D01*
G01X599912Y1001880D02*
X599915Y1001881D01*
G01X599909Y1001879D02*
X599912Y1001880D01*
G01X599905Y1001879D02*
X599909D01*
G01X599902Y1001878D02*
X599905Y1001879D01*
G01X598979Y1003078D02*
X598976Y1003077D01*
G01X598982Y1003080D02*
X598979Y1003078D01*
G01X598986Y1003081D02*
X598982Y1003080D01*
G01X598989Y1003081D02*
X598986D01*
G01X598993Y1003082D02*
X598989Y1003081D01*
G01X598996Y1003082D02*
X598993D01*
G01X598209Y992480D02*
X597776D01*
G01X598583D02*
X598209D01*
G01Y998780D02*
X597776D01*
G01X598583D02*
X598209D01*
G01Y1001929D02*
X597776D01*
G01X598583D02*
X598209D01*
G01X599931Y990471D02*
X599935Y990465D01*
G01X599927Y990475D02*
X599931Y990471D01*
G01X599921Y990479D02*
X599927Y990475D01*
G01X599915Y990481D02*
X599921Y990479D01*
G01X599908Y990483D02*
X599915Y990481D01*
G01X599902Y990483D02*
X599908D01*
G01X599931Y993620D02*
X599935Y993615D01*
G01X599927Y993625D02*
X599931Y993620D01*
G01X599921Y993628D02*
X599927Y993625D01*
G01X599915Y993631D02*
X599921Y993628D01*
G01X599908Y993633D02*
X599915Y993631D01*
G01X599902Y993633D02*
X599908D01*
G01X599931Y996770D02*
X599935Y996765D01*
G01X599927Y996774D02*
X599931Y996770D01*
G01X599921Y996778D02*
X599927Y996774D01*
G01X599915Y996781D02*
X599921Y996778D01*
G01X599908Y996782D02*
X599915Y996781D01*
G01X599902Y996783D02*
X599908Y996782D01*
G01X599931Y999920D02*
X599935Y999914D01*
G01X599927Y999924D02*
X599931Y999920D01*
G01X599921Y999928D02*
X599927Y999924D01*
G01X599915Y999930D02*
X599921Y999928D01*
G01X599908Y999932D02*
X599915Y999930D01*
G01X599902Y999932D02*
X599908D01*
G01X599931Y1003069D02*
X599935Y1003064D01*
G01X599927Y1003074D02*
X599931Y1003069D01*
G01X599921Y1003077D02*
X599927Y1003074D01*
G01X599915Y1003080D02*
X599921Y1003077D01*
G01X599908Y1003081D02*
X599915Y1003080D01*
G01X599902Y1003082D02*
X599908Y1003081D01*
G01X599931Y1006219D02*
X599935Y1006213D01*
G01X599927Y1006223D02*
X599931Y1006219D01*
G01X599921Y1006227D02*
X599927Y1006223D01*
G01X599915Y1006230D02*
X599921Y1006227D01*
G01X599908Y1006231D02*
X599915Y1006230D01*
G01X599902Y1006231D02*
X599908D01*
G01X599931Y1009369D02*
X599935Y1009363D01*
G01X599927Y1009373D02*
X599931Y1009369D01*
G01X599921Y1009376D02*
X599927Y1009373D01*
G01X599915Y1009379D02*
X599921Y1009376D01*
G01X599908Y1009381D02*
X599915Y1009379D01*
G01X599902Y1009381D02*
X599908D01*
G01X598957Y989310D02*
Y989317D01*
G01X598960Y989303D02*
X598957Y989310D01*
G01X598963Y989296D02*
X598960Y989303D01*
G01X598968Y989291D02*
X598963Y989296D01*
G01X598974Y989286D02*
X598968Y989291D01*
G01X598981Y989283D02*
X598974Y989286D01*
G01X598989Y989281D02*
X598981Y989283D01*
G01X598996Y989280D02*
X598989Y989281D01*
G01X598957Y992459D02*
Y992467D01*
G01X598960Y992452D02*
X598957Y992459D01*
G01X598963Y992446D02*
X598960Y992452D01*
G01X598968Y992441D02*
X598963Y992446D01*
G01X598974Y992436D02*
X598968Y992441D01*
G01X598981Y992432D02*
X598974Y992436D01*
G01X598989Y992430D02*
X598981Y992432D01*
G01X598996Y992430D02*
X598989D01*
G01X598957Y995609D02*
Y995616D01*
G01X598960Y995602D02*
X598957Y995609D01*
G01X598963Y995596D02*
X598960Y995602D01*
G01X598968Y995590D02*
X598963Y995596D01*
G01X598974Y995585D02*
X598968Y995590D01*
G01X598981Y995582D02*
X598974Y995585D01*
G01X598989Y995580D02*
X598981Y995582D01*
G01X598996Y995579D02*
X598989Y995580D01*
G01X598957Y998759D02*
Y998766D01*
G01X598960Y998752D02*
X598957Y998759D01*
G01X598963Y998745D02*
X598960Y998752D01*
G01X598968Y998740D02*
X598963Y998745D01*
G01X598974Y998735D02*
X598968Y998740D01*
G01X598981Y998731D02*
X598974Y998735D01*
G01X598989Y998730D02*
X598981Y998731D01*
G01X598996Y998729D02*
X598989Y998730D01*
G01X598957Y1001908D02*
Y1001915D01*
G01X598960Y1001901D02*
X598957Y1001908D01*
G01X598963Y1001895D02*
X598960Y1001901D01*
G01X598968Y1001889D02*
X598963Y1001895D01*
G01X598974Y1001885D02*
X598968Y1001889D01*
G01X598981Y1001881D02*
X598974Y1001885D01*
G01X598989Y1001879D02*
X598981Y1001881D01*
G01X598996Y1001878D02*
X598989Y1001879D01*
G01X598957Y1005058D02*
Y1005065D01*
G01X598960Y1005051D02*
X598957Y1005058D01*
G01X598963Y1005044D02*
X598960Y1005051D01*
G01X598968Y1005039D02*
X598963Y1005044D01*
G01X598974Y1005034D02*
X598968Y1005039D01*
G01X598981Y1005031D02*
X598974Y1005034D01*
G01X598989Y1005029D02*
X598981Y1005031D01*
G01X598996Y1005028D02*
X598989Y1005029D01*
G01X598957Y1008207D02*
Y1008215D01*
G01X598960Y1008200D02*
X598957Y1008207D01*
G01X598963Y1008194D02*
X598960Y1008200D01*
G01X598968Y1008189D02*
X598963Y1008194D01*
G01X598974Y1008184D02*
X598968Y1008189D01*
G01X598981Y1008180D02*
X598974Y1008184D01*
G01X598989Y1008178D02*
X598981Y1008180D01*
G01X598996Y1008178D02*
X598989D01*
G01X599911Y993620D02*
X599920Y993617D01*
G01X599900Y993622D02*
X599911Y993620D01*
G01Y996770D02*
X599920Y996766D01*
G01X599900Y996772D02*
X599911Y996770D01*
G01Y999920D02*
X599920Y999916D01*
G01X599900Y999921D02*
X599911Y999920D01*
G01Y1003069D02*
X599920Y1003065D01*
G01X599900Y1003071D02*
X599911Y1003069D01*
G01Y1006219D02*
X599920Y1006215D01*
G01X599900Y1006220D02*
X599911Y1006219D01*
G01Y1009369D02*
X599920Y1009365D01*
G01X599900Y1009370D02*
X599911Y1009369D01*
G01X598959Y990453D02*
X598954Y990433D01*
G01X598974Y990467D02*
X598959Y990453D01*
G01X598994Y990472D02*
X598974Y990467D01*
G01X598959Y993602D02*
X598954Y993583D01*
G01X598974Y993617D02*
X598959Y993602D01*
G01X598994Y993622D02*
X598974Y993617D01*
G01X598959Y996752D02*
X598954Y996732D01*
G01X598974Y996766D02*
X598959Y996752D01*
G01X598994Y996772D02*
X598974Y996766D01*
G01X598959Y999902D02*
X598954Y999882D01*
G01X598974Y999916D02*
X598959Y999902D01*
G01X598994Y999921D02*
X598974Y999916D01*
G01X598959Y1003051D02*
X598954Y1003031D01*
G01X598974Y1003065D02*
X598959Y1003051D01*
G01X598994Y1003071D02*
X598974Y1003065D01*
G01X598959Y1006201D02*
X598954Y1006181D01*
G01X598974Y1006215D02*
X598959Y1006201D01*
G01X598994Y1006220D02*
X598974Y1006215D01*
G01X598959Y1009350D02*
X598954Y1009331D01*
G01X598974Y1009365D02*
X598959Y1009350D01*
G01X598994Y1009370D02*
X598974Y1009365D01*
G01X599934Y989311D02*
X599939Y989331D01*
G01X599920Y989296D02*
X599934Y989311D01*
G01X599900Y989291D02*
X599920Y989296D01*
G01X599934Y992461D02*
X599939Y992480D01*
G01X599920Y992446D02*
X599934Y992461D01*
G01X599900Y992441D02*
X599920Y992446D01*
G01X599934Y995610D02*
X599939Y995630D01*
G01X599920Y995596D02*
X599934Y995610D01*
G01X599900Y995591D02*
X599920Y995596D01*
G01X599934Y998760D02*
X599939Y998780D01*
G01X599920Y998745D02*
X599934Y998760D01*
G01X599900Y998740D02*
X599920Y998745D01*
G01X599934Y1001909D02*
X599939Y1001929D01*
G01X599920Y1001895D02*
X599934Y1001909D01*
G01X599900Y1001890D02*
X599920Y1001895D01*
G01X599934Y1005059D02*
X599939Y1005079D01*
G01X599920Y1005044D02*
X599934Y1005059D01*
G01X599900Y1005039D02*
X599920Y1005044D01*
G01X599934Y1008209D02*
X599939Y1008228D01*
G01X599920Y1008194D02*
X599934Y1008209D01*
G01X599900Y1008189D02*
X599920Y1008194D01*
G01X599940Y1005058D02*
X599941Y1005065D01*
G01X599938Y1005051D02*
X599940Y1005058D01*
G01X599934Y1005044D02*
X599938Y1005051D01*
G01X599930Y1005039D02*
X599934Y1005044D01*
G01X599923Y1005034D02*
X599930Y1005039D01*
G01X599917Y1005031D02*
X599923Y1005034D01*
G01X599909Y1005029D02*
X599917Y1005031D01*
G01X599902Y1005028D02*
X599909Y1005029D01*
G01X598979Y1006228D02*
X598976Y1006226D01*
G01X598982Y1006229D02*
X598979Y1006228D01*
G01X598986Y1006230D02*
X598982Y1006229D01*
G01X598989Y1006231D02*
X598986Y1006230D01*
G01X598993Y1006231D02*
X598989D01*
G01X598996D02*
X598993D01*
G01X599919Y1008181D02*
X599922Y1008183D01*
G01X599915Y1008180D02*
X599919Y1008181D01*
G01X599912Y1008179D02*
X599915Y1008180D01*
G01X599909Y1008178D02*
X599912Y1008179D01*
G01X599905Y1008178D02*
X599909D01*
G01X599902D02*
X599905D01*
G01X598979Y1009378D02*
X598976Y1009376D01*
G01X598982Y1009379D02*
X598979Y1009378D01*
G01X598986Y1009380D02*
X598982Y1009379D01*
G01X598989Y1009381D02*
X598986Y1009380D01*
G01X598993Y1009381D02*
X598989D01*
G01X598996D02*
X598993D01*
G01X617717Y1046142D02*
X612383D01*
G01X612382Y1045650D02*
X613366D01*
G01Y1043012D02*
X612382D01*
G01X612383Y1042520D02*
X617717D01*
G01Y1042480D02*
X613369D01*
G01X617717Y1041142D02*
X612383D01*
G01X612382Y1040650D02*
X613366D01*
G01Y1038012D02*
X612382D01*
G01X612383Y1037520D02*
X617717D01*
G01Y1037480D02*
X613369D01*
G01X617717Y1036142D02*
X612383D01*
G01X612382Y1035650D02*
X613366D01*
G01Y1033012D02*
X612382D01*
G01X612383Y1032520D02*
X617717D01*
G01Y1032480D02*
X613369D01*
G01X617717Y1031142D02*
X612383D01*
G01X612382Y1030650D02*
X613366D01*
G01Y1028012D02*
X612382D01*
G01X612383Y1027520D02*
X617717D01*
G01Y1027480D02*
X613369D01*
G01X617717Y1026142D02*
X612383D01*
G01X612382Y1025650D02*
X613366D01*
G01Y1023012D02*
X612382D01*
G01X612383Y1022520D02*
X617717D01*
G01Y1022480D02*
X613369D01*
G01X617717Y1021142D02*
X612383D01*
G01X613366Y1045946D02*
X612382Y1045945D01*
G01Y1042715D02*
X613337Y1042717D01*
G01X613366Y1040946D02*
X612382Y1040945D01*
G01Y1037715D02*
X613337Y1037717D01*
G01X613366Y1035946D02*
X612382Y1035945D01*
G01Y1032715D02*
X613337Y1032717D01*
G01X613366Y1030946D02*
X612382Y1030945D01*
G01Y1027715D02*
X613337Y1027717D01*
G01X613366Y1025946D02*
X612382Y1025945D01*
G01Y1022715D02*
X613337Y1022717D01*
G01X613366Y1020946D02*
X612382Y1020945D01*
G01X598843Y1008228D02*
X598955Y1008220D01*
G01X598954Y998775D02*
X598843Y998780D01*
G01X598954Y992477D02*
X598843Y992480D01*
G01X598954Y1001926D02*
X598843Y1001929D01*
G01X612382Y1020650D02*
X613366D01*
G01Y1018012D02*
X612382D01*
G01X612383Y1017520D02*
X617717D01*
G01Y1017480D02*
X613369D01*
G01X617717Y1016142D02*
X612383D01*
G01X612382Y1015650D02*
X613366D01*
G01Y1013012D02*
X612382D01*
G01X612383Y1012520D02*
X617717D01*
G01Y1012480D02*
X613369D01*
G01X600394Y1011535D02*
X597047D01*
G01X617717Y1011142D02*
X612383D01*
G01X612382Y1010650D02*
X613366D01*
G01X610039Y1010374D02*
X613976D01*
G01X599902Y1009567D02*
X598996D01*
G01X599941Y1009528D02*
X598957D01*
G01X599900Y1009370D02*
X594016D01*
G01Y1009331D02*
X599940D01*
G01X608858Y1009193D02*
X612795D01*
G01X599939Y1008228D02*
X594016D01*
G01X599900Y1008189D02*
X594016D01*
G01X598957Y1008031D02*
X599941D01*
G01X598996Y1007992D02*
X599902D01*
G01Y1006417D02*
X598996D01*
G01X599941Y1006378D02*
X598957D01*
G01X599900Y1006220D02*
X594016D01*
G01Y1006181D02*
X599940D01*
G01X599939Y1005079D02*
X594016D01*
G01X599900Y1005039D02*
X594016D01*
G01X598957Y1004882D02*
X599941D01*
G01X598996Y1004843D02*
X599902D01*
G01Y1003268D02*
X598996D01*
G01X599941Y1003228D02*
X598957D01*
G01X599900Y1003071D02*
X594016D01*
G01Y1003031D02*
X599940D01*
G01X599939Y1001929D02*
X594016D01*
G01X599900Y1001890D02*
X594016D01*
G01X598957Y1001732D02*
X599941D01*
G01X598996Y1001693D02*
X599902D01*
G01Y1000118D02*
X598996D01*
G01X599941Y1000079D02*
X598957D01*
G01X599900Y999921D02*
X594016D01*
G01Y999882D02*
X599940D01*
G01X599939Y998780D02*
X594016D01*
G01X599900Y998740D02*
X594016D01*
G01X598957Y998583D02*
X599941D01*
G01X598996Y998543D02*
X599902D01*
G01Y996969D02*
X598996D01*
G01X599941Y996929D02*
X598957D01*
G01X599900Y996772D02*
X594016D01*
G01Y996732D02*
X599940D01*
G01X599939Y995630D02*
X594016D01*
G01X599900Y995591D02*
X594016D01*
G01X598957Y995433D02*
X599941D01*
G01X598996Y995394D02*
X599902D01*
G01Y993819D02*
X598996D01*
G01X599941Y993780D02*
X598957D01*
G01X599900Y993622D02*
X594016D01*
G01Y993583D02*
X599940D01*
G01X599939Y992480D02*
X594016D01*
G01X599900Y992441D02*
X594016D01*
G01X598957Y992283D02*
X599941D01*
G01X598996Y992244D02*
X599902D01*
G01Y990669D02*
X598996D01*
G01X599941Y990630D02*
X598957D01*
G01X599900Y990472D02*
X594016D01*
G01Y990433D02*
X599940D01*
G01X612795Y989469D02*
X608858D01*
G01X599939Y989331D02*
X594016D01*
G01X599900Y989291D02*
X594016D01*
G01X598957Y989134D02*
X599941D01*
G01X598996Y989094D02*
X599902D01*
G01X613976Y988287D02*
X610039D01*
G01X613366Y988012D02*
X612382D01*
G01X612383Y987520D02*
X617717D01*
G01Y987480D02*
X613369D01*
G01X600394Y987126D02*
X597047D01*
G01X617717Y986142D02*
X612383D01*
G01X612382Y985650D02*
X613366D01*
G01Y983012D02*
X612382D01*
G01X612383Y982520D02*
X617717D01*
G01Y982480D02*
X613369D01*
G01X617717Y981142D02*
X612383D01*
G01X612382Y980650D02*
X613366D01*
G01Y978012D02*
X612382D01*
G01X612383Y977520D02*
X617717D01*
G01Y977480D02*
X613369D01*
G01X617717Y976142D02*
X612383D01*
G01X612382Y975650D02*
X613366D01*
G01Y973012D02*
X612382D01*
G01X612383Y972520D02*
X617717D01*
G01Y972480D02*
X613369D01*
G01X617717Y971142D02*
X612383D01*
G01X612382Y970650D02*
X613366D01*
G01Y968012D02*
X612382D01*
G01X612383Y967520D02*
X617717D01*
G01Y967480D02*
X613369D01*
G01X617717Y966142D02*
X612383D01*
G01X612382Y965650D02*
X613366D01*
G01Y963012D02*
X612382D01*
G01X612383Y962520D02*
X617717D01*
G01Y962480D02*
X613369D01*
G01X617717Y961142D02*
X612383D01*
G01X612382Y960650D02*
X613366D01*
G01Y958012D02*
X612382D01*
G01X612383Y957520D02*
X617717D01*
G01Y957480D02*
X613369D01*
G01X617717Y956142D02*
X612383D01*
G01X612382Y955650D02*
X613366D01*
G01X608858Y953012D02*
X603346D01*
G01X612382Y1017715D02*
X613337Y1017717D01*
G01X613366Y1015946D02*
X612382Y1015945D01*
G01Y1012715D02*
X613337Y1012717D01*
G01X613366Y1010946D02*
X612382Y1010945D01*
G01Y987715D02*
X613337Y987717D01*
G01X613366Y985946D02*
X612382Y985945D01*
G01Y982715D02*
X613337Y982717D01*
G01X613366Y980946D02*
X612382Y980945D01*
G01Y977715D02*
X613337Y977717D01*
G01X613366Y975946D02*
X612382Y975945D01*
G01Y972715D02*
X613337Y972717D01*
G01X613366Y970946D02*
X612382Y970945D01*
G01Y967715D02*
X613337Y967717D01*
G01X613366Y965946D02*
X612382Y965945D01*
G01Y962715D02*
X613337Y962717D01*
G01X613366Y960946D02*
X612382Y960945D01*
G01Y957715D02*
X613337Y957717D01*
G01X613366Y955946D02*
X612382Y955945D01*
G01X612795Y989469D02*
X613976Y988287D01*
G01X608858Y989469D02*
X610039Y988287D01*
G01X599900Y1005039D02*
X599904Y1005028D01*
G01X599941Y990435D02*
Y990446D01*
G01Y993585D02*
Y993596D01*
G01Y996734D02*
Y996746D01*
G01Y999884D02*
Y999895D01*
G01Y1003033D02*
Y1003045D01*
G01Y1006183D02*
Y1006194D01*
G01Y1009333D02*
Y1009344D01*
G01X613366Y957494D02*
X613367Y957502D01*
G01X613366Y962494D02*
X613367Y962502D01*
G01X613366Y967494D02*
X613367Y967502D01*
G01X613366Y972494D02*
X613367Y972502D01*
G01X613366Y977494D02*
X613367Y977502D01*
G01X613366Y982494D02*
X613367Y982502D01*
G01X613366Y987494D02*
X613367Y987502D01*
G01X613366Y1012494D02*
X613367Y1012502D01*
G01X613366Y1017494D02*
X613367Y1017502D01*
G01X613366Y1022494D02*
X613367Y1022502D01*
G01X613366Y1027494D02*
X613367Y1027502D01*
G01X613366Y1032494D02*
X613367Y1032502D01*
G01X613366Y1037494D02*
X613367Y1037502D01*
G01X613366Y1042494D02*
X613367Y1042502D01*
G01X617717Y1046142D02*
Y1047520D01*
G01Y1041142D02*
Y1042520D01*
G01Y1036142D02*
Y1037520D01*
G01Y1031142D02*
Y1032520D01*
G01Y1026142D02*
Y1027520D01*
G01Y1021142D02*
Y1022520D01*
G01Y1016142D02*
Y1017520D01*
G01Y1011142D02*
Y1012520D01*
G01Y986142D02*
Y987520D01*
G01Y981142D02*
Y982520D01*
G01Y976142D02*
Y977520D01*
G01Y971142D02*
Y972520D01*
G01Y966142D02*
Y967520D01*
G01Y961142D02*
Y962520D01*
G01Y956142D02*
Y957520D01*
G01X614547D02*
Y956142D01*
G01Y962520D02*
Y961142D01*
G01Y967520D02*
Y966142D01*
G01Y972520D02*
Y971142D01*
G01Y977520D02*
Y976142D01*
G01Y982520D02*
Y981142D01*
G01Y987520D02*
Y986142D01*
G01Y1012520D02*
Y1011142D01*
G01Y1017520D02*
Y1016142D01*
G01Y1022520D02*
Y1021142D01*
G01Y1027520D02*
Y1026142D01*
G01Y1032520D02*
Y1031142D01*
G01Y1037520D02*
Y1036142D01*
G01Y1042520D02*
Y1041142D01*
G01Y1047520D02*
Y1046142D01*
G01X613976Y1010374D02*
Y988287D01*
G01X613366Y1045650D02*
Y1048012D01*
G01Y1040650D02*
Y1043012D01*
G01Y1035650D02*
Y1038012D01*
G01Y1030650D02*
Y1033012D01*
G01Y1025650D02*
Y1028012D01*
G01Y1020650D02*
Y1023012D01*
G01Y1015650D02*
Y1018012D01*
G01Y1010650D02*
Y1013012D01*
G01Y985650D02*
Y988012D01*
G01Y980650D02*
Y983012D01*
G01Y975650D02*
Y978012D01*
G01Y970650D02*
Y973012D01*
G01Y965650D02*
Y968012D01*
G01Y960650D02*
Y963012D01*
G01Y955650D02*
Y958012D01*
G01Y962494D02*
Y962637D01*
G01Y967494D02*
Y967637D01*
G01Y972494D02*
Y972637D01*
G01Y977494D02*
Y977637D01*
G01Y982494D02*
Y982637D01*
G01Y987494D02*
Y987637D01*
G01Y1012494D02*
Y1012637D01*
G01Y1017494D02*
Y1017637D01*
G01Y1022494D02*
Y1022637D01*
G01Y1027494D02*
Y1027637D01*
G01Y1032494D02*
Y1032637D01*
G01Y1037494D02*
Y1037637D01*
G01Y1042494D02*
Y1042637D01*
G01X612795Y1009193D02*
Y989469D01*
G01X612382Y958012D02*
Y955650D01*
G01Y963012D02*
Y960650D01*
G01Y968012D02*
Y965650D01*
G01Y973012D02*
Y970650D01*
G01Y978012D02*
Y975650D01*
G01Y983012D02*
Y980650D01*
G01Y988012D02*
Y985650D01*
G01Y1013012D02*
Y1010650D01*
G01Y1018012D02*
Y1015650D01*
G01Y1023012D02*
Y1020650D01*
G01Y1028012D02*
Y1025650D01*
G01Y1033012D02*
Y1030650D01*
G01Y1038012D02*
Y1035650D01*
G01Y1043012D02*
Y1040650D01*
G01Y1048012D02*
Y1045650D01*
G01X610039Y1086831D02*
Y1010374D01*
G01X608858Y989469D02*
Y953012D01*
G01Y1085650D02*
Y1009193D01*
G01X603346Y953012D02*
Y1085650D01*
G01X600394Y1090571D02*
Y1011535D01*
G01X599941Y1008031D02*
Y1009528D01*
G01Y1004881D02*
Y1006378D01*
G01Y1001732D02*
Y1003228D01*
G01Y998582D02*
Y1000079D01*
G01Y995433D02*
Y996929D01*
G01Y992283D02*
Y993780D01*
G01Y989133D02*
Y990630D01*
G01X599902Y989280D02*
Y989133D01*
G01Y990630D02*
Y990483D01*
G01Y995579D02*
Y995432D01*
G01Y992430D02*
Y992283D01*
G01Y993780D02*
Y993633D01*
G01Y998729D02*
Y998582D01*
G01Y1000079D02*
Y999932D01*
G01Y996930D02*
Y996783D01*
G01Y1001878D02*
Y1001731D01*
G01Y1003229D02*
Y1003082D01*
G01Y1008178D02*
Y1008031D01*
G01Y1009528D02*
Y1009381D01*
G01Y1005028D02*
Y1004881D01*
G01Y1006378D02*
Y1006231D01*
G01X598996Y1008031D02*
Y1008178D01*
G01Y1009381D02*
Y1009528D01*
G01Y1004881D02*
Y1005028D01*
G01Y1006231D02*
Y1006378D01*
G01Y1001731D02*
Y1001878D01*
G01Y1003082D02*
Y1003229D01*
G01Y998582D02*
Y998729D01*
G01Y999932D02*
Y1000079D01*
G01Y996783D02*
Y996930D01*
G01Y995432D02*
Y995579D01*
G01Y992283D02*
Y992430D01*
G01Y993633D02*
Y993780D01*
G01Y989133D02*
Y989280D01*
G01Y990483D02*
Y990630D01*
G01X598957D02*
Y989134D01*
G01Y993780D02*
Y992283D01*
G01Y1000079D02*
Y998583D01*
G01Y996929D02*
Y995433D01*
G01Y1003228D02*
Y1001732D01*
G01Y1009528D02*
Y1008031D01*
G01Y1006378D02*
Y1004882D01*
G01X597776Y990472D02*
Y989291D01*
G01Y996772D02*
Y995591D01*
G01Y993622D02*
Y992441D01*
G01Y999921D02*
Y998740D01*
G01Y1003071D02*
Y1001890D01*
G01Y1009370D02*
Y1008189D01*
G01Y1006220D02*
Y1005039D01*
G01X597441Y1011535D02*
Y987126D01*
G01X597047D02*
Y1011535D01*
G01X594016Y1008189D02*
Y1009370D01*
G01Y1005039D02*
Y1006220D01*
G01Y1001890D02*
Y1003071D01*
G01Y998740D02*
Y999921D01*
G01Y995591D02*
Y996772D01*
G01Y992441D02*
Y993622D01*
G01Y989291D02*
Y990472D01*
G01X599941Y1008215D02*
Y1008226D01*
G01Y1005065D02*
Y1005076D01*
G01Y1001916D02*
Y1001926D01*
G01Y998766D02*
Y998777D01*
G01Y995617D02*
Y995627D01*
G01Y992467D02*
Y992478D01*
G01Y989317D02*
Y989328D01*
G01X612795Y1009193D02*
X613976Y1010374D01*
G01X608858Y1009193D02*
X610039Y1010374D01*
G01X613367Y1081134D02*
X613366Y1081125D01*
G01X613367Y1081140D02*
Y1081134D01*
G01X613369Y1081142D02*
X613367Y1081140D01*
G01Y1076134D02*
X613366Y1076125D01*
G01X613367Y1076140D02*
Y1076134D01*
G01X613369Y1076142D02*
X613367Y1076140D01*
G01Y1071134D02*
X613366Y1071125D01*
G01X613367Y1071140D02*
Y1071134D01*
G01X613369Y1071142D02*
X613367Y1071140D01*
G01Y1066134D02*
X613366Y1066125D01*
G01X613367Y1066140D02*
Y1066134D01*
G01X613369Y1066142D02*
X613367Y1066140D01*
G01Y1061134D02*
X613366Y1061125D01*
G01X613367Y1061140D02*
Y1061134D01*
G01X613369Y1061142D02*
X613367Y1061140D01*
G01Y1056134D02*
X613366Y1056125D01*
G01X613367Y1056140D02*
Y1056134D01*
G01X613369Y1056142D02*
X613367Y1056140D01*
G01Y1051134D02*
X613366Y1051125D01*
G01X613367Y1051140D02*
Y1051134D01*
G01X613369Y1051142D02*
X613367Y1051140D01*
G01X613333Y1047618D02*
X613337Y1047717D01*
G01X613328Y1047546D02*
X613333Y1047618D01*
G01X613330Y1047520D02*
X613328Y1047546D01*
G01X613333Y1052618D02*
X613337Y1052717D01*
G01X613328Y1052546D02*
X613333Y1052618D01*
G01X613330Y1052520D02*
X613328Y1052546D01*
G01X613333Y1057618D02*
X613337Y1057717D01*
G01X613328Y1057546D02*
X613333Y1057618D01*
G01X613330Y1057520D02*
X613328Y1057546D01*
G01X613333Y1062618D02*
X613337Y1062717D01*
G01X613328Y1062546D02*
X613333Y1062618D01*
G01X613330Y1062520D02*
X613328Y1062546D01*
G01X613333Y1067618D02*
X613337Y1067717D01*
G01X613328Y1067546D02*
X613333Y1067618D01*
G01X613330Y1067520D02*
X613328Y1067546D01*
G01X613333Y1072618D02*
X613337Y1072717D01*
G01X613328Y1072546D02*
X613333Y1072618D01*
G01X613330Y1072520D02*
X613328Y1072546D01*
G01X613333Y1077618D02*
X613337Y1077717D01*
G01X613328Y1077546D02*
X613333Y1077618D01*
G01X613330Y1077520D02*
X613328Y1077546D01*
G01X613333Y1082618D02*
X613337Y1082717D01*
G01X613328Y1082546D02*
X613333Y1082618D01*
G01X613330Y1082520D02*
X613328Y1082546D01*
G01X612383Y1081140D02*
Y1081142D01*
G01X612382Y1081134D02*
X612383Y1081140D01*
G01X612382Y1081126D02*
Y1081134D01*
G01X612383Y1076140D02*
Y1076142D01*
G01X612382Y1076134D02*
X612383Y1076140D01*
G01X612382Y1076126D02*
Y1076134D01*
G01X612383Y1071140D02*
Y1071142D01*
G01X612382Y1071134D02*
X612383Y1071140D01*
G01X612382Y1071126D02*
Y1071134D01*
G01X612383Y1066140D02*
Y1066142D01*
G01X612382Y1066134D02*
X612383Y1066140D01*
G01X612382Y1066126D02*
Y1066134D01*
G01X612383Y1061140D02*
Y1061142D01*
G01X612382Y1061134D02*
X612383Y1061140D01*
G01X612382Y1061126D02*
Y1061134D01*
G01X612383Y1056140D02*
Y1056142D01*
G01X612382Y1056134D02*
X612383Y1056140D01*
G01X612382Y1056126D02*
Y1056134D01*
G01X612383Y1051140D02*
Y1051142D01*
G01X612382Y1051134D02*
X612383Y1051140D01*
G01X612382Y1051126D02*
Y1051134D01*
G01X613349Y1052515D02*
X613330Y1052520D01*
G01X613363Y1052500D02*
X613349Y1052515D01*
G01X613369Y1052480D02*
X613363Y1052500D01*
G01X613349Y1057515D02*
X613330Y1057520D01*
G01X613363Y1057500D02*
X613349Y1057515D01*
G01X613369Y1057480D02*
X613363Y1057500D01*
G01X613349Y1062515D02*
X613330Y1062520D01*
G01X613363Y1062500D02*
X613349Y1062515D01*
G01X613369Y1062480D02*
X613363Y1062500D01*
G01X613349Y1067515D02*
X613330Y1067520D01*
G01X613363Y1067500D02*
X613349Y1067515D01*
G01X613369Y1067480D02*
X613363Y1067500D01*
G01X613349Y1072515D02*
X613330Y1072520D01*
G01X613363Y1072500D02*
X613349Y1072515D01*
G01X613369Y1072480D02*
X613363Y1072500D01*
G01X613349Y1077515D02*
X613330Y1077520D01*
G01X613363Y1077500D02*
X613349Y1077515D01*
G01X613369Y1077480D02*
X613363Y1077500D01*
G01X613349Y1082515D02*
X613330Y1082520D01*
G01X613363Y1082500D02*
X613349Y1082515D01*
G01X613369Y1082480D02*
X613363Y1082500D01*
G01X612382Y1047527D02*
Y1047536D01*
G01X612383Y1047521D02*
X612382Y1047527D01*
G01X612383Y1047520D02*
Y1047521D01*
G01X612382Y1052527D02*
Y1052536D01*
G01X612383Y1052521D02*
X612382Y1052527D01*
G01X612383Y1052520D02*
Y1052521D01*
G01X612382Y1057527D02*
Y1057536D01*
G01X612383Y1057521D02*
X612382Y1057527D01*
G01X612383Y1057520D02*
Y1057521D01*
G01X612382Y1062527D02*
Y1062536D01*
G01X612383Y1062521D02*
X612382Y1062527D01*
G01X612383Y1062520D02*
Y1062521D01*
G01X612382Y1067527D02*
Y1067536D01*
G01X612383Y1067521D02*
X612382Y1067527D01*
G01X612383Y1067520D02*
Y1067521D01*
G01X612382Y1072527D02*
Y1072536D01*
G01X612383Y1072521D02*
X612382Y1072527D01*
G01X612383Y1072520D02*
Y1072521D01*
G01X612382Y1077527D02*
Y1077536D01*
G01X612383Y1077521D02*
X612382Y1077527D01*
G01X612383Y1077520D02*
Y1077521D01*
G01X612382Y1082527D02*
Y1082536D01*
G01X612383Y1082521D02*
X612382Y1082527D01*
G01X612383Y1082520D02*
Y1082521D01*
G01X613358Y1047663D02*
X613366Y1047637D01*
G01X613348Y1047690D02*
X613358Y1047663D01*
G01X613337Y1047717D02*
X613348Y1047690D01*
G01X613358Y1052663D02*
X613366Y1052637D01*
G01X613348Y1052690D02*
X613358Y1052663D01*
G01X613337Y1052717D02*
X613348Y1052690D01*
G01X613358Y1057663D02*
X613366Y1057637D01*
G01X613348Y1057690D02*
X613358Y1057663D01*
G01X613337Y1057717D02*
X613348Y1057690D01*
G01X613358Y1062663D02*
X613366Y1062637D01*
G01X613348Y1062690D02*
X613358Y1062663D01*
G01X613337Y1062717D02*
X613348Y1062690D01*
G01X613358Y1067663D02*
X613366Y1067637D01*
G01X613348Y1067690D02*
X613358Y1067663D01*
G01X613337Y1067717D02*
X613348Y1067690D01*
G01X613358Y1072663D02*
X613366Y1072637D01*
G01X613348Y1072690D02*
X613358Y1072663D01*
G01X613337Y1072717D02*
X613348Y1072690D01*
G01X613358Y1077663D02*
X613366Y1077637D01*
G01X613348Y1077690D02*
X613358Y1077663D01*
G01X613337Y1077717D02*
X613348Y1077690D01*
G01X613358Y1082663D02*
X613366Y1082637D01*
G01X613348Y1082690D02*
X613358Y1082663D01*
G01X613337Y1082717D02*
X613348Y1082690D01*
G01X613367Y1047482D02*
Y1047487D01*
G01Y1052487D02*
X613366Y1052494D01*
G01X613367Y1052482D02*
Y1052487D01*
G01X613369Y1052480D02*
X613367Y1052482D01*
G01Y1057487D02*
X613366Y1057494D01*
G01X613367Y1057482D02*
Y1057487D01*
G01X613369Y1057480D02*
X613367Y1057482D01*
G01Y1062487D02*
X613366Y1062494D01*
G01X613367Y1062482D02*
Y1062487D01*
G01X613369Y1062480D02*
X613367Y1062482D01*
G01Y1067487D02*
X613366Y1067494D01*
G01X613367Y1067482D02*
Y1067487D01*
G01X613369Y1067480D02*
X613367Y1067482D01*
G01Y1072487D02*
X613366Y1072494D01*
G01X613367Y1072482D02*
Y1072487D01*
G01X613369Y1072480D02*
X613367Y1072482D01*
G01Y1077487D02*
X613366Y1077494D01*
G01X613367Y1077482D02*
Y1077487D01*
G01X613369Y1077480D02*
X613367Y1077482D01*
G01Y1082487D02*
X613366Y1082494D01*
G01X613367Y1082482D02*
Y1082487D01*
G01X613369Y1082480D02*
X613367Y1082482D01*
G01X613354Y1052511D02*
X613365Y1052496D01*
G01X613329Y1052520D02*
X613354Y1052511D01*
G01Y1057511D02*
X613365Y1057496D01*
G01X613329Y1057520D02*
X613354Y1057511D01*
G01Y1062511D02*
X613365Y1062496D01*
G01X613329Y1062520D02*
X613354Y1062511D01*
G01Y1067511D02*
X613365Y1067496D01*
G01X613329Y1067520D02*
X613354Y1067511D01*
G01Y1072511D02*
X613365Y1072496D01*
G01X613329Y1072520D02*
X613354Y1072511D01*
G01Y1077511D02*
X613365Y1077496D01*
G01X613329Y1077520D02*
X613354Y1077511D01*
G01Y1082511D02*
X613365Y1082496D01*
G01X613329Y1082520D02*
X613354Y1082511D01*
G01X610358Y1170224D02*
G03X644169I16906J-13531D01*
G01X610358D02*
G03X644169I16906J-13531D01*
G01X611811Y1108012D02*
G03X611220Y1108602I-590J0D01*
G01X604528D02*
G03X603937Y1108012I-1J-590D01*
G01X606693Y1106831D02*
G03Y1104862I0J-985D01*
G01X609055D02*
G03Y1106831I0J984D01*
G01X605315Y1098917D02*
G03X604134Y1097736I0J-1181D01*
G01X611614D02*
G03X610433Y1098917I-1181J0D01*
G01X609764Y1093642D02*
G03I-1890J0D01*
G01X618701Y1107421D02*
G03X616732Y1109390I-1969J0D01*
G01X599016D02*
G03X597047Y1107421I0J-1969D01*
G01X610236Y1093642D02*
G03I-2362J0D01*
G01X616732Y1109390D02*
X599016D01*
G01X611220Y1108602D02*
X604528D01*
G01X609055Y1106831D02*
X606693D01*
G01Y1104862D02*
X609055D01*
G01X611811Y1103484D02*
X603937D01*
G01Y1101909D02*
X611811D01*
G01X618701Y1098957D02*
X597047D01*
G01X605315Y1098917D02*
X610433D01*
G01X606693Y1094232D02*
X609055D01*
G01X606693Y1092539D02*
X609055D01*
G01X600394Y1090571D02*
X614764D01*
G01X600394Y1089193D02*
X604134D01*
G01X614764D02*
X611614D01*
G01X600394Y1088327D02*
X615354D01*
G01X602165Y1086831D02*
X610039D01*
G01X603346Y1085650D02*
X608858D01*
G01X613366Y1083012D02*
X612382D01*
G01X612383Y1082520D02*
X617717D01*
G01Y1082480D02*
X613369D01*
G01X617717Y1081142D02*
X612383D01*
G01X612382Y1080650D02*
X613366D01*
G01Y1078012D02*
X612382D01*
G01X612383Y1077520D02*
X617717D01*
G01Y1077480D02*
X613369D01*
G01X617717Y1076142D02*
X612383D01*
G01X612382Y1075650D02*
X613366D01*
G01Y1073012D02*
X612382D01*
G01X612383Y1072520D02*
X617717D01*
G01Y1072480D02*
X613369D01*
G01X617717Y1071142D02*
X612383D01*
G01X612382Y1070650D02*
X613366D01*
G01Y1068012D02*
X612382D01*
G01X612383Y1067520D02*
X617717D01*
G01Y1067480D02*
X613369D01*
G01X617717Y1066142D02*
X612383D01*
G01X612382Y1065650D02*
X613366D01*
G01Y1063012D02*
X612382D01*
G01X612383Y1062520D02*
X617717D01*
G01Y1062480D02*
X613369D01*
G01X617717Y1061142D02*
X612383D01*
G01X612382Y1060650D02*
X613366D01*
G01Y1058012D02*
X612382D01*
G01X612383Y1057520D02*
X617717D01*
G01Y1057480D02*
X613369D01*
G01X617717Y1056142D02*
X612383D01*
G01X612382Y1055650D02*
X613366D01*
G01Y1053012D02*
X612382D01*
G01X612383Y1052520D02*
X617717D01*
G01Y1052480D02*
X613369D01*
G01X617717Y1051142D02*
X612383D01*
G01X612382Y1050650D02*
X613366D01*
G01Y1048012D02*
X612382D01*
G01X612383Y1047520D02*
X617717D01*
G01Y1047480D02*
X613369D01*
G01X612382Y1082715D02*
X613337Y1082717D01*
G01X613366Y1080946D02*
X612382Y1080945D01*
G01Y1077715D02*
X613337Y1077717D01*
G01X613366Y1075946D02*
X612382Y1075945D01*
G01Y1072715D02*
X613337Y1072717D01*
G01X613366Y1070946D02*
X612382Y1070945D01*
G01Y1067715D02*
X613337Y1067717D01*
G01X613366Y1065946D02*
X612382Y1065945D01*
G01Y1062715D02*
X613337Y1062717D01*
G01X613366Y1060946D02*
X612382Y1060945D01*
G01Y1057715D02*
X613337Y1057717D01*
G01X613366Y1055946D02*
X612382Y1055945D01*
G01Y1052715D02*
X613337Y1052717D01*
G01X613366Y1050946D02*
X612382Y1050945D01*
G01Y1047715D02*
X613337Y1047717D01*
G01X602165Y1086831D02*
X603346Y1085650D01*
G01X600394Y1088327D02*
X597047Y1091673D01*
G01X609055Y1092539D02*
X610359Y1090571D01*
G01X606693Y1094232D02*
X604383Y1098461D01*
G01X613366Y1047494D02*
X613367Y1047502D01*
G01X613366Y1052494D02*
X613367Y1052502D01*
G01X613366Y1057494D02*
X613367Y1057502D01*
G01X613366Y1062494D02*
X613367Y1062502D01*
G01X613366Y1067494D02*
X613367Y1067502D01*
G01X613366Y1072494D02*
X613367Y1072502D01*
G01X613366Y1077494D02*
X613367Y1077502D01*
G01X613366Y1082494D02*
X613367Y1082502D01*
G01X618701Y1091673D02*
Y1107421D01*
G01X617717Y1081142D02*
Y1082520D01*
G01Y1076142D02*
Y1077520D01*
G01Y1071142D02*
Y1072520D01*
G01Y1066142D02*
Y1067520D01*
G01Y1061142D02*
Y1062520D01*
G01Y1056142D02*
Y1057520D01*
G01Y1051142D02*
Y1052520D01*
G01X614547D02*
Y1051142D01*
G01Y1057520D02*
Y1056142D01*
G01Y1062520D02*
Y1061142D01*
G01Y1067520D02*
Y1066142D01*
G01Y1072520D02*
Y1071142D01*
G01Y1077520D02*
Y1076142D01*
G01Y1082520D02*
Y1081142D01*
G01X613366Y1080650D02*
Y1083012D01*
G01Y1075650D02*
Y1078012D01*
G01Y1070650D02*
Y1073012D01*
G01Y1065650D02*
Y1068012D01*
G01Y1060650D02*
Y1063012D01*
G01Y1055650D02*
Y1058012D01*
G01Y1050650D02*
Y1053012D01*
G01Y1047494D02*
Y1047637D01*
G01Y1052494D02*
Y1052637D01*
G01Y1057494D02*
Y1057637D01*
G01Y1062494D02*
Y1062637D01*
G01Y1067494D02*
Y1067637D01*
G01Y1072494D02*
Y1072637D01*
G01Y1077494D02*
Y1077637D01*
G01Y1082494D02*
Y1082637D01*
G01X612382Y1053012D02*
Y1050650D01*
G01Y1058012D02*
Y1055650D01*
G01Y1063012D02*
Y1060650D01*
G01Y1068012D02*
Y1065650D01*
G01Y1073012D02*
Y1070650D01*
G01Y1078012D02*
Y1075650D01*
G01Y1083012D02*
Y1080650D01*
G01X611811Y1101909D02*
Y1108012D01*
G01X611614Y1097736D02*
Y1089193D01*
G01X609055Y1094232D02*
Y1092539D01*
G01X606693D02*
Y1094232D01*
G01X604134Y1089193D02*
Y1097736D01*
G01X603937Y1101909D02*
Y1108012D01*
G01X597047Y1107421D02*
Y1091673D01*
G01X618701D02*
X615354Y1088327D01*
G01X608858Y1085650D02*
X610039Y1086831D01*
G01X611365Y1098461D02*
X609055Y1094232D01*
G01X605389Y1090571D02*
X606693Y1092539D01*
G01X637244Y1183355D02*
G03X644169Y1170224I37662J11471D01*
G01X637244Y1183355D02*
G03X617283I-9980J-3040D01*
G01X610358Y1170224D02*
G03X617283Y1183355I-30737J24602D01*
G01X637244D02*
G03X644169Y1170224I37662J11471D01*
G01X637244Y1183355D02*
G03X617283I-9980J-3040D01*
G01X610358Y1170224D02*
G03X617283Y1183355I-30737J24601D01*
G01X614173Y1497059D02*
G03Y1494280I0J-1389D01*
G01Y1498764D02*
G03Y1492575I0J-3094D01*
G01X612913Y1499606D02*
G03Y1491732I1260J-3937D01*
G01X610039Y1499606D02*
G03Y1491732I4134J-3937D01*
G01X601575Y1523622D02*
X635433D01*
G01Y1521654D02*
X631890D01*
G01X614173Y1520210D02*
X597638D01*
G01X601575Y1510954D02*
X624803D01*
G01X583071D02*
X593701D01*
G01X612106Y1505512D02*
X616240D01*
G01X595571D02*
X599705D01*
G01X579035D02*
X583169D01*
G01X593701Y1505210D02*
X597638D01*
G01X579134D02*
X583071D01*
G01X614173Y1499606D02*
X610039D01*
G01X624803Y1492913D02*
X635433D01*
G01X610039Y1491732D02*
X614173D01*
G01X604724Y1485827D02*
X590551D01*
G01X621260D02*
X607087D01*
G01X583169Y1469783D02*
X579035D01*
G01X599705D02*
X595571D01*
G01X616240D02*
X612106D01*
G01X583169Y1468996D02*
X579035D01*
G01X599705D02*
X595571D01*
G01X616240D02*
X612106D01*
G01X583169Y1464862D02*
X579035D01*
G01X599705D02*
X595571D01*
G01X616240D02*
X612106D01*
G01X583169Y1448130D02*
X579035D01*
G01X599705D02*
X595571D01*
G01X616240D02*
X612106D01*
G01X583169Y1447343D02*
X579035D01*
G01X599705D02*
X595571D01*
G01X616240D02*
X612106D01*
G01X583169Y1443209D02*
X579035D01*
G01X599705D02*
X595571D01*
G01X616240D02*
X612106D01*
G01X635433Y1492913D02*
Y1526772D01*
G01X633740Y1519685D02*
Y1521604D01*
G01X631890Y1526772D02*
Y1521654D01*
G01X624803Y1510954D02*
Y1471260D01*
G01X621260Y1516929D02*
Y1485827D01*
G01X620039Y1523622D02*
Y1471260D01*
G01X617323Y1485827D02*
Y1512992D01*
G01X616535Y1523622D02*
Y1471260D01*
G01X616240Y1443209D02*
Y1471260D01*
G01Y1505512D02*
Y1485827D01*
G01X614173Y1498764D02*
Y1497059D01*
G01Y1510954D02*
Y1526772D01*
G01Y1491732D02*
Y1499606D01*
G01Y1494279D02*
Y1492574D01*
G01X612106Y1471260D02*
Y1443209D01*
G01Y1505512D02*
Y1485827D01*
G01X611024D02*
Y1512992D01*
G01X607087Y1485827D02*
Y1512992D01*
G01X604724Y1485827D02*
Y1512992D01*
G01X601575Y1523622D02*
Y1509843D01*
G01X600787Y1485827D02*
Y1512992D01*
G01X599705Y1443209D02*
Y1471260D01*
G01Y1505512D02*
Y1485827D01*
G01X597638Y1526772D02*
Y1505210D01*
G01X595571Y1471260D02*
Y1443209D01*
G01Y1505512D02*
Y1485827D01*
G01X594488D02*
Y1512992D01*
G01X593701Y1505210D02*
Y1523622D01*
G01X590551Y1485827D02*
Y1512992D01*
G01X588189Y1485827D02*
Y1512992D01*
G01X584252Y1485827D02*
Y1512992D01*
G01X583169Y1443209D02*
Y1471260D01*
G01Y1505512D02*
Y1485827D01*
G01X583071Y1523622D02*
Y1505210D01*
G01X579134D02*
Y1523622D01*
G01X579035Y1471260D02*
Y1443209D01*
G01Y1505512D02*
Y1485827D01*
G01X577953D02*
Y1512992D01*
G01X631890Y1526772D02*
X621260Y1516929D01*
G01X635433Y1523622D02*
X624803Y1510954D01*
G01X631890Y1521654D02*
X621260Y1516929D01*
G01X697936Y-369410D02*
Y-388347D01*
G01X737566Y51999D02*
X737577Y51984D01*
G01X737542Y52008D02*
X737566Y51999D01*
G01Y56999D02*
X737577Y56984D01*
G01X737542Y57008D02*
X737566Y56999D01*
G01Y61999D02*
X737577Y61984D01*
G01X737542Y62008D02*
X737566Y61999D01*
G01Y66999D02*
X737577Y66984D01*
G01X737542Y67008D02*
X737566Y66999D01*
G01Y71999D02*
X737577Y71984D01*
G01X737542Y72008D02*
X737566Y71999D01*
G01X724131Y83772D02*
X724134Y83774D01*
G01X724128Y83770D02*
X724131Y83772D01*
G01X724125Y83770D02*
X724128D01*
G01X724121Y83769D02*
X724125Y83770D01*
G01X724118Y83769D02*
X724121D01*
G01X724114Y83768D02*
X724118Y83769D01*
G01X723192Y84968D02*
X723189Y84967D01*
G01X723195Y84969D02*
X723192Y84968D01*
G01X723198Y84970D02*
X723195Y84969D01*
G01X723202Y84971D02*
X723198Y84970D01*
G01X723205Y84972D02*
X723202Y84971D01*
G01X723209Y84972D02*
X723205D01*
G01X724131Y86921D02*
X724134Y86923D01*
G01X724128Y86920D02*
X724131Y86921D01*
G01X724125Y86919D02*
X724128Y86920D01*
G01X724121Y86919D02*
X724125D01*
G01X724118Y86918D02*
X724121Y86919D01*
G01X724114Y86918D02*
X724118D01*
G01X723192Y88118D02*
X723189Y88116D01*
G01X723195Y88119D02*
X723192Y88118D01*
G01X723198Y88120D02*
X723195Y88119D01*
G01X723202Y88121D02*
X723198Y88120D01*
G01X723205Y88121D02*
X723202D01*
G01X723209D02*
X723205D01*
G01X724131Y90071D02*
X724134Y90073D01*
G01X724128Y90070D02*
X724131Y90071D01*
G01X724125Y90069D02*
X724128Y90070D01*
G01X724121Y90068D02*
X724125Y90069D01*
G01X724118Y90068D02*
X724121D01*
G01X724114Y90067D02*
X724118Y90068D01*
G01X723192Y91267D02*
X723189Y91266D01*
G01X723195Y91269D02*
X723192Y91267D01*
G01X723198Y91270D02*
X723195Y91269D01*
G01X723202Y91270D02*
X723198D01*
G01X723205Y91271D02*
X723202Y91270D01*
G01X723209Y91271D02*
X723205D01*
G01X724131Y93220D02*
X724134Y93222D01*
G01X724128Y93219D02*
X724131Y93220D01*
G01X724125Y93219D02*
X724128D01*
G01X724121Y93218D02*
X724125Y93219D01*
G01X724118Y93217D02*
X724121Y93218D01*
G01X724114Y93217D02*
X724118D01*
G01X722422Y86969D02*
X721988D01*
G01X722796D02*
X722422D01*
G01Y93268D02*
X721988D01*
G01X722796D02*
X722422D01*
G01X724144Y84959D02*
X724148Y84954D01*
G01X724139Y84963D02*
X724144Y84959D01*
G01X724133Y84967D02*
X724139Y84963D01*
G01X724128Y84970D02*
X724133Y84967D01*
G01X724121Y84971D02*
X724128Y84970D01*
G01X724114Y84972D02*
X724121Y84971D01*
G01X724144Y88109D02*
X724148Y88103D01*
G01X724139Y88113D02*
X724144Y88109D01*
G01X724133Y88117D02*
X724139Y88113D01*
G01X724128Y88119D02*
X724133Y88117D01*
G01X724121Y88121D02*
X724128Y88119D01*
G01X724114Y88121D02*
X724121D01*
G01X724144Y91258D02*
X724148Y91253D01*
G01X724139Y91263D02*
X724144Y91258D01*
G01X724133Y91266D02*
X724139Y91263D01*
G01X724128Y91269D02*
X724133Y91266D01*
G01X724121Y91270D02*
X724128Y91269D01*
G01X724114Y91271D02*
X724121Y91270D01*
G01X723170Y83798D02*
X723169Y83805D01*
G01X723172Y83791D02*
X723170Y83798D01*
G01X723176Y83785D02*
X723172Y83791D01*
G01X723181Y83779D02*
X723176Y83785D01*
G01X723187Y83774D02*
X723181Y83779D01*
G01X723194Y83771D02*
X723187Y83774D01*
G01X723201Y83769D02*
X723194Y83771D01*
G01X723209Y83768D02*
X723201Y83769D01*
G01X723170Y86948D02*
X723169Y86955D01*
G01X723172Y86941D02*
X723170Y86948D01*
G01X723176Y86934D02*
X723172Y86941D01*
G01X723181Y86929D02*
X723176Y86934D01*
G01X723187Y86924D02*
X723181Y86929D01*
G01X723194Y86920D02*
X723187Y86924D01*
G01X723201Y86919D02*
X723194Y86920D01*
G01X723209Y86918D02*
X723201Y86919D01*
G01X723170Y90097D02*
X723169Y90104D01*
G01X723172Y90090D02*
X723170Y90097D01*
G01X723176Y90084D02*
X723172Y90090D01*
G01X723181Y90078D02*
X723176Y90084D01*
G01X723187Y90074D02*
X723181Y90078D01*
G01X723194Y90070D02*
X723187Y90074D01*
G01X723201Y90068D02*
X723194Y90070D01*
G01X723209Y90067D02*
X723201Y90068D01*
G01X723170Y93247D02*
X723169Y93254D01*
G01X723172Y93240D02*
X723170Y93247D01*
G01X723176Y93233D02*
X723172Y93240D01*
G01X723181Y93228D02*
X723176Y93233D01*
G01X723187Y93223D02*
X723181Y93228D01*
G01X723194Y93220D02*
X723187Y93223D01*
G01X723201Y93218D02*
X723194Y93220D01*
G01X723209Y93217D02*
X723201Y93218D01*
G01X724123Y84959D02*
X724133Y84955D01*
G01X724113Y84961D02*
X724123Y84959D01*
G01Y88109D02*
X724133Y88105D01*
G01X724113Y88110D02*
X724123Y88109D01*
G01Y91258D02*
X724133Y91254D01*
G01X724113Y91260D02*
X724123Y91258D01*
G01X723169Y86959D02*
Y86955D01*
G01X723171Y86952D02*
X723169Y86959D01*
G01X723183Y86937D02*
X723171Y86952D01*
G01X723207Y86929D02*
X723183Y86937D01*
G01X723169Y90108D02*
Y90104D01*
G01X723171Y90102D02*
X723169Y90108D01*
G01X723182Y90087D02*
X723171Y90102D01*
G01X723207Y90079D02*
X723182Y90087D01*
G01X723169Y83809D02*
Y83806D01*
G01X723171Y83803D02*
X723169Y83809D01*
G01X723182Y83788D02*
X723171Y83803D01*
G01X723207Y83780D02*
X723182Y83788D01*
G01X737577Y76984D02*
X737579Y76978D01*
G01X737566Y76999D02*
X737577Y76984D01*
G01X737542Y77008D02*
X737566Y76999D01*
G01Y81999D02*
X737577Y81984D01*
G01X737542Y82008D02*
X737566Y81999D01*
G01X723169Y93258D02*
Y93254D01*
G01X723171Y93252D02*
X723169Y93258D01*
G01X723181Y93238D02*
X723171Y93252D01*
G01X723204Y93228D02*
X723181Y93238D01*
G01X724122Y91259D02*
X724113Y91260D01*
G01X724131Y91256D02*
X724122Y91259D01*
G01X724139Y91250D02*
X724131Y91256D01*
G01X724122Y84959D02*
X724113Y84961D01*
G01X724131Y84956D02*
X724122Y84959D01*
G01X724139Y84951D02*
X724131Y84956D01*
G01X724122Y88109D02*
X724113Y88110D01*
G01X724131Y88106D02*
X724122Y88109D01*
G01X724139Y88100D02*
X724131Y88106D01*
G01X723208Y83774D02*
X723209Y83768D01*
G01X723207Y83778D02*
X723208Y83774D01*
G01X723206Y83780D02*
X723207Y83778D01*
G01X723208Y86924D02*
X723209Y86918D01*
G01X723207Y86928D02*
X723208Y86924D01*
G01X723206Y86929D02*
X723207Y86928D01*
G01X723208Y90074D02*
X723209Y90067D01*
G01X723207Y90078D02*
X723208Y90074D01*
G01X723206Y90079D02*
X723207Y90078D01*
G01X723208Y93223D02*
X723209Y93217D01*
G01X723207Y93227D02*
X723208Y93223D01*
G01X723206Y93228D02*
X723207Y93227D01*
G01X723172Y84941D02*
X723167Y84921D01*
G01X723187Y84955D02*
X723172Y84941D01*
G01X723206Y84961D02*
X723187Y84955D01*
G01X723172Y88091D02*
X723167Y88071D01*
G01X723187Y88105D02*
X723172Y88091D01*
G01X723206Y88110D02*
X723187Y88105D01*
G01X723172Y91240D02*
X723167Y91220D01*
G01X723187Y91254D02*
X723172Y91240D01*
G01X723206Y91260D02*
X723187Y91254D01*
G01X724147Y83799D02*
X724152Y83819D01*
G01X724132Y83785D02*
X724147Y83799D01*
G01X724113Y83780D02*
X724132Y83785D01*
G01X724147Y86949D02*
X724152Y86969D01*
G01X724132Y86934D02*
X724147Y86949D01*
G01X724113Y86929D02*
X724132Y86934D01*
G01X724147Y90098D02*
X724152Y90118D01*
G01X724132Y90084D02*
X724147Y90098D01*
G01X724113Y90079D02*
X724132Y90084D01*
G01X724147Y93248D02*
X724152Y93268D01*
G01X724132Y93233D02*
X724147Y93248D01*
G01X724113Y93228D02*
X724132Y93233D01*
G01X737579Y51975D02*
Y51982D01*
G01X737580Y51970D02*
X737579Y51975D01*
G01X737581Y51969D02*
X737580Y51970D01*
G01X737579Y56975D02*
Y56982D01*
G01X737580Y56970D02*
X737579Y56975D01*
G01X737581Y56969D02*
X737580Y56970D01*
G01X737579Y61975D02*
Y61982D01*
G01X737580Y61970D02*
X737579Y61975D01*
G01X737581Y61969D02*
X737580Y61970D01*
G01X737579Y66975D02*
Y66982D01*
G01X737580Y66970D02*
X737579Y66975D01*
G01X737581Y66969D02*
X737580Y66970D01*
G01X737579Y71975D02*
Y71982D01*
G01X737580Y71970D02*
X737579Y71975D01*
G01X737581Y71969D02*
X737580Y71970D01*
G01X737579Y76975D02*
Y76982D01*
G01X737580Y76970D02*
X737579Y76975D01*
G01X737581Y76969D02*
X737580Y76970D01*
G01X737579Y81975D02*
Y81982D01*
G01X737580Y81970D02*
X737579Y81975D01*
G01X737581Y81969D02*
X737580Y81970D01*
G01X723192Y86931D02*
X723206Y86929D01*
G01X723181Y86939D02*
X723192Y86931D01*
G01X723169Y86957D02*
X723181Y86939D01*
G01X723192Y90081D02*
X723206Y90079D01*
G01X723180Y90089D02*
X723192Y90081D01*
G01X723168Y90109D02*
X723180Y90089D01*
G01X724154Y83813D02*
Y83805D01*
G01X724153Y83817D02*
X724154Y83813D01*
G01X724152Y83819D02*
X724153Y83817D01*
G01X724154Y86963D02*
Y86955D01*
G01X724153Y86967D02*
X724154Y86963D01*
G01X724152Y86969D02*
X724153Y86967D01*
G01X724154Y90112D02*
Y90104D01*
G01X724153Y90117D02*
X724154Y90112D01*
G01X724152Y90118D02*
X724153Y90117D01*
G01X724154Y93262D02*
Y93254D01*
G01X724153Y93266D02*
X724154Y93262D01*
G01X724152Y93268D02*
X724153Y93266D01*
G01X723191Y83782D02*
X723206Y83780D01*
G01X723178Y83791D02*
X723191Y83782D01*
G01X723168Y83811D02*
X723178Y83791D01*
G01X724153Y84941D02*
X724154Y84935D01*
G01X724151Y84948D02*
X724153Y84941D01*
G01X724148Y84954D02*
X724151Y84948D01*
G01X724153Y88091D02*
X724154Y88084D01*
G01X724151Y88097D02*
X724153Y88091D01*
G01X724148Y88103D02*
X724151Y88097D01*
G01X724153Y91241D02*
X724154Y91234D01*
G01X724151Y91247D02*
X724153Y91241D01*
G01X724148Y91253D02*
X724151Y91247D01*
G01X724115Y83774D02*
Y83768D01*
G01X724113Y83778D02*
X724115Y83774D01*
G01X724113Y83780D02*
Y83778D01*
G01X724115Y86924D02*
Y86918D01*
G01X724113Y86928D02*
X724115Y86924D01*
G01X724113Y86929D02*
Y86928D01*
G01X724115Y90074D02*
Y90067D01*
G01X724113Y90077D02*
X724115Y90074D01*
G01X724113Y90079D02*
Y90077D01*
G01X724115Y93223D02*
Y93217D01*
G01X724113Y93227D02*
X724115Y93223D01*
G01X724113Y93228D02*
Y93227D01*
G01X736594Y52015D02*
Y52024D01*
G01X736595Y52009D02*
X736594Y52015D01*
G01X736596Y52008D02*
X736595Y52009D01*
G01X736594Y57015D02*
Y57024D01*
G01X736595Y57009D02*
X736594Y57015D01*
G01X736596Y57008D02*
X736595Y57009D01*
G01X736594Y62015D02*
Y62024D01*
G01X736595Y62009D02*
X736594Y62015D01*
G01X736596Y62008D02*
X736595Y62009D01*
G01X736594Y67015D02*
Y67024D01*
G01X736595Y67009D02*
X736594Y67015D01*
G01X736596Y67008D02*
X736595Y67009D01*
G01X736594Y72015D02*
Y72024D01*
G01X736595Y72009D02*
X736594Y72015D01*
G01X736596Y72008D02*
X736595Y72009D01*
G01X736594Y77015D02*
Y77024D01*
G01X736595Y77009D02*
X736594Y77015D01*
G01X736596Y77008D02*
X736595Y77009D01*
G01X736594Y82015D02*
Y82024D01*
G01X736595Y82009D02*
X736594Y82015D01*
G01X736596Y82008D02*
X736595Y82009D01*
G01X737571Y52152D02*
X737579Y52125D01*
G01X737561Y52178D02*
X737571Y52152D01*
G01X737550Y52205D02*
X737561Y52178D01*
G01X737571Y57152D02*
X737579Y57125D01*
G01X737561Y57178D02*
X737571Y57152D01*
G01X737550Y57205D02*
X737561Y57178D01*
G01X737571Y62152D02*
X737579Y62125D01*
G01X737561Y62178D02*
X737571Y62152D01*
G01X737550Y62205D02*
X737561Y62178D01*
G01X737571Y67152D02*
X737579Y67125D01*
G01X737561Y67178D02*
X737571Y67152D01*
G01X737550Y67205D02*
X737561Y67178D01*
G01X737571Y72152D02*
X737579Y72125D01*
G01X737561Y72178D02*
X737571Y72152D01*
G01X737550Y72205D02*
X737561Y72178D01*
G01X737571Y77152D02*
X737579Y77125D01*
G01X737561Y77178D02*
X737571Y77152D01*
G01X737550Y77205D02*
X737561Y77178D01*
G01X737571Y82152D02*
X737579Y82125D01*
G01X737561Y82178D02*
X737571Y82152D01*
G01X737550Y82205D02*
X737561Y82178D01*
G01X723187Y93233D02*
X723206Y93228D01*
G01X723174Y93246D02*
X723187Y93233D01*
G01X723167Y93263D02*
X723174Y93246D01*
G01X737561Y52003D02*
X737542Y52008D01*
G01X737576Y51988D02*
X737561Y52003D01*
G01X737581Y51969D02*
X737576Y51988D01*
G01X737561Y57003D02*
X737542Y57008D01*
G01X737576Y56988D02*
X737561Y57003D01*
G01X737581Y56969D02*
X737576Y56988D01*
G01X737561Y62003D02*
X737542Y62008D01*
G01X737576Y61988D02*
X737561Y62003D01*
G01X737581Y61969D02*
X737576Y61988D01*
G01X737561Y67003D02*
X737542Y67008D01*
G01X737576Y66988D02*
X737561Y67003D01*
G01X737581Y66969D02*
X737576Y66988D01*
G01X737561Y72003D02*
X737542Y72008D01*
G01X737576Y71988D02*
X737561Y72003D01*
G01X737581Y71969D02*
X737576Y71988D01*
G01X737561Y77003D02*
X737542Y77008D01*
G01X737576Y76988D02*
X737561Y77003D01*
G01X737581Y76969D02*
X737576Y76988D01*
G01X737561Y82003D02*
X737542Y82008D01*
G01X737576Y81988D02*
X737561Y82003D01*
G01X737581Y81969D02*
X737576Y81988D01*
G01X724146Y91242D02*
X724139Y91250D01*
G01X724151Y91231D02*
X724146Y91242D01*
G01X724152Y91220D02*
X724151Y91231D01*
G01X724146Y84943D02*
X724139Y84951D01*
G01X724151Y84932D02*
X724146Y84943D01*
G01X724152Y84921D02*
X724151Y84932D01*
G01X724146Y88092D02*
X724139Y88100D01*
G01X724151Y88082D02*
X724146Y88092D01*
G01X724152Y88071D02*
X724151Y88082D01*
G01X737546Y52106D02*
X737550Y52205D01*
G01X737540Y52034D02*
X737546Y52106D01*
G01X737542Y52008D02*
X737540Y52034D01*
G01X737546Y57106D02*
X737550Y57205D01*
G01X737540Y57034D02*
X737546Y57106D01*
G01X737542Y57008D02*
X737540Y57034D01*
G01X737546Y62106D02*
X737550Y62205D01*
G01X737540Y62034D02*
X737546Y62106D01*
G01X737542Y62008D02*
X737540Y62034D01*
G01X737546Y67106D02*
X737550Y67205D01*
G01X737540Y67034D02*
X737546Y67106D01*
G01X737542Y67008D02*
X737540Y67034D01*
G01X737546Y72106D02*
X737550Y72205D01*
G01X737540Y72034D02*
X737546Y72106D01*
G01X737542Y72008D02*
X737540Y72034D01*
G01X737546Y77106D02*
X737550Y77205D01*
G01X737540Y77034D02*
X737546Y77106D01*
G01X737542Y77008D02*
X737540Y77034D01*
G01X737546Y82106D02*
X737550Y82205D01*
G01X737540Y82034D02*
X737546Y82106D01*
G01X737542Y82008D02*
X737540Y82034D01*
G01X723209Y91444D02*
Y91457D01*
G01X723206Y91431D02*
X723209Y91444D01*
G01X723206Y91417D02*
Y91431D01*
G01X723209Y88294D02*
Y88307D01*
G01X723206Y88281D02*
X723209Y88294D01*
G01X723206Y88268D02*
Y88281D01*
G01X723209Y85145D02*
Y85157D01*
G01X723206Y85132D02*
X723209Y85145D01*
G01X723206Y85118D02*
Y85132D01*
G01X736595Y80628D02*
X736596Y80630D01*
G01X736594Y80622D02*
X736595Y80628D01*
G01X736594Y80614D02*
Y80622D01*
G01X736595Y75628D02*
X736596Y75630D01*
G01X736594Y75622D02*
X736595Y75628D01*
G01X736594Y75614D02*
Y75622D01*
G01X736595Y70628D02*
X736596Y70630D01*
G01X736594Y70622D02*
X736595Y70628D01*
G01X736594Y70614D02*
Y70622D01*
G01X736595Y65628D02*
X736596Y65630D01*
G01X736594Y65622D02*
X736595Y65628D01*
G01X736594Y65614D02*
Y65622D01*
G01X736595Y60628D02*
X736596Y60630D01*
G01X736594Y60622D02*
X736595Y60628D01*
G01X736594Y60614D02*
Y60622D01*
G01X736595Y55628D02*
X736596Y55630D01*
G01X736594Y55622D02*
X736595Y55628D01*
G01X736594Y55614D02*
Y55622D01*
G01X736595Y50628D02*
X736596Y50630D01*
G01X736594Y50622D02*
X736595Y50628D01*
G01X736594Y50614D02*
Y50622D01*
G01X723206Y93057D02*
X723205Y93070D01*
G01X723209Y93044D02*
X723206Y93057D01*
G01X723209Y93031D02*
Y93044D01*
G01X723206Y89907D02*
X723205Y89921D01*
G01X723209Y89894D02*
X723206Y89907D01*
G01X723209Y89882D02*
Y89894D01*
G01X723206Y86757D02*
X723205Y86771D01*
G01X723209Y86745D02*
X723206Y86757D01*
G01X723209Y86732D02*
Y86745D01*
G01X723206Y83608D02*
X723205Y83622D01*
G01X723209Y83595D02*
X723206Y83608D01*
G01X723209Y83583D02*
Y83595D01*
G01X724117Y91431D02*
X724118Y91417D01*
G01X724113Y91444D02*
X724117Y91431D01*
G01X724114Y91457D02*
X724113Y91444D01*
G01X724117Y88281D02*
X724118Y88268D01*
G01X724113Y88294D02*
X724117Y88281D01*
G01X724114Y88307D02*
X724113Y88294D01*
G01X724117Y85132D02*
X724118Y85118D01*
G01X724113Y85145D02*
X724117Y85132D01*
G01X724114Y85157D02*
X724113Y85145D01*
G01X723169Y90112D02*
Y90105D01*
G01X723168Y90117D02*
X723169Y90112D01*
G01X723168Y90109D02*
Y90117D01*
G01X724113Y93044D02*
X724114Y93031D01*
G01X724116Y93057D02*
X724113Y93044D01*
G01X724117Y93070D02*
X724116Y93057D01*
G01X724113Y89894D02*
X724114Y89882D01*
G01X724116Y89907D02*
X724113Y89894D01*
G01X724117Y89921D02*
X724116Y89907D01*
G01X724113Y86745D02*
X724114Y86732D01*
G01X724116Y86757D02*
X724113Y86745D01*
G01X724117Y86771D02*
X724116Y86757D01*
G01X724113Y83595D02*
X724114Y83583D01*
G01X724116Y83608D02*
X724113Y83595D01*
G01X724117Y83622D02*
X724116Y83608D01*
G01X723169Y83813D02*
Y83806D01*
G01X723168Y83817D02*
X723169Y83813D01*
G01X723168Y83811D02*
Y83817D01*
G01X723182Y91251D02*
X723206Y91260D01*
G01X723171Y91237D02*
X723182Y91251D01*
G01X723169Y91230D02*
X723171Y91237D01*
G01X723182Y88102D02*
X723206Y88110D01*
G01X723171Y88087D02*
X723182Y88102D01*
G01X723169Y88080D02*
X723171Y88087D01*
G01X723182Y84952D02*
X723206Y84961D01*
G01X723171Y84937D02*
X723182Y84952D01*
G01X723169Y84931D02*
X723171Y84937D01*
G01X724154Y91227D02*
Y91234D01*
G01X724153Y91222D02*
X724154Y91227D01*
G01X724152Y91220D02*
X724153Y91222D01*
G01X724154Y88077D02*
Y88084D01*
G01X724153Y88072D02*
X724154Y88077D01*
G01X724152Y88071D02*
X724153Y88072D01*
G01X724154Y84928D02*
Y84935D01*
G01X724153Y84923D02*
X724154Y84928D01*
G01X724152Y84921D02*
X724153Y84923D01*
G01X723169Y93262D02*
Y93254D01*
G01X723168Y93266D02*
X723169Y93262D01*
G01X723167Y93263D02*
X723168Y93266D01*
G01X723169Y86963D02*
Y86955D01*
G01X723168Y86967D02*
X723169Y86963D01*
G01X723167Y86965D02*
X723168Y86967D01*
G01X724114Y91265D02*
Y91271D01*
G01X724113Y91261D02*
X724114Y91265D01*
G01X724113Y91260D02*
Y91261D01*
G01X724114Y88115D02*
Y88121D01*
G01X724113Y88111D02*
X724114Y88115D01*
G01X724113Y88110D02*
Y88111D01*
G01X724114Y84966D02*
Y84972D01*
G01X724113Y84962D02*
X724114Y84966D01*
G01X724113Y84961D02*
Y84962D01*
G01X737579Y80622D02*
Y80613D01*
G01X737580Y80628D02*
X737579Y80622D01*
G01X737581Y80630D02*
X737580Y80628D01*
G01X737579Y75622D02*
Y75613D01*
G01X737580Y75628D02*
X737579Y75622D01*
G01X737581Y75630D02*
X737580Y75628D01*
G01X737579Y70622D02*
Y70613D01*
G01X737580Y70628D02*
X737579Y70622D01*
G01X737581Y70630D02*
X737580Y70628D01*
G01X737579Y65622D02*
Y65613D01*
G01X737580Y65628D02*
X737579Y65622D01*
G01X737581Y65630D02*
X737580Y65628D01*
G01X737579Y60622D02*
Y60613D01*
G01X737580Y60628D02*
X737579Y60622D01*
G01X737581Y60630D02*
X737580Y60628D01*
G01X737579Y55622D02*
Y55613D01*
G01X737580Y55628D02*
X737579Y55622D01*
G01X737581Y55630D02*
X737580Y55628D01*
G01X737579Y50622D02*
Y50613D01*
G01X737580Y50628D02*
X737579Y50622D01*
G01X737581Y50630D02*
X737580Y50628D01*
G01X723169Y91226D02*
Y91234D01*
G01X723168Y91222D02*
X723169Y91226D01*
G01X723167Y91220D02*
X723168Y91222D01*
G01X723169Y88077D02*
Y88084D01*
G01X723168Y88072D02*
X723169Y88077D01*
G01X723167Y88071D02*
X723168Y88072D01*
G01X723169Y84927D02*
Y84935D01*
G01X723168Y84923D02*
X723169Y84927D01*
G01X723167Y84921D02*
X723168Y84923D01*
G01X724151Y93242D02*
X724154Y93254D01*
G01X724144Y93230D02*
X724151Y93242D01*
G01X724134Y93222D02*
X724144Y93230D01*
G01X724151Y90092D02*
X724154Y90104D01*
G01X724144Y90081D02*
X724151Y90092D01*
G01X724134Y90073D02*
X724144Y90081D01*
G01X724151Y86943D02*
X724154Y86955D01*
G01X724144Y86931D02*
X724151Y86943D01*
G01X724134Y86923D02*
X724144Y86931D01*
G01X724151Y83793D02*
X724154Y83805D01*
G01X724144Y83781D02*
X724151Y83793D01*
G01X724134Y83774D02*
X724144Y83781D01*
G01X723208Y91265D02*
Y91271D01*
G01Y91261D02*
Y91265D01*
G01X723206Y91260D02*
X723208Y91261D01*
G01Y88115D02*
Y88121D01*
G01Y88111D02*
Y88115D01*
G01X723206Y88110D02*
X723208Y88111D01*
G01Y84965D02*
Y84972D01*
G01Y84962D02*
Y84965D01*
G01X723206Y84961D02*
X723208Y84962D01*
G01X723170Y91240D02*
X723169Y91234D01*
G01X723172Y91246D02*
X723170Y91240D01*
G01X723174Y91252D02*
X723172Y91246D01*
G01X723178Y91257D02*
X723174Y91252D01*
G01X723183Y91262D02*
X723178Y91257D01*
G01X723189Y91266D02*
X723183Y91262D01*
G01X723170Y88091D02*
X723169Y88084D01*
G01X723172Y88097D02*
X723170Y88091D01*
G01X723174Y88103D02*
X723172Y88097D01*
G01X723178Y88108D02*
X723174Y88103D01*
G01X723183Y88113D02*
X723178Y88108D01*
G01X723189Y88116D02*
X723183Y88113D01*
G01X723170Y84941D02*
X723169Y84935D01*
G01X723172Y84947D02*
X723170Y84941D01*
G01X723174Y84953D02*
X723172Y84947D01*
G01X723178Y84958D02*
X723174Y84953D01*
G01X723183Y84963D02*
X723178Y84958D01*
G01X723189Y84967D02*
X723183Y84963D01*
G01X724125Y93230D02*
X724113Y93228D01*
G01X724135Y93235D02*
X724125Y93230D01*
G01Y90081D02*
X724113Y90079D01*
G01X724135Y90085D02*
X724125Y90081D01*
G01Y86931D02*
X724113Y86929D01*
G01X724135Y86936D02*
X724125Y86931D01*
G01Y83781D02*
X724113Y83780D01*
G01X724135Y83786D02*
X724125Y83781D01*
G01X728150Y25138D02*
G03X728740Y24547I590J-1D01*
G01X735433D02*
G03X736024Y25138I0J591D01*
G01X733268Y26319D02*
G03Y28287I0J984D01*
G01X730906D02*
G03Y26319I0J-984D01*
G01X733189Y39508D02*
G03I-1102J0D01*
G01X734646Y34232D02*
G03X735827Y35413I0J1181D01*
G01X728346D02*
G03X729528Y34232I1181J0D01*
G01X733661Y39508D02*
G03I-1574J0D01*
G01X721260Y25728D02*
G03X723228Y23760I1968J0D01*
G01X740945D02*
G03X742913Y25728I0J1968D01*
G01X727559Y47500D02*
X726378Y46319D01*
G01X724606Y44823D02*
X721260Y41476D01*
G01X734571Y42579D02*
X733268Y40610D01*
G01X728595Y34688D02*
X730906Y38917D01*
G01X724153Y84923D02*
X724154Y84935D01*
G01X724153Y88073D02*
X724154Y88084D01*
G01X724153Y91222D02*
X724154Y91234D01*
G01X737579Y51982D02*
Y51991D01*
G01Y56982D02*
Y56991D01*
G01Y61982D02*
Y61991D01*
G01Y66982D02*
Y66991D01*
G01Y71982D02*
Y71991D01*
G01Y76982D02*
Y76991D01*
G01Y81982D02*
Y81991D01*
G01X742913Y25728D02*
Y41476D01*
G01X741929Y80630D02*
Y82008D01*
G01Y75630D02*
Y77008D01*
G01Y70630D02*
Y72008D01*
G01Y65630D02*
Y67008D01*
G01Y60630D02*
Y62008D01*
G01Y55630D02*
Y57008D01*
G01Y50630D02*
Y52008D01*
G01X739567Y182815D02*
Y44823D01*
G01X738976Y185059D02*
Y42579D01*
G01X738760Y52008D02*
Y50630D01*
G01Y57008D02*
Y55630D01*
G01Y62008D02*
Y60630D01*
G01Y67008D02*
Y65630D01*
G01Y72008D02*
Y70630D01*
G01Y77008D02*
Y75630D01*
G01Y82008D02*
Y80630D01*
G01X738189Y104862D02*
Y82776D01*
G01X737579Y51982D02*
Y52125D01*
G01Y56982D02*
Y57125D01*
G01Y61982D02*
Y62125D01*
G01Y66982D02*
Y67125D01*
G01Y71982D02*
Y72125D01*
G01Y76982D02*
Y77125D01*
G01Y81982D02*
Y82125D01*
G01Y80138D02*
Y82500D01*
G01Y75138D02*
Y77500D01*
G01Y70138D02*
Y72500D01*
G01Y65138D02*
Y67500D01*
G01Y60138D02*
Y62500D01*
G01Y55138D02*
Y57500D01*
G01Y50138D02*
Y52500D01*
G01X737008Y103681D02*
Y83957D01*
G01X736594Y52500D02*
Y50138D01*
G01Y57500D02*
Y55138D01*
G01Y62500D02*
Y60138D01*
G01Y67500D02*
Y65138D01*
G01Y72500D02*
Y70138D01*
G01Y77500D02*
Y75138D01*
G01Y82500D02*
Y80138D01*
G01X736024Y31240D02*
Y25138D01*
G01X735827Y43957D02*
Y35413D01*
G01X734252Y82776D02*
Y46319D01*
G01X733268Y40610D02*
Y38917D01*
G01X733071Y83957D02*
Y47500D01*
G01X730906Y38917D02*
Y40610D01*
G01X728346Y35413D02*
Y43957D01*
G01X728150Y31240D02*
Y25138D01*
G01X727559Y47500D02*
Y180138D01*
G01X726378Y46319D02*
Y181319D01*
G01X724606Y81614D02*
Y42579D01*
G01X724154Y93070D02*
Y94567D01*
G01Y89921D02*
Y91417D01*
G01Y86771D02*
Y88268D01*
G01Y83622D02*
Y85118D01*
G01X724114Y86918D02*
Y86771D01*
G01Y83768D02*
Y83621D01*
G01Y85119D02*
Y84972D01*
G01Y90067D02*
Y89920D01*
G01Y91418D02*
Y91271D01*
G01Y88268D02*
Y88121D01*
G01Y93217D02*
Y93070D01*
G01X723209D02*
Y93217D01*
G01Y89920D02*
Y90067D01*
G01Y91271D02*
Y91418D01*
G01Y88121D02*
Y88268D01*
G01Y86771D02*
Y86918D01*
G01Y83621D02*
Y83768D01*
G01Y84972D02*
Y85119D01*
G01X723169Y85118D02*
Y83622D01*
G01Y91417D02*
Y89921D01*
G01Y88268D02*
Y86772D01*
G01Y94567D02*
Y93071D01*
G01X721988Y88110D02*
Y86929D01*
G01Y84961D02*
Y83780D01*
G01Y91260D02*
Y90079D01*
G01Y94409D02*
Y93228D01*
G01X721654Y106024D02*
Y81614D01*
G01X721260D02*
Y106024D01*
G01Y41476D02*
Y25728D01*
G01X718228Y93228D02*
Y94409D01*
G01Y90079D02*
Y91260D01*
G01Y86929D02*
Y88110D01*
G01Y83780D02*
Y84961D01*
G01X724154Y93254D02*
X724153Y93265D01*
G01X724154Y90105D02*
X724153Y90115D01*
G01X724154Y86955D02*
X724153Y86966D01*
G01X724154Y83806D02*
X724153Y83816D01*
G01X733268Y38917D02*
X735578Y34688D01*
G01X730906Y40610D02*
X729602Y42579D01*
G01X737008Y83957D02*
X738189Y82776D01*
G01X733071Y83957D02*
X734252Y82776D01*
G01X739567Y44823D02*
X742913Y41476D01*
G01X733071Y47500D02*
X734252Y46319D01*
G01X723167Y93263D02*
X723056Y93268D01*
G01X723167Y86965D02*
X723056Y86969D01*
G01X724152Y93268D02*
X718228D01*
G01X724113Y93228D02*
X718228D01*
G01X723169Y93071D02*
X724154D01*
G01X723209Y93031D02*
X724114D01*
G01Y91457D02*
X723209D01*
G01X724154Y91417D02*
X723169D01*
G01X724113Y91260D02*
X718228D01*
G01Y91220D02*
X724152D01*
G01Y90118D02*
X718228D01*
G01X724113Y90079D02*
X718228D01*
G01X723169Y89921D02*
X724154D01*
G01X723209Y89882D02*
X724114D01*
G01Y88307D02*
X723209D01*
G01X724154Y88268D02*
X723169D01*
G01X724113Y88110D02*
X718228D01*
G01Y88071D02*
X724152D01*
G01Y86969D02*
X718228D01*
G01X724113Y86929D02*
X718228D01*
G01X723169Y86772D02*
X724154D01*
G01X723209Y86732D02*
X724114D01*
G01Y85157D02*
X723209D01*
G01X724154Y85118D02*
X723169D01*
G01X724113Y84961D02*
X718228D01*
G01Y84921D02*
X724152D01*
G01X737008Y83957D02*
X733071D01*
G01X724152Y83819D02*
X718228D01*
G01X724113Y83780D02*
X718228D01*
G01X723169Y83622D02*
X724154D01*
G01X723209Y83583D02*
X724114D01*
G01X738189Y82776D02*
X734252D01*
G01X737579Y82500D02*
X736594D01*
G01X736596Y82008D02*
X741929D01*
G01Y81969D02*
X737581D01*
G01X724606Y81614D02*
X721260D01*
G01X741929Y80630D02*
X736596D01*
G01X736594Y80138D02*
X737579D01*
G01Y77500D02*
X736594D01*
G01X736596Y77008D02*
X741929D01*
G01Y76969D02*
X737581D01*
G01X741929Y75630D02*
X736596D01*
G01X736594Y75138D02*
X737579D01*
G01Y72500D02*
X736594D01*
G01X736596Y72008D02*
X741929D01*
G01Y71969D02*
X737581D01*
G01X741929Y70630D02*
X736596D01*
G01X736594Y70138D02*
X737579D01*
G01Y67500D02*
X736594D01*
G01X736596Y67008D02*
X741929D01*
G01Y66969D02*
X737581D01*
G01X741929Y65630D02*
X736596D01*
G01X736594Y65138D02*
X737579D01*
G01Y62500D02*
X736594D01*
G01X736596Y62008D02*
X741929D01*
G01Y61969D02*
X737581D01*
G01X741929Y60630D02*
X736596D01*
G01X736594Y60138D02*
X737579D01*
G01Y57500D02*
X736594D01*
G01X736596Y57008D02*
X741929D01*
G01Y56969D02*
X737581D01*
G01X741929Y55630D02*
X736596D01*
G01X736594Y55138D02*
X737579D01*
G01Y52500D02*
X736594D01*
G01X736596Y52008D02*
X741929D01*
G01Y51969D02*
X737581D01*
G01X741929Y50630D02*
X736596D01*
G01X736594Y50138D02*
X737579D01*
G01X733071Y47500D02*
X727559D01*
G01X734252Y46319D02*
X726378D01*
G01X739567Y44823D02*
X724606D01*
G01X735827Y43957D02*
X738976D01*
G01X728346D02*
X724606D01*
G01Y42579D02*
X738976D01*
G01X733268Y40610D02*
X730906D01*
G01X733268Y38917D02*
X730906D01*
G01X736594Y82204D02*
X737550Y82205D01*
G01X737579Y80434D02*
X736594Y80433D01*
G01Y77204D02*
X737550Y77205D01*
G01X737579Y75434D02*
X736594Y75433D01*
G01Y72204D02*
X737550Y72205D01*
G01X737579Y70434D02*
X736594Y70433D01*
G01Y67204D02*
X737550Y67205D01*
G01X737579Y65434D02*
X736594Y65433D01*
G01Y62204D02*
X737550Y62205D01*
G01X737579Y60434D02*
X736594Y60433D01*
G01Y57204D02*
X737550Y57205D01*
G01X737579Y55434D02*
X736594Y55433D01*
G01Y52204D02*
X737550Y52205D01*
G01X737579Y50434D02*
X736594Y50433D01*
G01X734646Y34232D02*
X729528D01*
G01X742913Y34193D02*
X721260D01*
G01X736024Y31240D02*
X728150D01*
G01Y29665D02*
X736024D01*
G01X733268Y28287D02*
X730906D01*
G01Y26319D02*
X733268D01*
G01X735433Y24547D02*
X728740D01*
G01X740945Y23760D02*
X723228D01*
G01X723192Y94417D02*
X723189Y94415D01*
G01X723195Y94418D02*
X723192Y94417D01*
G01X723198Y94419D02*
X723195Y94418D01*
G01X723202Y94420D02*
X723198Y94419D01*
G01X723205Y94420D02*
X723202D01*
G01X723209D02*
X723205D01*
G01X724131Y96370D02*
X724134Y96372D01*
G01X724128Y96369D02*
X724131Y96370D01*
G01X724125Y96368D02*
X724128Y96369D01*
G01X724121Y96367D02*
X724125Y96368D01*
G01X724118Y96367D02*
X724121D01*
G01X724114D02*
X724118D01*
G01X723192Y97567D02*
X723189Y97565D01*
G01X723195Y97568D02*
X723192Y97567D01*
G01X723198Y97569D02*
X723195Y97568D01*
G01X723202Y97570D02*
X723198Y97569D01*
G01X723205Y97570D02*
X723202D01*
G01X723209D02*
X723205D01*
G01X723192Y100716D02*
X723189Y100715D01*
G01X723195Y100717D02*
X723192Y100716D01*
G01X723198Y100719D02*
X723195Y100717D01*
G01X723202Y100719D02*
X723198D01*
G01X723205Y100720D02*
X723202Y100719D01*
G01X723209Y100720D02*
X723205D01*
G01X724131Y102669D02*
X724134Y102671D01*
G01X724128Y102668D02*
X724131Y102669D01*
G01X724125Y102667D02*
X724128Y102668D01*
G01X724121Y102667D02*
X724125D01*
G01X724118Y102666D02*
X724121Y102667D01*
G01X724114Y102666D02*
X724118D01*
G01X723192Y103866D02*
X723189Y103864D01*
G01X723195Y103867D02*
X723192Y103866D01*
G01X723198Y103868D02*
X723195Y103867D01*
G01X723202Y103869D02*
X723198Y103868D01*
G01X723205Y103869D02*
X723202D01*
G01X723209D02*
X723205D01*
G01X722422Y96417D02*
X721988D01*
G01X722796D02*
X722422D01*
G01X724144Y94408D02*
X724148Y94402D01*
G01X724139Y94412D02*
X724144Y94408D01*
G01X724133Y94416D02*
X724139Y94412D01*
G01X724128Y94419D02*
X724133Y94416D01*
G01X724121Y94420D02*
X724128Y94419D01*
G01X724114Y94420D02*
X724121D01*
G01X724144Y97557D02*
X724148Y97552D01*
G01X724139Y97562D02*
X724144Y97557D01*
G01X724133Y97565D02*
X724139Y97562D01*
G01X724128Y97568D02*
X724133Y97565D01*
G01X724121Y97570D02*
X724128Y97568D01*
G01X724114Y97570D02*
X724121D01*
G01X724144Y100707D02*
X724148Y100702D01*
G01X724139Y100711D02*
X724144Y100707D01*
G01X724133Y100715D02*
X724139Y100711D01*
G01X724128Y100718D02*
X724133Y100715D01*
G01X724121Y100719D02*
X724128Y100718D01*
G01X724114Y100720D02*
X724121Y100719D01*
G01X724144Y103857D02*
X724148Y103851D01*
G01X724139Y103861D02*
X724144Y103857D01*
G01X724133Y103865D02*
X724139Y103861D01*
G01X724128Y103867D02*
X724133Y103865D01*
G01X724121Y103869D02*
X724128Y103867D01*
G01X724114Y103869D02*
X724121D01*
G01X723170Y96396D02*
X723169Y96404D01*
G01X723172Y96389D02*
X723170Y96396D01*
G01X723176Y96383D02*
X723172Y96389D01*
G01X723181Y96378D02*
X723176Y96383D01*
G01X723187Y96373D02*
X723181Y96378D01*
G01X723194Y96369D02*
X723187Y96373D01*
G01X723201Y96367D02*
X723194Y96369D01*
G01X723209Y96367D02*
X723201D01*
G01X723170Y99546D02*
X723169Y99553D01*
G01X723172Y99539D02*
X723170Y99546D01*
G01X723176Y99533D02*
X723172Y99539D01*
G01X723181Y99527D02*
X723176Y99533D01*
G01X723187Y99522D02*
X723181Y99527D01*
G01X723194Y99519D02*
X723187Y99522D01*
G01X723201Y99517D02*
X723194Y99519D01*
G01X723209Y99516D02*
X723201Y99517D01*
G01X723170Y102696D02*
X723169Y102703D01*
G01X723172Y102689D02*
X723170Y102696D01*
G01X723176Y102682D02*
X723172Y102689D01*
G01X723181Y102677D02*
X723176Y102682D01*
G01X723187Y102672D02*
X723181Y102677D01*
G01X723194Y102669D02*
X723187Y102672D01*
G01X723201Y102667D02*
X723194Y102669D01*
G01X723209Y102666D02*
X723201Y102667D01*
G01X724123Y94408D02*
X724133Y94404D01*
G01X724113Y94409D02*
X724123Y94408D01*
G01Y97557D02*
X724133Y97554D01*
G01X724113Y97559D02*
X724123Y97557D01*
G01Y100707D02*
X724133Y100703D01*
G01X724113Y100709D02*
X724123Y100707D01*
G01Y103857D02*
X724133Y103853D01*
G01X724113Y103858D02*
X724123Y103857D01*
G01X723169Y96407D02*
Y96404D01*
G01X723171Y96401D02*
X723169Y96407D01*
G01X723182Y96386D02*
X723171Y96401D01*
G01X723207Y96378D02*
X723182Y96386D01*
G01X723169Y99557D02*
Y99553D01*
G01X723171Y99551D02*
X723169Y99557D01*
G01X723182Y99536D02*
X723171Y99551D01*
G01X723207Y99528D02*
X723182Y99536D01*
G01X723169Y102707D02*
Y102703D01*
G01X723171Y102701D02*
X723169Y102707D01*
G01X723182Y102685D02*
X723171Y102701D01*
G01X723207Y102677D02*
X723182Y102685D01*
G01X737566Y106999D02*
X737577Y106984D01*
G01X737542Y107008D02*
X737566Y106999D01*
G01Y111999D02*
X737577Y111984D01*
G01X737542Y112008D02*
X737566Y111999D01*
G01Y116999D02*
X737577Y116984D01*
G01X737542Y117008D02*
X737566Y116999D01*
G01Y121999D02*
X737577Y121984D01*
G01X737542Y122008D02*
X737566Y121999D01*
G01Y126999D02*
X737577Y126984D01*
G01X737542Y127008D02*
X737566Y126999D01*
G01Y131999D02*
X737577Y131984D01*
G01X737542Y132008D02*
X737566Y131999D01*
G01Y136999D02*
X737577Y136984D01*
G01X737542Y137008D02*
X737566Y136999D01*
G01Y141999D02*
X737577Y141984D01*
G01X737542Y142008D02*
X737566Y141999D01*
G01Y146999D02*
X737577Y146984D01*
G01X737542Y147008D02*
X737566Y146999D01*
G01Y151999D02*
X737577Y151984D01*
G01X737542Y152008D02*
X737566Y151999D01*
G01Y156999D02*
X737577Y156984D01*
G01X737542Y157008D02*
X737566Y156999D01*
G01X724122Y94408D02*
X724113Y94409D01*
G01X724131Y94405D02*
X724122Y94408D01*
G01X724139Y94400D02*
X724131Y94405D01*
G01X724122Y97558D02*
X724113Y97559D01*
G01X724131Y97555D02*
X724122Y97558D01*
G01X724139Y97549D02*
X724131Y97555D01*
G01X724122Y100707D02*
X724113Y100709D01*
G01X724131Y100704D02*
X724122Y100707D01*
G01X724139Y100699D02*
X724131Y100704D01*
G01X724122Y103857D02*
X724113Y103858D01*
G01X724131Y103854D02*
X724122Y103857D01*
G01X724139Y103848D02*
X724131Y103854D01*
G01X723208Y96373D02*
X723209Y96367D01*
G01X723207Y96377D02*
X723208Y96373D01*
G01X723206Y96378D02*
X723207Y96377D01*
G01X723208Y99522D02*
X723209Y99516D01*
G01X723207Y99526D02*
X723208Y99522D01*
G01X723206Y99528D02*
X723207Y99526D01*
G01X723208Y102672D02*
X723209Y102666D01*
G01X723207Y102676D02*
X723208Y102672D01*
G01X723206Y102677D02*
X723207Y102676D01*
G01X723172Y94390D02*
X723167Y94370D01*
G01X723187Y94404D02*
X723172Y94390D01*
G01X723206Y94409D02*
X723187Y94404D01*
G01X723172Y97539D02*
X723167Y97520D01*
G01X723187Y97554D02*
X723172Y97539D01*
G01X723206Y97559D02*
X723187Y97554D01*
G01X723172Y100689D02*
X723167Y100669D01*
G01X723187Y100703D02*
X723172Y100689D01*
G01X723206Y100709D02*
X723187Y100703D01*
G01X723172Y103839D02*
X723167Y103819D01*
G01X723187Y103853D02*
X723172Y103839D01*
G01X723206Y103858D02*
X723187Y103853D01*
G01X724147Y96398D02*
X724152Y96417D01*
G01X724132Y96383D02*
X724147Y96398D01*
G01X724113Y96378D02*
X724132Y96383D01*
G01X724147Y99547D02*
X724152Y99567D01*
G01X724132Y99533D02*
X724147Y99547D01*
G01X724113Y99528D02*
X724132Y99533D01*
G01X724147Y102697D02*
X724152Y102717D01*
G01X724132Y102682D02*
X724147Y102697D01*
G01X724113Y102677D02*
X724132Y102682D01*
G01X724153Y99546D02*
X724154Y99553D01*
G01X724150Y99539D02*
X724153Y99546D01*
G01X724147Y99533D02*
X724150Y99539D01*
G01X724142Y99527D02*
X724147Y99533D01*
G01X724136Y99522D02*
X724142Y99527D01*
G01X724129Y99519D02*
X724136Y99522D01*
G01X724122Y99517D02*
X724129Y99519D01*
G01X724114Y99516D02*
X724122Y99517D01*
G01X737566Y161999D02*
X737577Y161984D01*
G01X737542Y162008D02*
X737566Y161999D01*
G01Y166999D02*
X737577Y166984D01*
G01X737542Y167008D02*
X737566Y166999D01*
G01Y171999D02*
X737577Y171984D01*
G01X737542Y172008D02*
X737566Y171999D01*
G01Y176999D02*
X737577Y176984D01*
G01X737542Y177008D02*
X737566Y176999D01*
G01X737579Y106975D02*
Y106982D01*
G01X737580Y106970D02*
X737579Y106975D01*
G01X737581Y106969D02*
X737580Y106970D01*
G01X737579Y111975D02*
Y111982D01*
G01X737580Y111970D02*
X737579Y111975D01*
G01X737581Y111969D02*
X737580Y111970D01*
G01X737579Y116975D02*
Y116982D01*
G01X737580Y116970D02*
X737579Y116975D01*
G01X737581Y116969D02*
X737580Y116970D01*
G01X737579Y121975D02*
Y121982D01*
G01X737580Y121970D02*
X737579Y121975D01*
G01X737581Y121969D02*
X737580Y121970D01*
G01X737579Y126975D02*
Y126982D01*
G01X737580Y126970D02*
X737579Y126975D01*
G01X737581Y126969D02*
X737580Y126970D01*
G01X737579Y131975D02*
Y131982D01*
G01X737580Y131970D02*
X737579Y131975D01*
G01X737581Y131969D02*
X737580Y131970D01*
G01X723192Y96380D02*
X723206Y96378D01*
G01X723180Y96388D02*
X723192Y96380D01*
G01X723169Y96406D02*
X723180Y96388D01*
G01X737579Y136975D02*
Y136982D01*
G01X737580Y136970D02*
X737579Y136975D01*
G01X737581Y136969D02*
X737580Y136970D01*
G01X737579Y141975D02*
Y141982D01*
G01X737580Y141970D02*
X737579Y141975D01*
G01X737581Y141969D02*
X737580Y141970D01*
G01X737579Y146975D02*
Y146982D01*
G01X737580Y146970D02*
X737579Y146975D01*
G01X737581Y146969D02*
X737580Y146970D01*
G01X737579Y151975D02*
Y151982D01*
G01X737580Y151970D02*
X737579Y151975D01*
G01X737581Y151969D02*
X737580Y151970D01*
G01X737579Y156975D02*
Y156982D01*
G01X737580Y156970D02*
X737579Y156975D01*
G01X737581Y156969D02*
X737580Y156970D01*
G01X737579Y161975D02*
Y161982D01*
G01X737580Y161970D02*
X737579Y161975D01*
G01X737581Y161969D02*
X737580Y161970D01*
G01X737579Y166975D02*
Y166982D01*
G01X737580Y166970D02*
X737579Y166975D01*
G01X737581Y166969D02*
X737580Y166970D01*
G01X737579Y171975D02*
Y171982D01*
G01X737580Y171970D02*
X737579Y171975D01*
G01X737581Y171969D02*
X737580Y171970D01*
G01X737579Y176975D02*
Y176982D01*
G01X737580Y176970D02*
X737579Y176975D01*
G01X737581Y176969D02*
X737580Y176970D01*
G01X723192Y99530D02*
X723206Y99528D01*
G01X723180Y99538D02*
X723192Y99530D01*
G01X723168Y99558D02*
X723180Y99538D01*
G01X724154Y96411D02*
Y96404D01*
G01X724153Y96416D02*
X724154Y96411D01*
G01X724152Y96417D02*
X724153Y96416D01*
G01X724154Y99561D02*
Y99553D01*
G01X724153Y99565D02*
X724154Y99561D01*
G01X724152Y99567D02*
X724153Y99565D01*
G01X724154Y102711D02*
Y102703D01*
G01X724153Y102715D02*
X724154Y102711D01*
G01X724152Y102717D02*
X724153Y102715D01*
G01X723192Y102680D02*
X723206Y102677D01*
G01X723179Y102688D02*
X723192Y102680D01*
G01X723168Y102708D02*
X723179Y102688D01*
G01X724153Y94390D02*
X724154Y94383D01*
G01X724151Y94396D02*
X724153Y94390D01*
G01X724148Y94402D02*
X724151Y94396D01*
G01X724153Y97540D02*
X724154Y97533D01*
G01X724151Y97546D02*
X724153Y97540D01*
G01X724148Y97552D02*
X724151Y97546D01*
G01X724153Y100689D02*
X724154Y100683D01*
G01X724151Y100696D02*
X724153Y100689D01*
G01X724148Y100702D02*
X724151Y100696D01*
G01X724153Y103839D02*
X724154Y103832D01*
G01X724151Y103845D02*
X724153Y103839D01*
G01X724148Y103851D02*
X724151Y103845D01*
G01X724115Y96373D02*
Y96367D01*
G01X724113Y96376D02*
X724115Y96373D01*
G01X724113Y96378D02*
Y96376D01*
G01X724115Y102672D02*
Y102666D01*
G01X724113Y102676D02*
X724115Y102672D01*
G01X724113Y102677D02*
Y102676D01*
G01X736594Y107015D02*
Y107024D01*
G01X736595Y107009D02*
X736594Y107015D01*
G01X736596Y107008D02*
X736595Y107009D01*
G01X736594Y112015D02*
Y112024D01*
G01X736595Y112009D02*
X736594Y112015D01*
G01X736596Y112008D02*
X736595Y112009D01*
G01X736594Y117015D02*
Y117024D01*
G01X736595Y117009D02*
X736594Y117015D01*
G01X736596Y117008D02*
X736595Y117009D01*
G01X736594Y122015D02*
Y122024D01*
G01X736595Y122009D02*
X736594Y122015D01*
G01X736596Y122008D02*
X736595Y122009D01*
G01X736594Y127015D02*
Y127024D01*
G01X736595Y127009D02*
X736594Y127015D01*
G01X736596Y127008D02*
X736595Y127009D01*
G01X736594Y132015D02*
Y132024D01*
G01X736595Y132009D02*
X736594Y132015D01*
G01X736596Y132008D02*
X736595Y132009D01*
G01X736594Y137015D02*
Y137024D01*
G01X736595Y137009D02*
X736594Y137015D01*
G01X736596Y137008D02*
X736595Y137009D01*
G01X736594Y142015D02*
Y142024D01*
G01X736595Y142009D02*
X736594Y142015D01*
G01X736596Y142008D02*
X736595Y142009D01*
G01X736594Y147015D02*
Y147024D01*
G01X736595Y147009D02*
X736594Y147015D01*
G01X736596Y147008D02*
X736595Y147009D01*
G01X736594Y152015D02*
Y152024D01*
G01X736595Y152009D02*
X736594Y152015D01*
G01X736596Y152008D02*
X736595Y152009D01*
G01X736594Y157015D02*
Y157024D01*
G01X736595Y157009D02*
X736594Y157015D01*
G01X736596Y157008D02*
X736595Y157009D01*
G01X736594Y162015D02*
Y162024D01*
G01X736595Y162009D02*
X736594Y162015D01*
G01X736596Y162008D02*
X736595Y162009D01*
G01X736594Y167015D02*
Y167024D01*
G01X736595Y167009D02*
X736594Y167015D01*
G01X736596Y167008D02*
X736595Y167009D01*
G01X736594Y172015D02*
Y172024D01*
G01X736595Y172009D02*
X736594Y172015D01*
G01X736596Y172008D02*
X736595Y172009D01*
G01X736594Y177015D02*
Y177024D01*
G01X736595Y177009D02*
X736594Y177015D01*
G01X736596Y177008D02*
X736595Y177009D01*
G01X737571Y107152D02*
X737579Y107125D01*
G01X737561Y107178D02*
X737571Y107152D01*
G01X737550Y107205D02*
X737561Y107178D01*
G01X737571Y112152D02*
X737579Y112125D01*
G01X737561Y112178D02*
X737571Y112152D01*
G01X737550Y112205D02*
X737561Y112178D01*
G01X737571Y117152D02*
X737579Y117125D01*
G01X737561Y117178D02*
X737571Y117152D01*
G01X737550Y117205D02*
X737561Y117178D01*
G01X737571Y122152D02*
X737579Y122125D01*
G01X737561Y122178D02*
X737571Y122152D01*
G01X737550Y122205D02*
X737561Y122178D01*
G01X737571Y127152D02*
X737579Y127125D01*
G01X737561Y127178D02*
X737571Y127152D01*
G01X737550Y127205D02*
X737561Y127178D01*
G01X737571Y132152D02*
X737579Y132125D01*
G01X737561Y132178D02*
X737571Y132152D01*
G01X737550Y132205D02*
X737561Y132178D01*
G01X737571Y137152D02*
X737579Y137125D01*
G01X737561Y137178D02*
X737571Y137152D01*
G01X737550Y137205D02*
X737561Y137178D01*
G01X737571Y142152D02*
X737579Y142125D01*
G01X737561Y142178D02*
X737571Y142152D01*
G01X737550Y142205D02*
X737561Y142178D01*
G01X737571Y147152D02*
X737579Y147125D01*
G01X737561Y147178D02*
X737571Y147152D01*
G01X737550Y147205D02*
X737561Y147178D01*
G01X737571Y152152D02*
X737579Y152125D01*
G01X737561Y152178D02*
X737571Y152152D01*
G01X737550Y152205D02*
X737561Y152178D01*
G01X737571Y157152D02*
X737579Y157125D01*
G01X737561Y157178D02*
X737571Y157152D01*
G01X737550Y157205D02*
X737561Y157178D01*
G01X737571Y162152D02*
X737579Y162125D01*
G01X737561Y162178D02*
X737571Y162152D01*
G01X737550Y162205D02*
X737561Y162178D01*
G01X737571Y167152D02*
X737579Y167125D01*
G01X737561Y167178D02*
X737571Y167152D01*
G01X737550Y167205D02*
X737561Y167178D01*
G01X737571Y172152D02*
X737579Y172125D01*
G01X737561Y172178D02*
X737571Y172152D01*
G01X737550Y172205D02*
X737561Y172178D01*
G01X737571Y177152D02*
X737579Y177125D01*
G01X737561Y177178D02*
X737571Y177152D01*
G01X737550Y177205D02*
X737561Y177178D01*
G01Y107003D02*
X737542Y107008D01*
G01X737576Y106988D02*
X737561Y107003D01*
G01X737581Y106969D02*
X737576Y106988D01*
G01X737561Y112003D02*
X737542Y112008D01*
G01X737576Y111988D02*
X737561Y112003D01*
G01X737581Y111969D02*
X737576Y111988D01*
G01X737561Y117003D02*
X737542Y117008D01*
G01X737576Y116988D02*
X737561Y117003D01*
G01X737581Y116969D02*
X737576Y116988D01*
G01X737561Y122003D02*
X737542Y122008D01*
G01X737576Y121988D02*
X737561Y122003D01*
G01X737581Y121969D02*
X737576Y121988D01*
G01X737561Y127003D02*
X737542Y127008D01*
G01X737576Y126988D02*
X737561Y127003D01*
G01X737581Y126969D02*
X737576Y126988D01*
G01X737561Y132003D02*
X737542Y132008D01*
G01X737576Y131988D02*
X737561Y132003D01*
G01X737581Y131969D02*
X737576Y131988D01*
G01X737561Y137003D02*
X737542Y137008D01*
G01X737576Y136988D02*
X737561Y137003D01*
G01X737581Y136969D02*
X737576Y136988D01*
G01X737561Y142003D02*
X737542Y142008D01*
G01X737576Y141988D02*
X737561Y142003D01*
G01X737581Y141969D02*
X737576Y141988D01*
G01X737561Y147003D02*
X737542Y147008D01*
G01X737576Y146988D02*
X737561Y147003D01*
G01X737581Y146969D02*
X737576Y146988D01*
G01X737561Y152003D02*
X737542Y152008D01*
G01X737576Y151988D02*
X737561Y152003D01*
G01X737581Y151969D02*
X737576Y151988D01*
G01X737561Y157003D02*
X737542Y157008D01*
G01X737576Y156988D02*
X737561Y157003D01*
G01X737581Y156969D02*
X737576Y156988D01*
G01X737561Y162003D02*
X737542Y162008D01*
G01X737576Y161988D02*
X737561Y162003D01*
G01X737581Y161969D02*
X737576Y161988D01*
G01X737561Y167003D02*
X737542Y167008D01*
G01X737576Y166988D02*
X737561Y167003D01*
G01X737581Y166969D02*
X737576Y166988D01*
G01X737561Y172003D02*
X737542Y172008D01*
G01X737576Y171988D02*
X737561Y172003D01*
G01X737581Y171969D02*
X737576Y171988D01*
G01X737561Y177003D02*
X737542Y177008D01*
G01X737576Y176988D02*
X737561Y177003D01*
G01X737581Y176969D02*
X737576Y176988D01*
G01X724146Y94391D02*
X724139Y94400D01*
G01X724151Y94381D02*
X724146Y94391D01*
G01X724152Y94370D02*
X724151Y94381D01*
G01X724146Y97541D02*
X724139Y97549D01*
G01X724151Y97531D02*
X724146Y97541D01*
G01X724152Y97520D02*
X724151Y97531D01*
G01X724146Y100691D02*
X724139Y100699D01*
G01X724151Y100680D02*
X724146Y100691D01*
G01X724152Y100669D02*
X724151Y100680D01*
G01X724146Y103840D02*
X724139Y103848D01*
G01X724151Y103830D02*
X724146Y103840D01*
G01X724152Y103819D02*
X724151Y103830D01*
G01X737546Y107106D02*
X737550Y107205D01*
G01X737540Y107034D02*
X737546Y107106D01*
G01X737542Y107008D02*
X737540Y107034D01*
G01X737546Y112106D02*
X737550Y112205D01*
G01X737540Y112034D02*
X737546Y112106D01*
G01X737542Y112008D02*
X737540Y112034D01*
G01X737546Y117106D02*
X737550Y117205D01*
G01X737540Y117034D02*
X737546Y117106D01*
G01X737542Y117008D02*
X737540Y117034D01*
G01X737546Y122106D02*
X737550Y122205D01*
G01X737540Y122034D02*
X737546Y122106D01*
G01X737542Y122008D02*
X737540Y122034D01*
G01X737546Y127106D02*
X737550Y127205D01*
G01X737540Y127034D02*
X737546Y127106D01*
G01X737542Y127008D02*
X737540Y127034D01*
G01X737546Y132106D02*
X737550Y132205D01*
G01X737540Y132034D02*
X737546Y132106D01*
G01X737542Y132008D02*
X737540Y132034D01*
G01X737546Y137106D02*
X737550Y137205D01*
G01X737540Y137034D02*
X737546Y137106D01*
G01X737542Y137008D02*
X737540Y137034D01*
G01X737546Y142106D02*
X737550Y142205D01*
G01X737540Y142034D02*
X737546Y142106D01*
G01X737542Y142008D02*
X737540Y142034D01*
G01X737546Y147106D02*
X737550Y147205D01*
G01X737540Y147034D02*
X737546Y147106D01*
G01X737542Y147008D02*
X737540Y147034D01*
G01X737546Y152106D02*
X737550Y152205D01*
G01X737540Y152034D02*
X737546Y152106D01*
G01X737542Y152008D02*
X737540Y152034D01*
G01X737546Y157106D02*
X737550Y157205D01*
G01X737540Y157034D02*
X737546Y157106D01*
G01X737542Y157008D02*
X737540Y157034D01*
G01X737546Y162106D02*
X737550Y162205D01*
G01X737540Y162034D02*
X737546Y162106D01*
G01X737542Y162008D02*
X737540Y162034D01*
G01X737546Y167106D02*
X737550Y167205D01*
G01X737540Y167034D02*
X737546Y167106D01*
G01X737542Y167008D02*
X737540Y167034D01*
G01X737546Y172106D02*
X737550Y172205D01*
G01X737540Y172034D02*
X737546Y172106D01*
G01X737542Y172008D02*
X737540Y172034D01*
G01X737546Y177106D02*
X737550Y177205D01*
G01X737540Y177034D02*
X737546Y177106D01*
G01X737542Y177008D02*
X737540Y177034D01*
G01X723169Y96411D02*
Y96404D01*
G01X723168Y96416D02*
X723169Y96411D01*
G01Y96406D02*
X723168Y96416D01*
G01X723209Y104043D02*
Y104055D01*
G01X723206Y104030D02*
X723209Y104043D01*
G01X723206Y104016D02*
Y104030D01*
G01X723209Y100893D02*
Y100906D01*
G01X723206Y100880D02*
X723209Y100893D01*
G01X723206Y100866D02*
Y100880D01*
G01X723209Y97743D02*
Y97756D01*
G01X723206Y97730D02*
X723209Y97743D01*
G01X723206Y97717D02*
Y97730D01*
G01X723209Y94594D02*
Y94606D01*
G01X723206Y94581D02*
X723209Y94594D01*
G01X723206Y94567D02*
Y94581D01*
G01X736595Y175628D02*
X736596Y175630D01*
G01X736594Y175622D02*
X736595Y175628D01*
G01X736594Y175614D02*
Y175622D01*
G01X736595Y170628D02*
X736596Y170630D01*
G01X736594Y170622D02*
X736595Y170628D01*
G01X736594Y170614D02*
Y170622D01*
G01X736595Y165628D02*
X736596Y165630D01*
G01X736594Y165622D02*
X736595Y165628D01*
G01X736594Y165614D02*
Y165622D01*
G01X736595Y160628D02*
X736596Y160630D01*
G01X736594Y160622D02*
X736595Y160628D01*
G01X736594Y160614D02*
Y160622D01*
G01X736595Y155628D02*
X736596Y155630D01*
G01X736594Y155622D02*
X736595Y155628D01*
G01X736594Y155614D02*
Y155622D01*
G01X736595Y150628D02*
X736596Y150630D01*
G01X736594Y150622D02*
X736595Y150628D01*
G01X736594Y150614D02*
Y150622D01*
G01X736595Y145628D02*
X736596Y145630D01*
G01X736594Y145622D02*
X736595Y145628D01*
G01X736594Y145614D02*
Y145622D01*
G01X736595Y140628D02*
X736596Y140630D01*
G01X736594Y140622D02*
X736595Y140628D01*
G01X736594Y140614D02*
Y140622D01*
G01X736595Y135628D02*
X736596Y135630D01*
G01X736594Y135622D02*
X736595Y135628D01*
G01X736594Y135614D02*
Y135622D01*
G01X736595Y130628D02*
X736596Y130630D01*
G01X736594Y130622D02*
X736595Y130628D01*
G01X736594Y130614D02*
Y130622D01*
G01X736595Y125628D02*
X736596Y125630D01*
G01X736594Y125622D02*
X736595Y125628D01*
G01X736594Y125614D02*
Y125622D01*
G01X736595Y120628D02*
X736596Y120630D01*
G01X736594Y120622D02*
X736595Y120628D01*
G01X736594Y120614D02*
Y120622D01*
G01X736595Y115628D02*
X736596Y115630D01*
G01X736594Y115622D02*
X736595Y115628D01*
G01X736594Y115614D02*
Y115622D01*
G01X736595Y110628D02*
X736596Y110630D01*
G01X736594Y110622D02*
X736595Y110628D01*
G01X736594Y110614D02*
Y110622D01*
G01X736595Y105628D02*
X736596Y105630D01*
G01X736594Y105622D02*
X736595Y105628D01*
G01X736594Y105614D02*
Y105622D01*
G01X723169Y102711D02*
Y102703D01*
G01X723168Y102715D02*
X723169Y102711D01*
G01X723168Y102707D02*
Y102715D01*
G01X723206Y102506D02*
X723205Y102519D01*
G01X723209Y102493D02*
X723206Y102506D01*
G01X723209Y102480D02*
Y102493D01*
G01X723206Y99356D02*
X723205Y99370D01*
G01X723209Y99343D02*
X723206Y99356D01*
G01X723209Y99331D02*
Y99343D01*
G01X723206Y96206D02*
X723205Y96220D01*
G01X723209Y96194D02*
X723206Y96206D01*
G01X723209Y96181D02*
Y96194D01*
G01X724117Y104030D02*
X724118Y104016D01*
G01X724113Y104043D02*
X724117Y104030D01*
G01X724114Y104055D02*
X724113Y104043D01*
G01X724117Y100880D02*
X724118Y100866D01*
G01X724113Y100893D02*
X724117Y100880D01*
G01X724114Y100906D02*
X724113Y100893D01*
G01X724117Y97730D02*
X724118Y97717D01*
G01X724113Y97743D02*
X724117Y97730D01*
G01X724114Y97756D02*
X724113Y97743D01*
G01X724117Y94581D02*
X724118Y94567D01*
G01X724113Y94594D02*
X724117Y94581D01*
G01X724114Y94606D02*
X724113Y94594D01*
G01X723169Y99561D02*
Y99554D01*
G01X723168Y99565D02*
X723169Y99561D01*
G01X723168Y99558D02*
Y99565D01*
G01X724113Y102493D02*
X724114Y102480D01*
G01X724116Y102506D02*
X724113Y102493D01*
G01X724117Y102519D02*
X724116Y102506D01*
G01X724113Y99343D02*
X724114Y99331D01*
G01X724116Y99356D02*
X724113Y99343D01*
G01X724117Y99370D02*
X724116Y99356D01*
G01X724113Y96194D02*
X724114Y96181D01*
G01X724116Y96206D02*
X724113Y96194D01*
G01X724117Y96220D02*
X724116Y96206D01*
G01X723182Y103850D02*
X723206Y103858D01*
G01X723171Y103835D02*
X723182Y103850D01*
G01X723169Y103828D02*
X723171Y103835D01*
G01X723182Y100700D02*
X723206Y100709D01*
G01X723171Y100685D02*
X723182Y100700D01*
G01X723169Y100679D02*
X723171Y100685D01*
G01X723182Y97550D02*
X723206Y97559D01*
G01X723171Y97536D02*
X723182Y97550D01*
G01X723169Y97529D02*
X723171Y97536D01*
G01X723182Y94401D02*
X723206Y94409D01*
G01X723171Y94386D02*
X723182Y94401D01*
G01X723169Y94380D02*
X723171Y94386D01*
G01X724154Y103825D02*
Y103832D01*
G01X724153Y103820D02*
X724154Y103825D01*
G01X724152Y103819D02*
X724153Y103820D01*
G01X724154Y100676D02*
Y100683D01*
G01X724153Y100671D02*
X724154Y100676D01*
G01X724152Y100669D02*
X724153Y100671D01*
G01X724154Y97526D02*
Y97533D01*
G01X724153Y97521D02*
X724154Y97526D01*
G01X724152Y97520D02*
X724153Y97521D01*
G01X724154Y94376D02*
Y94383D01*
G01X724153Y94372D02*
X724154Y94376D01*
G01X724152Y94370D02*
X724153Y94372D01*
G01X724114Y103863D02*
Y103869D01*
G01X724113Y103859D02*
X724114Y103863D01*
G01X724113Y103858D02*
Y103859D01*
G01X724114Y100714D02*
Y100720D01*
G01X724113Y100710D02*
X724114Y100714D01*
G01X724113Y100709D02*
Y100710D01*
G01X724114Y97564D02*
Y97570D01*
G01X724113Y97560D02*
X724114Y97564D01*
G01X724113Y97559D02*
Y97560D01*
G01X724114Y94415D02*
Y94420D01*
G01X724113Y94411D02*
X724114Y94415D01*
G01X724113Y94409D02*
Y94411D01*
G01X737579Y175622D02*
Y175613D01*
G01X737580Y175628D02*
X737579Y175622D01*
G01X737581Y175630D02*
X737580Y175628D01*
G01X737579Y170622D02*
Y170613D01*
G01X737580Y170628D02*
X737579Y170622D01*
G01X737581Y170630D02*
X737580Y170628D01*
G01X737579Y165622D02*
Y165613D01*
G01X737580Y165628D02*
X737579Y165622D01*
G01X737581Y165630D02*
X737580Y165628D01*
G01X737579Y160622D02*
Y160613D01*
G01X737580Y160628D02*
X737579Y160622D01*
G01X737581Y160630D02*
X737580Y160628D01*
G01X737579Y155622D02*
Y155613D01*
G01X737580Y155628D02*
X737579Y155622D01*
G01X737581Y155630D02*
X737580Y155628D01*
G01X737579Y150622D02*
Y150613D01*
G01X737580Y150628D02*
X737579Y150622D01*
G01X737581Y150630D02*
X737580Y150628D01*
G01X737579Y145622D02*
Y145613D01*
G01X737580Y145628D02*
X737579Y145622D01*
G01X737581Y145630D02*
X737580Y145628D01*
G01X737579Y140622D02*
Y140613D01*
G01X737580Y140628D02*
X737579Y140622D01*
G01X737581Y140630D02*
X737580Y140628D01*
G01X737579Y135622D02*
Y135613D01*
G01X737580Y135628D02*
X737579Y135622D01*
G01X737581Y135630D02*
X737580Y135628D01*
G01X737579Y130622D02*
Y130613D01*
G01X737580Y130628D02*
X737579Y130622D01*
G01X737581Y130630D02*
X737580Y130628D01*
G01X737579Y125622D02*
Y125613D01*
G01X737580Y125628D02*
X737579Y125622D01*
G01X737581Y125630D02*
X737580Y125628D01*
G01X737579Y120622D02*
Y120613D01*
G01X737580Y120628D02*
X737579Y120622D01*
G01X737581Y120630D02*
X737580Y120628D01*
G01X737579Y115622D02*
Y115613D01*
G01X737580Y115628D02*
X737579Y115622D01*
G01X737581Y115630D02*
X737580Y115628D01*
G01X737579Y110622D02*
Y110613D01*
G01X737580Y110628D02*
X737579Y110622D01*
G01X737581Y110630D02*
X737580Y110628D01*
G01X737579Y105622D02*
Y105613D01*
G01X737580Y105628D02*
X737579Y105622D01*
G01X737581Y105630D02*
X737580Y105628D01*
G01X723169Y103825D02*
Y103832D01*
G01X723168Y103820D02*
X723169Y103825D01*
G01X723167Y103819D02*
X723168Y103820D01*
G01X723169Y100675D02*
Y100683D01*
G01X723168Y100671D02*
X723169Y100675D01*
G01X723167Y100669D02*
X723168Y100671D01*
G01X723169Y97526D02*
Y97533D01*
G01X723168Y97521D02*
X723169Y97526D01*
G01X723167Y97520D02*
X723168Y97521D01*
G01X723169Y94376D02*
Y94383D01*
G01X723168Y94372D02*
X723169Y94376D01*
G01X723167Y94370D02*
X723168Y94372D01*
G01X724151Y102691D02*
X724154Y102703D01*
G01X724144Y102679D02*
X724151Y102691D01*
G01X724134Y102671D02*
X724144Y102679D01*
G01X724151Y96391D02*
X724154Y96404D01*
G01X724144Y96380D02*
X724151Y96391D01*
G01X724134Y96372D02*
X724144Y96380D01*
G01X723208Y103863D02*
Y103869D01*
G01Y103859D02*
Y103863D01*
G01X723206Y103858D02*
X723208Y103859D01*
G01Y100713D02*
Y100720D01*
G01Y100710D02*
Y100713D01*
G01X723206Y100709D02*
X723208Y100710D01*
G01Y97564D02*
Y97570D01*
G01Y97560D02*
Y97564D01*
G01X723206Y97559D02*
X723208Y97560D01*
G01Y94414D02*
Y94420D01*
G01Y94411D02*
Y94414D01*
G01X723206Y94409D02*
X723208Y94411D01*
G01X723170Y103839D02*
X723169Y103832D01*
G01X723172Y103845D02*
X723170Y103839D01*
G01X723174Y103851D02*
X723172Y103845D01*
G01X723178Y103856D02*
X723174Y103851D01*
G01X723183Y103861D02*
X723178Y103856D01*
G01X723189Y103864D02*
X723183Y103861D01*
G01X723170Y100689D02*
X723169Y100683D01*
G01X723172Y100695D02*
X723170Y100689D01*
G01X723174Y100701D02*
X723172Y100695D01*
G01X723178Y100706D02*
X723174Y100701D01*
G01X723183Y100711D02*
X723178Y100706D01*
G01X723189Y100715D02*
X723183Y100711D01*
G01X723170Y97539D02*
X723169Y97533D01*
G01X723172Y97546D02*
X723170Y97539D01*
G01X723174Y97552D02*
X723172Y97546D01*
G01X723178Y97557D02*
X723174Y97552D01*
G01X723183Y97561D02*
X723178Y97557D01*
G01X723189Y97565D02*
X723183Y97561D01*
G01X723170Y94390D02*
X723169Y94383D01*
G01X723172Y94396D02*
X723170Y94390D01*
G01X723174Y94402D02*
X723172Y94396D01*
G01X723178Y94407D02*
X723174Y94402D01*
G01X723183Y94412D02*
X723178Y94407D01*
G01X723189Y94415D02*
X723183Y94412D01*
G01X724125Y102679D02*
X724113Y102677D01*
G01X724135Y102684D02*
X724125Y102679D01*
G01Y99530D02*
X724113Y99528D01*
G01X724135Y99534D02*
X724125Y99530D01*
G01Y96380D02*
X724113Y96378D01*
G01X724135Y96385D02*
X724125Y96380D01*
G01X733976Y188130D02*
G03I-1889J0D01*
G01X734449D02*
G03I-2362J0D01*
G01X737008Y103681D02*
X738189Y104862D01*
G01X733071Y103681D02*
X734252Y104862D01*
G01X742913Y186161D02*
X739567Y182815D01*
G01X733071Y180138D02*
X734252Y181319D01*
G01X729602Y185059D02*
X730906Y187028D01*
G01X735578Y192950D02*
X733268Y188720D01*
G01X724153Y94372D02*
X724154Y94383D01*
G01X724153Y97522D02*
X724154Y97533D01*
G01X724153Y100671D02*
X724154Y100683D01*
G01X724153Y103821D02*
X724154Y103832D01*
G01X737579Y106982D02*
Y106991D01*
G01Y111982D02*
Y111991D01*
G01Y116982D02*
Y116991D01*
G01Y121982D02*
Y121991D01*
G01Y126982D02*
Y126991D01*
G01Y131982D02*
Y131991D01*
G01Y136982D02*
Y136991D01*
G01Y141982D02*
Y141991D01*
G01Y146982D02*
Y146991D01*
G01Y151982D02*
Y151991D01*
G01Y156982D02*
Y156991D01*
G01Y161982D02*
Y161991D01*
G01Y166982D02*
Y166991D01*
G01Y171982D02*
Y171991D01*
G01Y176982D02*
Y176991D01*
G01X742913Y186161D02*
Y201909D01*
G01X741929Y175630D02*
Y177008D01*
G01Y170630D02*
Y172008D01*
G01Y165630D02*
Y167008D01*
G01Y160630D02*
Y162008D01*
G01Y155630D02*
Y157008D01*
G01Y150630D02*
Y152008D01*
G01Y145630D02*
Y147008D01*
G01Y140630D02*
Y142008D01*
G01Y135630D02*
Y137008D01*
G01Y130630D02*
Y132008D01*
G01Y125630D02*
Y127008D01*
G01Y120630D02*
Y122008D01*
G01Y115630D02*
Y117008D01*
G01Y110630D02*
Y112008D01*
G01Y105630D02*
Y107008D01*
G01X738760D02*
Y105630D01*
G01Y112008D02*
Y110630D01*
G01Y117008D02*
Y115630D01*
G01Y122008D02*
Y120630D01*
G01Y127008D02*
Y125630D01*
G01Y132008D02*
Y130630D01*
G01Y137008D02*
Y135630D01*
G01Y142008D02*
Y140630D01*
G01Y147008D02*
Y145630D01*
G01Y152008D02*
Y150630D01*
G01Y157008D02*
Y155630D01*
G01Y162008D02*
Y160630D01*
G01Y167008D02*
Y165630D01*
G01Y172008D02*
Y170630D01*
G01Y177008D02*
Y175630D01*
G01X737579Y106982D02*
Y107125D01*
G01Y111982D02*
Y112125D01*
G01Y116982D02*
Y117125D01*
G01Y121982D02*
Y122125D01*
G01Y126982D02*
Y127125D01*
G01Y131982D02*
Y132125D01*
G01Y136982D02*
Y137125D01*
G01Y141982D02*
Y142125D01*
G01Y146982D02*
Y147125D01*
G01Y151982D02*
Y152125D01*
G01Y156982D02*
Y157125D01*
G01Y161982D02*
Y162125D01*
G01Y166982D02*
Y167125D01*
G01Y171982D02*
Y172125D01*
G01Y176982D02*
Y177125D01*
G01Y175138D02*
Y177500D01*
G01Y170138D02*
Y172500D01*
G01Y165138D02*
Y167500D01*
G01Y160138D02*
Y162500D01*
G01Y155138D02*
Y157500D01*
G01Y150138D02*
Y152500D01*
G01Y145138D02*
Y147500D01*
G01Y140138D02*
Y142500D01*
G01Y135138D02*
Y137500D01*
G01Y130138D02*
Y132500D01*
G01Y125138D02*
Y127500D01*
G01Y120138D02*
Y122500D01*
G01Y115138D02*
Y117500D01*
G01Y110138D02*
Y112500D01*
G01Y105138D02*
Y107500D01*
G01X736594D02*
Y105138D01*
G01Y112500D02*
Y110138D01*
G01Y117500D02*
Y115138D01*
G01Y122500D02*
Y120138D01*
G01Y127500D02*
Y125138D01*
G01Y132500D02*
Y130138D01*
G01Y137500D02*
Y135138D01*
G01Y142500D02*
Y140138D01*
G01Y147500D02*
Y145138D01*
G01Y152500D02*
Y150138D01*
G01Y157500D02*
Y155138D01*
G01Y162500D02*
Y160138D01*
G01Y167500D02*
Y165138D01*
G01Y172500D02*
Y170138D01*
G01Y177500D02*
Y175138D01*
G01X735827Y192224D02*
Y183681D01*
G01X734252Y181319D02*
Y104862D01*
G01X733268Y188720D02*
Y187028D01*
G01X733071Y180138D02*
Y103681D01*
G01X730906Y187028D02*
Y188720D01*
G01X728346Y183681D02*
Y192224D01*
G01X724606Y185059D02*
Y106024D01*
G01X724154Y102519D02*
Y104016D01*
G01Y99370D02*
Y100866D01*
G01Y96220D02*
Y97717D01*
G01X724114Y96367D02*
Y96220D01*
G01Y94567D02*
Y94420D01*
G01Y99516D02*
Y99369D01*
G01Y100867D02*
Y100720D01*
G01Y97717D02*
Y97570D01*
G01Y102666D02*
Y102519D01*
G01Y104016D02*
Y103869D01*
G01X723209Y102519D02*
Y102666D01*
G01Y103869D02*
Y104016D01*
G01Y99369D02*
Y99516D01*
G01Y100720D02*
Y100867D01*
G01Y97570D02*
Y97717D01*
G01Y96220D02*
Y96367D01*
G01Y94420D02*
Y94567D01*
G01X723169Y100866D02*
Y99370D01*
G01Y97717D02*
Y96220D01*
G01Y104016D02*
Y102520D01*
G01X721988Y97559D02*
Y96378D01*
G01Y100709D02*
Y99528D01*
G01Y103858D02*
Y102677D01*
G01X721260Y201909D02*
Y186161D01*
G01X718228Y102677D02*
Y103858D01*
G01Y99528D02*
Y100709D01*
G01Y96378D02*
Y97559D01*
G01X724154Y102703D02*
X724153Y102714D01*
G01X724154Y99554D02*
X724153Y99564D01*
G01X724154Y96404D02*
X724153Y96415D01*
G01X724113Y99528D02*
X724116Y99516D01*
G01X730906Y188720D02*
X728595Y192950D01*
G01X733268Y187028D02*
X734571Y185059D01*
G01X726378Y181319D02*
X727559Y180138D01*
G01X721260Y186161D02*
X724606Y182815D01*
G01X730906Y187028D02*
X733268D01*
G01X724606Y185059D02*
X738976D01*
G01X724606Y183681D02*
X728346D01*
G01X738976D02*
X735827D01*
G01X724606Y182815D02*
X739567D01*
G01X726378Y181319D02*
X734252D01*
G01X727559Y180138D02*
X733071D01*
G01X737579Y177500D02*
X736594D01*
G01X736596Y177008D02*
X741929D01*
G01Y176969D02*
X737581D01*
G01X741929Y175630D02*
X736596D01*
G01X736594Y175138D02*
X737579D01*
G01Y172500D02*
X736594D01*
G01X736596Y172008D02*
X741929D01*
G01Y171969D02*
X737581D01*
G01X741929Y170630D02*
X736596D01*
G01X736594Y170138D02*
X737579D01*
G01Y167500D02*
X736594D01*
G01X736596Y167008D02*
X741929D01*
G01Y166969D02*
X737581D01*
G01X741929Y165630D02*
X736596D01*
G01X736594Y165138D02*
X737579D01*
G01Y162500D02*
X736594D01*
G01X736596Y162008D02*
X741929D01*
G01Y161969D02*
X737581D01*
G01X741929Y160630D02*
X736596D01*
G01X736594Y160138D02*
X737579D01*
G01Y157500D02*
X736594D01*
G01X736596Y157008D02*
X741929D01*
G01Y156969D02*
X737581D01*
G01X741929Y155630D02*
X736596D01*
G01X736594Y155138D02*
X737579D01*
G01Y152500D02*
X736594D01*
G01X736596Y152008D02*
X741929D01*
G01Y151969D02*
X737581D01*
G01X741929Y150630D02*
X736596D01*
G01X736594Y150138D02*
X737579D01*
G01Y147500D02*
X736594D01*
G01X736596Y147008D02*
X741929D01*
G01Y146969D02*
X737581D01*
G01X741929Y145630D02*
X736596D01*
G01X736594Y145138D02*
X737579D01*
G01Y142500D02*
X736594D01*
G01X736596Y142008D02*
X741929D01*
G01Y141969D02*
X737581D01*
G01X741929Y140630D02*
X736596D01*
G01X736594Y140138D02*
X737579D01*
G01Y137500D02*
X736594D01*
G01X736596Y137008D02*
X741929D01*
G01Y136969D02*
X737581D01*
G01X741929Y135630D02*
X736596D01*
G01X736594Y135138D02*
X737579D01*
G01Y132500D02*
X736594D01*
G01X736596Y132008D02*
X741929D01*
G01Y131969D02*
X737581D01*
G01X741929Y130630D02*
X736596D01*
G01X736594Y130138D02*
X737579D01*
G01Y127500D02*
X736594D01*
G01X736596Y127008D02*
X741929D01*
G01Y126969D02*
X737581D01*
G01X741929Y125630D02*
X736596D01*
G01X736594Y125138D02*
X737579D01*
G01Y122500D02*
X736594D01*
G01X736596Y122008D02*
X741929D01*
G01Y121969D02*
X737581D01*
G01X741929Y120630D02*
X736596D01*
G01X736594Y120138D02*
X737579D01*
G01Y117500D02*
X736594D01*
G01Y177204D02*
X737550Y177205D01*
G01X737579Y175434D02*
X736594Y175433D01*
G01Y172204D02*
X737550Y172205D01*
G01X737579Y170434D02*
X736594Y170433D01*
G01Y167204D02*
X737550Y167205D01*
G01X737579Y165434D02*
X736594Y165433D01*
G01Y162204D02*
X737550Y162205D01*
G01X737579Y160434D02*
X736594Y160433D01*
G01Y157204D02*
X737550Y157205D01*
G01X737579Y155434D02*
X736594Y155433D01*
G01Y152204D02*
X737550Y152205D01*
G01X737579Y150434D02*
X736594Y150433D01*
G01Y147204D02*
X737550Y147205D01*
G01X737579Y145434D02*
X736594Y145433D01*
G01Y142204D02*
X737550Y142205D01*
G01X737579Y140434D02*
X736594Y140433D01*
G01Y137204D02*
X737550Y137205D01*
G01X737579Y135434D02*
X736594Y135433D01*
G01Y132204D02*
X737550Y132205D01*
G01X737579Y130434D02*
X736594Y130433D01*
G01Y127204D02*
X737550Y127205D01*
G01X737579Y125434D02*
X736594Y125433D01*
G01Y122204D02*
X737550Y122205D01*
G01X737579Y120434D02*
X736594Y120433D01*
G01Y117204D02*
X737550Y117205D01*
G01X723056Y102717D02*
X723168Y102708D01*
G01X723167Y96414D02*
X723056Y96417D01*
G01X736596Y117008D02*
X741929D01*
G01Y116969D02*
X737581D01*
G01X741929Y115630D02*
X736596D01*
G01X736594Y115138D02*
X737579D01*
G01Y112500D02*
X736594D01*
G01X736596Y112008D02*
X741929D01*
G01Y111969D02*
X737581D01*
G01X741929Y110630D02*
X736596D01*
G01X736594Y110138D02*
X737579D01*
G01Y107500D02*
X736594D01*
G01X736596Y107008D02*
X741929D01*
G01Y106969D02*
X737581D01*
G01X724606Y106024D02*
X721260D01*
G01X741929Y105630D02*
X736596D01*
G01X736594Y105138D02*
X737579D01*
G01X734252Y104862D02*
X738189D01*
G01X724114Y104055D02*
X723209D01*
G01X724154Y104016D02*
X723169D01*
G01X724113Y103858D02*
X718228D01*
G01Y103819D02*
X724152D01*
G01X733071Y103681D02*
X737008D01*
G01X724152Y102717D02*
X718228D01*
G01X724113Y102677D02*
X718228D01*
G01X723169Y102520D02*
X724154D01*
G01X723209Y102480D02*
X724114D01*
G01Y100906D02*
X723209D01*
G01X724154Y100866D02*
X723169D01*
G01X724113Y100709D02*
X718228D01*
G01Y100669D02*
X724152D01*
G01Y99567D02*
X718228D01*
G01X724113Y99528D02*
X718228D01*
G01X723169Y99370D02*
X724154D01*
G01X723209Y99331D02*
X724114D01*
G01Y97756D02*
X723209D01*
G01X724154Y97717D02*
X723169D01*
G01X724113Y97559D02*
X718228D01*
G01Y97520D02*
X724152D01*
G01Y96417D02*
X718228D01*
G01X724113Y96378D02*
X718228D01*
G01X723169Y96220D02*
X724154D01*
G01X723209Y96181D02*
X724114D01*
G01Y94606D02*
X723209D01*
G01X724154Y94567D02*
X723169D01*
G01X724113Y94409D02*
X718228D01*
G01Y94370D02*
X724152D01*
G01X737579Y115434D02*
X736594Y115433D01*
G01Y112204D02*
X737550Y112205D01*
G01X737579Y110434D02*
X736594Y110433D01*
G01Y107204D02*
X737550Y107205D01*
G01X737579Y105434D02*
X736594Y105433D01*
G01X736024Y202500D02*
G03X735433Y203091I-591J0D01*
G01X728740D02*
G03X728150Y202500I1J-591D01*
G01X730906Y201319D02*
G03Y199350I0J-985D01*
G01X733268D02*
G03Y201319I0J984D01*
G01X729528Y193406D02*
G03X728346Y192224I-1J-1181D01*
G01X735827D02*
G03X734646Y193406I-1181J1D01*
G01X742913Y201909D02*
G03X740945Y203878I-1968J1D01*
G01X723228D02*
G03X721260Y201909I1J-1969D01*
G01X692126Y260630D02*
G03X693307I591J0D01*
G01Y254331D02*
G03X692126I-590J0D01*
G01X690157D02*
G03X688976I-590J0D01*
G01Y260630D02*
G03X690157I590J0D01*
G01X692126D02*
G03X693307I591J0D01*
G01Y254331D02*
G03X692126I-590J0D01*
G01X690157D02*
G03X688976I-590J0D01*
G01Y260630D02*
G03X690157I590J0D01*
G01X736024Y196398D02*
Y202500D01*
G01X728150Y196398D02*
Y202500D01*
G01X694094Y254331D02*
Y260630D01*
G01Y254331D02*
Y260630D01*
G01X688189Y254331D02*
Y260630D01*
G01D02*
Y254331D01*
G01X688976Y260630D02*
X688189D01*
G01X688976D02*
X688189D01*
G01X692126D02*
X690157D01*
G01X694094D02*
X693307D01*
G01X692126D02*
X690157D01*
G01X694094D02*
X693307D01*
G01X694094Y259646D02*
X688189D01*
G01Y259449D02*
X694094D01*
G01X688189Y255512D02*
X694094D01*
G01Y255315D02*
X688189D01*
G01X693307Y254331D02*
X694094D01*
G01X690157D02*
X692126D01*
G01X693307D02*
X694094D01*
G01X690157D02*
X692126D01*
G01X688189D02*
X688976D01*
G01X688189D02*
X688976D01*
G01X740945Y203878D02*
X723228D01*
G01X735433Y203091D02*
X728740D01*
G01X733268Y201319D02*
X730906D01*
G01Y199350D02*
X733268D01*
G01X736024Y197972D02*
X728150D01*
G01Y196398D02*
X736024D01*
G01X742913Y193445D02*
X721260D01*
G01X729528Y193406D02*
X734646D01*
G01X730906Y188720D02*
X733268D01*
G01X730339Y383610D02*
G03X764149I16905J-13531D01*
G01X730339Y383609D02*
G03X764150I16905J-13530D01*
G01X757225Y396741D02*
G03X764149Y383610I37663J11469D01*
G01X757225Y396741D02*
G03X737264I-9981J-3040D01*
G01X730339Y383610D02*
G03X737264Y396741I-30737J24602D01*
G01X757224D02*
G03X737264I-9980J-3041D01*
G01X757224D02*
G03X764150Y383609I37662J11471D01*
G01X730339D02*
G03X737264Y396741I-30738J24601D01*
G01X737566Y504755D02*
X737577Y504740D01*
G01X737542Y504764D02*
X737566Y504755D01*
G01X724122Y544015D02*
X724113Y544016D01*
G01X724131Y544011D02*
X724122Y544015D01*
G01X724139Y544006D02*
X724131Y544011D01*
G01X724122Y537715D02*
X724113Y537717D01*
G01X724131Y537712D02*
X724122Y537715D01*
G01X724139Y537707D02*
X724131Y537712D01*
G01X724122Y540865D02*
X724113Y540866D01*
G01X724131Y540862D02*
X724122Y540865D01*
G01X724139Y540856D02*
X724131Y540862D01*
G01X723208Y536530D02*
X723209Y536524D01*
G01X723207Y536534D02*
X723208Y536530D01*
G01X723206Y536535D02*
X723207Y536534D01*
G01X723208Y539680D02*
X723209Y539674D01*
G01X723207Y539684D02*
X723208Y539680D01*
G01X723206Y539685D02*
X723207Y539684D01*
G01X723208Y542830D02*
X723209Y542823D01*
G01X723207Y542833D02*
X723208Y542830D01*
G01X723206Y542835D02*
X723207Y542833D01*
G01X723208Y545979D02*
X723209Y545973D01*
G01X723207Y545983D02*
X723208Y545979D01*
G01X723206Y545984D02*
X723207Y545983D01*
G01X723208Y549129D02*
X723209Y549122D01*
G01X723207Y549133D02*
X723208Y549129D01*
G01X723206Y549134D02*
X723207Y549133D01*
G01X723208Y552278D02*
X723209Y552272D01*
G01X723207Y552282D02*
X723208Y552278D01*
G01X723206Y552283D02*
X723207Y552282D01*
G01X737579Y504731D02*
Y504738D01*
G01X737580Y504726D02*
X737579Y504731D01*
G01X737581Y504724D02*
X737580Y504726D01*
G01X737579Y509731D02*
Y509738D01*
G01X737580Y509726D02*
X737579Y509731D01*
G01X737581Y509724D02*
X737580Y509726D01*
G01X737579Y514731D02*
Y514738D01*
G01X737580Y514726D02*
X737579Y514731D01*
G01X737581Y514724D02*
X737580Y514726D01*
G01X737579Y519731D02*
Y519738D01*
G01X737580Y519726D02*
X737579Y519731D01*
G01X737581Y519724D02*
X737580Y519726D01*
G01X737579Y524731D02*
Y524738D01*
G01X737580Y524726D02*
X737579Y524731D01*
G01X737581Y524724D02*
X737580Y524726D01*
G01X737579Y529731D02*
Y529738D01*
G01X737580Y529726D02*
X737579Y529731D01*
G01X737581Y529724D02*
X737580Y529726D01*
G01X737579Y534731D02*
Y534738D01*
G01X737580Y534726D02*
X737579Y534731D01*
G01X737581Y534724D02*
X737580Y534726D01*
G01X723192Y539687D02*
X723206Y539685D01*
G01X723181Y539694D02*
X723192Y539687D01*
G01X723169Y539713D02*
X723181Y539694D01*
G01X723192Y549136D02*
X723206Y549134D01*
G01X723180Y549144D02*
X723192Y549136D01*
G01X723169Y549162D02*
X723180Y549144D01*
G01X723192Y542837D02*
X723206Y542835D01*
G01X723180Y542845D02*
X723192Y542837D01*
G01X723168Y542865D02*
X723180Y542845D01*
G01X724154Y536569D02*
Y536561D01*
G01X724153Y536573D02*
X724154Y536569D01*
G01X724152Y536575D02*
X724153Y536573D01*
G01X724154Y539719D02*
Y539711D01*
G01X724153Y539723D02*
X724154Y539719D01*
G01X724152Y539724D02*
X724153Y539723D01*
G01X724154Y542868D02*
Y542860D01*
G01X724153Y542872D02*
X724154Y542868D01*
G01X724152Y542874D02*
X724153Y542872D01*
G01X724154Y546018D02*
Y546010D01*
G01X724153Y546022D02*
X724154Y546018D01*
G01X724152Y546024D02*
X724153Y546022D01*
G01X723191Y536538D02*
X723206Y536535D01*
G01X723178Y536547D02*
X723191Y536538D01*
G01X723168Y536567D02*
X723178Y536547D01*
G01X724153Y537697D02*
X724154Y537691D01*
G01X724151Y537704D02*
X724153Y537697D01*
G01X724148Y537709D02*
X724151Y537704D01*
G01X724153Y540847D02*
X724154Y540840D01*
G01X724151Y540853D02*
X724153Y540847D01*
G01X724148Y540859D02*
X724151Y540853D01*
G01X737546Y504862D02*
X737550Y504961D01*
G01X737540Y504790D02*
X737546Y504862D01*
G01X737542Y504764D02*
X737540Y504790D01*
G01X737546Y509862D02*
X737550Y509961D01*
G01X737540Y509790D02*
X737546Y509862D01*
G01X737542Y509764D02*
X737540Y509790D01*
G01X737546Y514862D02*
X737550Y514961D01*
G01X737540Y514790D02*
X737546Y514862D01*
G01X737542Y514764D02*
X737540Y514790D01*
G01X737546Y519862D02*
X737550Y519961D01*
G01X737540Y519790D02*
X737546Y519862D01*
G01X737542Y519764D02*
X737540Y519790D01*
G01X737546Y524862D02*
X737550Y524961D01*
G01X737540Y524790D02*
X737546Y524862D01*
G01X737542Y524764D02*
X737540Y524790D01*
G01X737546Y529862D02*
X737550Y529961D01*
G01X737540Y529790D02*
X737546Y529862D01*
G01X737542Y529764D02*
X737540Y529790D01*
G01X737546Y534862D02*
X737550Y534961D01*
G01X737540Y534790D02*
X737546Y534862D01*
G01X737542Y534764D02*
X737540Y534790D01*
G01X737546Y559862D02*
X737550Y559961D01*
G01X737540Y559790D02*
X737546Y559862D01*
G01X737542Y559764D02*
X737540Y559790D01*
G01X737546Y564862D02*
X737550Y564961D01*
G01X737540Y564790D02*
X737546Y564862D01*
G01X737542Y564764D02*
X737540Y564790D01*
G01X737546Y569862D02*
X737550Y569961D01*
G01X737540Y569790D02*
X737546Y569862D01*
G01X737542Y569764D02*
X737540Y569790D01*
G01X723169Y549167D02*
Y549160D01*
G01X723168Y549172D02*
X723169Y549167D01*
G01Y549162D02*
X723168Y549172D01*
G01X723209Y556798D02*
Y556811D01*
G01X723206Y556785D02*
X723209Y556798D01*
G01X723206Y556772D02*
Y556785D01*
G01X723209Y553649D02*
Y553661D01*
G01X723206Y553636D02*
X723209Y553649D01*
G01X723206Y553622D02*
Y553636D01*
G01X723209Y550499D02*
Y550512D01*
G01X723206Y550486D02*
X723209Y550499D01*
G01X723206Y550472D02*
Y550486D01*
G01X723209Y547350D02*
Y547362D01*
G01X723206Y547337D02*
X723209Y547350D01*
G01X723206Y547323D02*
Y547337D01*
G01X723209Y544200D02*
Y544213D01*
G01X723206Y544187D02*
X723209Y544200D01*
G01X723206Y544173D02*
Y544187D01*
G01X723209Y541050D02*
Y541063D01*
G01X723206Y541037D02*
X723209Y541050D01*
G01X723206Y541024D02*
Y541037D01*
G01X723209Y537901D02*
Y537913D01*
G01X723206Y537888D02*
X723209Y537901D01*
G01X723206Y537874D02*
Y537888D01*
G01X723169Y555467D02*
Y555459D01*
G01X723168Y555471D02*
X723169Y555467D01*
G01X723168Y555463D02*
Y555471D01*
G01X724144Y537715D02*
X724148Y537709D01*
G01X724139Y537719D02*
X724144Y537715D01*
G01X724133Y537723D02*
X724139Y537719D01*
G01X724128Y537726D02*
X724133Y537723D01*
G01X724121Y537727D02*
X724128Y537726D01*
G01X724114Y537728D02*
X724121Y537727D01*
G01X724144Y540865D02*
X724148Y540859D01*
G01X724139Y540869D02*
X724144Y540865D01*
G01X724133Y540872D02*
X724139Y540869D01*
G01X724128Y540875D02*
X724133Y540872D01*
G01X724121Y540877D02*
X724128Y540875D01*
G01X724114Y540877D02*
X724121D01*
G01X724144Y544014D02*
X724148Y544009D01*
G01X724139Y544019D02*
X724144Y544014D01*
G01X724133Y544022D02*
X724139Y544019D01*
G01X724128Y544025D02*
X724133Y544022D01*
G01X724121Y544026D02*
X724128Y544025D01*
G01X724114Y544027D02*
X724121Y544026D01*
G01X723170Y536554D02*
X723169Y536561D01*
G01X723172Y536547D02*
X723170Y536554D01*
G01X723176Y536541D02*
X723172Y536547D01*
G01X723181Y536535D02*
X723176Y536541D01*
G01X723187Y536530D02*
X723181Y536535D01*
G01X723194Y536527D02*
X723187Y536530D01*
G01X723201Y536525D02*
X723194Y536527D01*
G01X723209Y536524D02*
X723201Y536525D01*
G01X723170Y539704D02*
X723169Y539711D01*
G01X723172Y539696D02*
X723170Y539704D01*
G01X723176Y539690D02*
X723172Y539696D01*
G01X723181Y539685D02*
X723176Y539690D01*
G01X723187Y539680D02*
X723181Y539685D01*
G01X723194Y539676D02*
X723187Y539680D01*
G01X723201Y539674D02*
X723194Y539676D01*
G01X723209Y539674D02*
X723201D01*
G01X723170Y542853D02*
X723169Y542860D01*
G01X723172Y542846D02*
X723170Y542853D01*
G01X723176Y542840D02*
X723172Y542846D01*
G01X723181Y542834D02*
X723176Y542840D01*
G01X723187Y542830D02*
X723181Y542834D01*
G01X723194Y542826D02*
X723187Y542830D01*
G01X723201Y542824D02*
X723194Y542826D01*
G01X723209Y542823D02*
X723201Y542824D01*
G01X723170Y546003D02*
X723169Y546010D01*
G01X723172Y545996D02*
X723170Y546003D01*
G01X723176Y545989D02*
X723172Y545996D01*
G01X723181Y545984D02*
X723176Y545989D01*
G01X723187Y545979D02*
X723181Y545984D01*
G01X723194Y545976D02*
X723187Y545979D01*
G01X723201Y545974D02*
X723194Y545976D01*
G01X723209Y545973D02*
X723201Y545974D01*
G01X723170Y549152D02*
X723169Y549159D01*
G01X723172Y549145D02*
X723170Y549152D01*
G01X723176Y549139D02*
X723172Y549145D01*
G01X723181Y549133D02*
X723176Y549139D01*
G01X723187Y549129D02*
X723181Y549133D01*
G01X723194Y549125D02*
X723187Y549129D01*
G01X723201Y549123D02*
X723194Y549125D01*
G01X723209Y549122D02*
X723201Y549123D01*
G01X724123Y537715D02*
X724133Y537711D01*
G01X724113Y537717D02*
X724123Y537715D01*
G01Y540865D02*
X724133Y540861D01*
G01X724113Y540866D02*
X724123Y540865D01*
G01Y544014D02*
X724133Y544010D01*
G01X724113Y544016D02*
X724123Y544014D01*
G01Y547164D02*
X724133Y547160D01*
G01X724113Y547165D02*
X724123Y547164D01*
G01Y550313D02*
X724133Y550309D01*
G01X724113Y550315D02*
X724123Y550313D01*
G01Y553463D02*
X724133Y553459D01*
G01X724113Y553465D02*
X724123Y553463D01*
G01Y556613D02*
X724133Y556609D01*
G01X724113Y556614D02*
X724123Y556613D01*
G01X723169Y539715D02*
Y539711D01*
G01X723171Y539708D02*
X723169Y539715D01*
G01X723183Y539693D02*
X723171Y539708D01*
G01X723207Y539685D02*
X723183Y539693D01*
G01X723169Y542864D02*
Y542860D01*
G01X723171Y542858D02*
X723169Y542864D01*
G01X723182Y542843D02*
X723171Y542858D01*
G01X723207Y542835D02*
X723182Y542843D01*
G01X723169Y549163D02*
Y549159D01*
G01X723171Y549157D02*
X723169Y549163D01*
G01X723182Y549142D02*
X723171Y549157D01*
G01X723207Y549134D02*
X723182Y549142D01*
G01X723169Y552313D02*
Y552309D01*
G01X723171Y552307D02*
X723169Y552313D01*
G01X723182Y552292D02*
X723171Y552307D01*
G01X723207Y552283D02*
X723182Y552292D01*
G01X723169Y536565D02*
Y536561D01*
G01X723171Y536559D02*
X723169Y536565D01*
G01X723182Y536544D02*
X723171Y536559D01*
G01X723207Y536535D02*
X723182Y536544D01*
G01X723169Y555463D02*
Y555459D01*
G01X723171Y555457D02*
X723169Y555463D01*
G01X723182Y555441D02*
X723171Y555457D01*
G01X723207Y555433D02*
X723182Y555441D01*
G01X737566Y509755D02*
X737577Y509740D01*
G01X737542Y509764D02*
X737566Y509755D01*
G01Y514755D02*
X737577Y514740D01*
G01X737542Y514764D02*
X737566Y514755D01*
G01Y519755D02*
X737577Y519740D01*
G01X737542Y519764D02*
X737566Y519755D01*
G01Y524755D02*
X737577Y524740D01*
G01X737542Y524764D02*
X737566Y524755D01*
G01Y529755D02*
X737577Y529740D01*
G01X737542Y529764D02*
X737566Y529755D01*
G01Y534755D02*
X737577Y534740D01*
G01X737542Y534764D02*
X737566Y534755D01*
G01Y559755D02*
X737577Y559740D01*
G01X737542Y559764D02*
X737566Y559755D01*
G01Y564755D02*
X737577Y564740D01*
G01X737542Y564764D02*
X737566Y564755D01*
G01Y569755D02*
X737577Y569740D01*
G01X737542Y569764D02*
X737566Y569755D01*
G01X723169Y546014D02*
Y546010D01*
G01X723171Y546008D02*
X723169Y546014D01*
G01X723181Y545994D02*
X723171Y546008D01*
G01X723204Y545984D02*
X723181Y545994D01*
G01X724122Y547164D02*
X724113Y547165D01*
G01X724131Y547161D02*
X724122Y547164D01*
G01X724139Y547156D02*
X724131Y547161D01*
G01X724122Y550314D02*
X724113Y550315D01*
G01X724131Y550311D02*
X724122Y550314D01*
G01X724139Y550305D02*
X724131Y550311D01*
G01X724122Y553463D02*
X724113Y553465D01*
G01X724131Y553460D02*
X724122Y553463D01*
G01X724139Y553455D02*
X724131Y553460D01*
G01X724122Y556613D02*
X724113Y556614D01*
G01X724131Y556610D02*
X724122Y556613D01*
G01X724139Y556604D02*
X724131Y556610D01*
G01X723208Y555428D02*
X723209Y555422D01*
G01X723207Y555432D02*
X723208Y555428D01*
G01X723206Y555433D02*
X723207Y555432D01*
G01X737579Y559731D02*
Y559738D01*
G01X737580Y559726D02*
X737579Y559731D01*
G01X737581Y559724D02*
X737580Y559726D01*
G01X737579Y564731D02*
Y564738D01*
G01X737580Y564726D02*
X737579Y564731D01*
G01X737581Y564724D02*
X737580Y564726D01*
G01X737579Y569731D02*
Y569738D01*
G01X737580Y569726D02*
X737579Y569731D01*
G01X737581Y569724D02*
X737580Y569726D01*
G01X723192Y552286D02*
X723206Y552283D01*
G01X723180Y552294D02*
X723192Y552286D01*
G01X723168Y552314D02*
X723180Y552294D01*
G01X724154Y549167D02*
Y549159D01*
G01X724153Y549172D02*
X724154Y549167D01*
G01X724152Y549173D02*
X724153Y549172D01*
G01X724154Y552317D02*
Y552309D01*
G01X724153Y552321D02*
X724154Y552317D01*
G01X724152Y552323D02*
X724153Y552321D01*
G01X724154Y555467D02*
Y555459D01*
G01X724153Y555471D02*
X724154Y555467D01*
G01X724152Y555472D02*
X724153Y555471D01*
G01X723192Y555436D02*
X723206Y555433D01*
G01X723179Y555444D02*
X723192Y555436D01*
G01X723168Y555464D02*
X723179Y555444D01*
G01X724153Y543996D02*
X724154Y543990D01*
G01X724151Y544003D02*
X724153Y543996D01*
G01X724148Y544009D02*
X724151Y544003D01*
G01X724153Y547146D02*
X724154Y547139D01*
G01X724151Y547152D02*
X724153Y547146D01*
G01X724148Y547158D02*
X724151Y547152D01*
G01X724153Y550296D02*
X724154Y550289D01*
G01X724151Y550302D02*
X724153Y550296D01*
G01X724148Y550308D02*
X724151Y550302D01*
G01X724153Y553445D02*
X724154Y553439D01*
G01X724151Y553452D02*
X724153Y553445D01*
G01X724148Y553457D02*
X724151Y553452D01*
G01X724153Y556595D02*
X724154Y556588D01*
G01X724151Y556601D02*
X724153Y556595D01*
G01X724148Y556607D02*
X724151Y556601D01*
G01X724115Y536530D02*
Y536524D01*
G01X724113Y536534D02*
X724115Y536530D01*
G01X724113Y536535D02*
Y536534D01*
G01X724115Y539680D02*
Y539674D01*
G01X724113Y539683D02*
X724115Y539680D01*
G01X724113Y539685D02*
Y539683D01*
G01X724115Y542830D02*
Y542823D01*
G01X724113Y542833D02*
X724115Y542830D01*
G01X724113Y542835D02*
Y542833D01*
G01X724115Y545979D02*
Y545973D01*
G01X724113Y545983D02*
X724115Y545979D01*
G01X724113Y545984D02*
Y545983D01*
G01X724115Y549129D02*
Y549122D01*
G01X724113Y549132D02*
X724115Y549129D01*
G01X724113Y549134D02*
Y549132D01*
G01X724115Y555428D02*
Y555422D01*
G01X724113Y555431D02*
X724115Y555428D01*
G01X724113Y555433D02*
Y555431D01*
G01X736594Y504771D02*
Y504780D01*
G01X736595Y504765D02*
X736594Y504771D01*
G01X736596Y504764D02*
X736595Y504765D01*
G01X736594Y509771D02*
Y509780D01*
G01X736595Y509765D02*
X736594Y509771D01*
G01X736596Y509764D02*
X736595Y509765D01*
G01X736594Y514771D02*
Y514780D01*
G01X736595Y514765D02*
X736594Y514771D01*
G01X736596Y514764D02*
X736595Y514765D01*
G01X736594Y519771D02*
Y519780D01*
G01X736595Y519765D02*
X736594Y519771D01*
G01X736596Y519764D02*
X736595Y519765D01*
G01X736594Y524771D02*
Y524780D01*
G01X736595Y524765D02*
X736594Y524771D01*
G01X736596Y524764D02*
X736595Y524765D01*
G01X736594Y529771D02*
Y529780D01*
G01X736595Y529765D02*
X736594Y529771D01*
G01X736596Y529764D02*
X736595Y529765D01*
G01X736594Y534771D02*
Y534780D01*
G01X736595Y534765D02*
X736594Y534771D01*
G01X736596Y534764D02*
X736595Y534765D01*
G01X736594Y559771D02*
Y559780D01*
G01X736595Y559765D02*
X736594Y559771D01*
G01X736596Y559764D02*
X736595Y559765D01*
G01X736594Y564771D02*
Y564780D01*
G01X736595Y564765D02*
X736594Y564771D01*
G01X736596Y564764D02*
X736595Y564765D01*
G01X736594Y569771D02*
Y569780D01*
G01X736595Y569765D02*
X736594Y569771D01*
G01X736596Y569764D02*
X736595Y569765D01*
G01X737571Y504907D02*
X737579Y504881D01*
G01X737561Y504934D02*
X737571Y504907D01*
G01X737550Y504961D02*
X737561Y504934D01*
G01X737571Y509907D02*
X737579Y509881D01*
G01X737561Y509934D02*
X737571Y509907D01*
G01X737550Y509961D02*
X737561Y509934D01*
G01X737571Y514907D02*
X737579Y514881D01*
G01X737561Y514934D02*
X737571Y514907D01*
G01X737550Y514961D02*
X737561Y514934D01*
G01X737571Y519907D02*
X737579Y519881D01*
G01X737561Y519934D02*
X737571Y519907D01*
G01X737550Y519961D02*
X737561Y519934D01*
G01X737571Y524907D02*
X737579Y524881D01*
G01X737561Y524934D02*
X737571Y524907D01*
G01X737550Y524961D02*
X737561Y524934D01*
G01X737571Y529907D02*
X737579Y529881D01*
G01X737561Y529934D02*
X737571Y529907D01*
G01X737550Y529961D02*
X737561Y529934D01*
G01X737571Y534907D02*
X737579Y534881D01*
G01X737561Y534934D02*
X737571Y534907D01*
G01X737550Y534961D02*
X737561Y534934D01*
G01X737571Y559907D02*
X737579Y559881D01*
G01X737561Y559934D02*
X737571Y559907D01*
G01X737550Y559961D02*
X737561Y559934D01*
G01X737571Y564907D02*
X737579Y564881D01*
G01X737561Y564934D02*
X737571Y564907D01*
G01X737550Y564961D02*
X737561Y564934D01*
G01X737571Y569907D02*
X737579Y569881D01*
G01X737561Y569934D02*
X737571Y569907D01*
G01X737550Y569961D02*
X737561Y569934D01*
G01X723187Y545989D02*
X723206Y545984D01*
G01X723174Y546002D02*
X723187Y545989D01*
G01X723167Y546019D02*
X723174Y546002D01*
G01X737561Y504759D02*
X737542Y504764D01*
G01X737576Y504744D02*
X737561Y504759D01*
G01X737581Y504724D02*
X737576Y504744D01*
G01X737561Y509759D02*
X737542Y509764D01*
G01X737576Y509744D02*
X737561Y509759D01*
G01X737581Y509724D02*
X737576Y509744D01*
G01X737561Y514759D02*
X737542Y514764D01*
G01X737576Y514744D02*
X737561Y514759D01*
G01X737581Y514724D02*
X737576Y514744D01*
G01X737561Y519759D02*
X737542Y519764D01*
G01X737576Y519744D02*
X737561Y519759D01*
G01X737581Y519724D02*
X737576Y519744D01*
G01X737561Y524759D02*
X737542Y524764D01*
G01X737576Y524744D02*
X737561Y524759D01*
G01X737581Y524724D02*
X737576Y524744D01*
G01X737561Y529759D02*
X737542Y529764D01*
G01X737576Y529744D02*
X737561Y529759D01*
G01X737581Y529724D02*
X737576Y529744D01*
G01X737561Y534759D02*
X737542Y534764D01*
G01X737576Y534744D02*
X737561Y534759D01*
G01X737581Y534724D02*
X737576Y534744D01*
G01X737561Y559759D02*
X737542Y559764D01*
G01X737576Y559744D02*
X737561Y559759D01*
G01X737581Y559724D02*
X737576Y559744D01*
G01X737561Y564759D02*
X737542Y564764D01*
G01X737576Y564744D02*
X737561Y564759D01*
G01X737581Y564724D02*
X737576Y564744D01*
G01X737561Y569759D02*
X737542Y569764D01*
G01X737576Y569744D02*
X737561Y569759D01*
G01X737581Y569724D02*
X737576Y569744D01*
G01X724146Y543998D02*
X724139Y544006D01*
G01X724151Y543987D02*
X724146Y543998D01*
G01X724152Y543976D02*
X724151Y543987D01*
G01X724146Y537698D02*
X724139Y537707D01*
G01X724151Y537688D02*
X724146Y537698D01*
G01X724152Y537677D02*
X724151Y537688D01*
G01X724146Y540848D02*
X724139Y540856D01*
G01X724151Y540838D02*
X724146Y540848D01*
G01X724152Y540827D02*
X724151Y540838D01*
G01X724146Y547147D02*
X724139Y547156D01*
G01X724151Y547137D02*
X724146Y547147D01*
G01X724152Y547126D02*
X724151Y547137D01*
G01X724146Y550297D02*
X724139Y550305D01*
G01X724151Y550287D02*
X724146Y550297D01*
G01X724152Y550276D02*
X724151Y550287D01*
G01X724146Y553446D02*
X724139Y553455D01*
G01X724151Y553436D02*
X724146Y553446D01*
G01X724152Y553425D02*
X724151Y553436D01*
G01X724146Y556596D02*
X724139Y556604D01*
G01X724151Y556586D02*
X724146Y556596D01*
G01X724152Y556575D02*
X724151Y556586D01*
G01X736595Y568384D02*
X736596Y568386D01*
G01X736594Y568378D02*
X736595Y568384D01*
G01X736594Y568370D02*
Y568378D01*
G01X736595Y563384D02*
X736596Y563386D01*
G01X736594Y563378D02*
X736595Y563384D01*
G01X736594Y563370D02*
Y563378D01*
G01X736595Y558384D02*
X736596Y558386D01*
G01X736594Y558378D02*
X736595Y558384D01*
G01X736594Y558370D02*
Y558378D01*
G01X736595Y533384D02*
X736596Y533386D01*
G01X736594Y533378D02*
X736595Y533384D01*
G01X736594Y533370D02*
Y533378D01*
G01X736595Y528384D02*
X736596Y528386D01*
G01X736594Y528378D02*
X736595Y528384D01*
G01X736594Y528370D02*
Y528378D01*
G01X736595Y523384D02*
X736596Y523386D01*
G01X736594Y523378D02*
X736595Y523384D01*
G01X736594Y523370D02*
Y523378D01*
G01X736595Y518384D02*
X736596Y518386D01*
G01X736594Y518378D02*
X736595Y518384D01*
G01X736594Y518370D02*
Y518378D01*
G01X736595Y513384D02*
X736596Y513386D01*
G01X736594Y513378D02*
X736595Y513384D01*
G01X736594Y513370D02*
Y513378D01*
G01X736595Y508384D02*
X736596Y508386D01*
G01X736594Y508378D02*
X736595Y508384D01*
G01X736594Y508370D02*
Y508378D01*
G01X736595Y503384D02*
X736596Y503386D01*
G01X736594Y503378D02*
X736595Y503384D01*
G01X736594Y503370D02*
Y503378D01*
G01X723206Y555261D02*
X723205Y555275D01*
G01X723209Y555249D02*
X723206Y555261D01*
G01X723209Y555236D02*
Y555249D01*
G01X723206Y552112D02*
X723205Y552126D01*
G01X723209Y552099D02*
X723206Y552112D01*
G01X723209Y552087D02*
Y552099D01*
G01X723206Y548962D02*
X723205Y548976D01*
G01X723209Y548950D02*
X723206Y548962D01*
G01X723209Y548937D02*
Y548950D01*
G01X723206Y545813D02*
X723205Y545826D01*
G01X723209Y545800D02*
X723206Y545813D01*
G01X723209Y545787D02*
Y545800D01*
G01X723206Y542663D02*
X723205Y542677D01*
G01X723209Y542650D02*
X723206Y542663D01*
G01X723209Y542638D02*
Y542650D01*
G01X723206Y539513D02*
X723205Y539527D01*
G01X723209Y539501D02*
X723206Y539513D01*
G01X723209Y539488D02*
Y539501D01*
G01X723206Y536364D02*
X723205Y536378D01*
G01X723209Y536351D02*
X723206Y536364D01*
G01X723209Y536339D02*
Y536351D01*
G01X724117Y556785D02*
X724118Y556772D01*
G01X724113Y556798D02*
X724117Y556785D01*
G01X724114Y556811D02*
X724113Y556798D01*
G01X724117Y553636D02*
X724118Y553622D01*
G01X724113Y553649D02*
X724117Y553636D01*
G01X724114Y553661D02*
X724113Y553649D01*
G01X724117Y550486D02*
X724118Y550472D01*
G01X724113Y550499D02*
X724117Y550486D01*
G01X724114Y550512D02*
X724113Y550499D01*
G01X724117Y547337D02*
X724118Y547323D01*
G01X724113Y547350D02*
X724117Y547337D01*
G01X724114Y547362D02*
X724113Y547350D01*
G01X724117Y544187D02*
X724118Y544173D01*
G01X724113Y544200D02*
X724117Y544187D01*
G01X724114Y544213D02*
X724113Y544200D01*
G01X724117Y541037D02*
X724118Y541024D01*
G01X724113Y541050D02*
X724117Y541037D01*
G01X724114Y541063D02*
X724113Y541050D01*
G01X724117Y537888D02*
X724118Y537874D01*
G01X724113Y537901D02*
X724117Y537888D01*
G01X724114Y537913D02*
X724113Y537901D01*
G01X723169Y542868D02*
Y542861D01*
G01X723168Y542872D02*
X723169Y542868D01*
G01X723168Y542865D02*
Y542872D01*
G01X723169Y552317D02*
Y552309D01*
G01X723168Y552321D02*
X723169Y552317D01*
G01X723168Y552314D02*
Y552321D01*
G01X724113Y555249D02*
X724114Y555236D01*
G01X724116Y555261D02*
X724113Y555249D01*
G01X724117Y555275D02*
X724116Y555261D01*
G01X724113Y552099D02*
X724114Y552087D01*
G01X724116Y552112D02*
X724113Y552099D01*
G01X724117Y552126D02*
X724116Y552112D01*
G01X724113Y548950D02*
X724114Y548937D01*
G01X724116Y548962D02*
X724113Y548950D01*
G01X724117Y548976D02*
X724116Y548962D01*
G01X724113Y545800D02*
X724114Y545787D01*
G01X724116Y545813D02*
X724113Y545800D01*
G01X724117Y545826D02*
X724116Y545813D01*
G01X724113Y542650D02*
X724114Y542638D01*
G01X724116Y542663D02*
X724113Y542650D01*
G01X724117Y542677D02*
X724116Y542663D01*
G01X724113Y539501D02*
X724114Y539488D01*
G01X724116Y539513D02*
X724113Y539501D01*
G01X724117Y539527D02*
X724116Y539513D01*
G01X724113Y536351D02*
X724114Y536339D01*
G01X724116Y536364D02*
X724113Y536351D01*
G01X724117Y536378D02*
X724116Y536364D01*
G01X723169Y536569D02*
Y536561D01*
G01X723168Y536573D02*
X723169Y536569D01*
G01X723168Y536567D02*
Y536573D01*
G01X723182Y556606D02*
X723206Y556614D01*
G01X723171Y556591D02*
X723182Y556606D01*
G01X723169Y556584D02*
X723171Y556591D01*
G01X723182Y553456D02*
X723206Y553465D01*
G01X723171Y553441D02*
X723182Y553456D01*
G01X723169Y553435D02*
X723171Y553441D01*
G01X723182Y550306D02*
X723206Y550315D01*
G01X723171Y550292D02*
X723182Y550306D01*
G01X723169Y550285D02*
X723171Y550292D01*
G01X723182Y547157D02*
X723206Y547165D01*
G01X723171Y547142D02*
X723182Y547157D01*
G01X723169Y547135D02*
X723171Y547142D01*
G01X723182Y544007D02*
X723206Y544016D01*
G01X723171Y543993D02*
X723182Y544007D01*
G01X723169Y543986D02*
X723171Y543993D01*
G01X723182Y540857D02*
X723206Y540866D01*
G01X723171Y540843D02*
X723182Y540857D01*
G01X723169Y540836D02*
X723171Y540843D01*
G01X723182Y537708D02*
X723206Y537717D01*
G01X723171Y537693D02*
X723182Y537708D01*
G01X723169Y537687D02*
X723171Y537693D01*
G01X723172Y537697D02*
X723167Y537677D01*
G01X723187Y537711D02*
X723172Y537697D01*
G01X723206Y537717D02*
X723187Y537711D01*
G01X724147Y536555D02*
X724152Y536575D01*
G01X724132Y536541D02*
X724147Y536555D01*
G01X724113Y536535D02*
X724132Y536541D01*
G01X724153Y552302D02*
X724154Y552309D01*
G01X724150Y552295D02*
X724153Y552302D01*
G01X724147Y552289D02*
X724150Y552295D01*
G01X724142Y552283D02*
X724147Y552289D01*
G01X724136Y552278D02*
X724142Y552283D01*
G01X724129Y552275D02*
X724136Y552278D01*
G01X724122Y552273D02*
X724129Y552275D01*
G01X724114Y552272D02*
X724122Y552273D01*
G01X724131Y536528D02*
X724134Y536530D01*
G01X724128Y536526D02*
X724131Y536528D01*
G01X724125Y536526D02*
X724128D01*
G01X724121Y536525D02*
X724125Y536526D01*
G01X724118Y536524D02*
X724121Y536525D01*
G01X724114Y536524D02*
X724118D01*
G01X723192Y537724D02*
X723189Y537722D01*
G01X723195Y537725D02*
X723192Y537724D01*
G01X723198Y537726D02*
X723195Y537725D01*
G01X723202Y537727D02*
X723198Y537726D01*
G01X723205Y537728D02*
X723202Y537727D01*
G01X723209Y537728D02*
X723205D01*
G01X724131Y539677D02*
X724134Y539679D01*
G01X724128Y539676D02*
X724131Y539677D01*
G01X724125Y539675D02*
X724128Y539676D01*
G01X724121Y539674D02*
X724125Y539675D01*
G01X724118Y539674D02*
X724121D01*
G01X724114D02*
X724118D01*
G01X723192Y540874D02*
X723189Y540872D01*
G01X723195Y540875D02*
X723192Y540874D01*
G01X723198Y540876D02*
X723195Y540875D01*
G01X723202Y540877D02*
X723198Y540876D01*
G01X723205Y540877D02*
X723202D01*
G01X723209D02*
X723205D01*
G01X724131Y542827D02*
X724134Y542829D01*
G01X724128Y542826D02*
X724131Y542827D01*
G01X724125Y542825D02*
X724128Y542826D01*
G01X724121Y542824D02*
X724125Y542825D01*
G01X724118Y542824D02*
X724121D01*
G01X724114Y542823D02*
X724118Y542824D01*
G01X723192Y544023D02*
X723189Y544022D01*
G01X723195Y544024D02*
X723192Y544023D01*
G01X723198Y544026D02*
X723195Y544024D01*
G01X723202Y544026D02*
X723198D01*
G01X723205Y544027D02*
X723202Y544026D01*
G01X723209Y544027D02*
X723205D01*
G01X724131Y545976D02*
X724134Y545978D01*
G01X724128Y545975D02*
X724131Y545976D01*
G01X724125Y545974D02*
X724128Y545975D01*
G01X724121Y545974D02*
X724125D01*
G01X724118Y545973D02*
X724121Y545974D01*
G01X724114Y545973D02*
X724118D01*
G01X723192Y547173D02*
X723189Y547171D01*
G01X723195Y547174D02*
X723192Y547173D01*
G01X723198Y547175D02*
X723195Y547174D01*
G01X723202Y547176D02*
X723198Y547175D01*
G01X723205Y547176D02*
X723202D01*
G01X723209D02*
X723205D01*
G01X724131Y549126D02*
X724134Y549128D01*
G01X724128Y549125D02*
X724131Y549126D01*
G01X724125Y549124D02*
X724128Y549125D01*
G01X724121Y549123D02*
X724125Y549124D01*
G01X724118Y549123D02*
X724121D01*
G01X724114Y549122D02*
X724118Y549123D01*
G01X723192Y550322D02*
X723189Y550321D01*
G01X723195Y550324D02*
X723192Y550322D01*
G01X723198Y550325D02*
X723195Y550324D01*
G01X723202Y550326D02*
X723198Y550325D01*
G01X723205Y550326D02*
X723202D01*
G01X723209D02*
X723205D01*
G01X723192Y553472D02*
X723189Y553470D01*
G01X723195Y553473D02*
X723192Y553472D01*
G01X723198Y553474D02*
X723195Y553473D01*
G01X723202Y553475D02*
X723198Y553474D01*
G01X723205Y553476D02*
X723202Y553475D01*
G01X723209Y553476D02*
X723205D01*
G01X724131Y555425D02*
X724134Y555427D01*
G01X724128Y555424D02*
X724131Y555425D01*
G01X724125Y555423D02*
X724128Y555424D01*
G01X724121Y555422D02*
X724125Y555423D01*
G01X724118Y555422D02*
X724121D01*
G01X724114D02*
X724118D01*
G01X723192Y556622D02*
X723189Y556620D01*
G01X723195Y556623D02*
X723192Y556622D01*
G01X723198Y556624D02*
X723195Y556623D01*
G01X723202Y556625D02*
X723198Y556624D01*
G01X723205Y556625D02*
X723202D01*
G01X723209D02*
X723205D01*
G01X722422Y539724D02*
X721988D01*
G01X722796D02*
X722422D01*
G01Y546024D02*
X721988D01*
G01X722796D02*
X722422D01*
G01Y549173D02*
X721988D01*
G01X722796D02*
X722422D01*
G01X724144Y547164D02*
X724148Y547158D01*
G01X724139Y547168D02*
X724144Y547164D01*
G01X724133Y547172D02*
X724139Y547168D01*
G01X724128Y547174D02*
X724133Y547172D01*
G01X724121Y547176D02*
X724128Y547174D01*
G01X724114Y547176D02*
X724121D01*
G01X724144Y550313D02*
X724148Y550308D01*
G01X724139Y550318D02*
X724144Y550313D01*
G01X724133Y550321D02*
X724139Y550318D01*
G01X724128Y550324D02*
X724133Y550321D01*
G01X724121Y550326D02*
X724128Y550324D01*
G01X724114Y550326D02*
X724121D01*
G01X724144Y553463D02*
X724148Y553457D01*
G01X724139Y553467D02*
X724144Y553463D01*
G01X724133Y553471D02*
X724139Y553467D01*
G01X724128Y553474D02*
X724133Y553471D01*
G01X724121Y553475D02*
X724128Y553474D01*
G01X724114Y553476D02*
X724121Y553475D01*
G01X724144Y556613D02*
X724148Y556607D01*
G01X724139Y556617D02*
X724144Y556613D01*
G01X724133Y556620D02*
X724139Y556617D01*
G01X724128Y556623D02*
X724133Y556620D01*
G01X724121Y556625D02*
X724128Y556623D01*
G01X724114Y556625D02*
X724121D01*
G01X723170Y552302D02*
X723169Y552309D01*
G01X723172Y552295D02*
X723170Y552302D01*
G01X723176Y552289D02*
X723172Y552295D01*
G01X723181Y552283D02*
X723176Y552289D01*
G01X723187Y552278D02*
X723181Y552283D01*
G01X723194Y552275D02*
X723187Y552278D01*
G01X723201Y552273D02*
X723194Y552275D01*
G01X723209Y552272D02*
X723201Y552273D01*
G01X723170Y555452D02*
X723169Y555459D01*
G01X723172Y555444D02*
X723170Y555452D01*
G01X723176Y555438D02*
X723172Y555444D01*
G01X723181Y555433D02*
X723176Y555438D01*
G01X723187Y555428D02*
X723181Y555433D01*
G01X723194Y555424D02*
X723187Y555428D01*
G01X723201Y555422D02*
X723194Y555424D01*
G01X723209Y555422D02*
X723201D01*
G01X724154Y556581D02*
Y556588D01*
G01X724153Y556576D02*
X724154Y556581D01*
G01X724152Y556575D02*
X724153Y556576D01*
G01X724154Y553431D02*
Y553439D01*
G01X724153Y553427D02*
X724154Y553431D01*
G01X724152Y553425D02*
X724153Y553427D01*
G01X724154Y550282D02*
Y550289D01*
G01X724153Y550277D02*
X724154Y550282D01*
G01X724152Y550276D02*
X724153Y550277D01*
G01X724154Y547132D02*
Y547139D01*
G01X724153Y547128D02*
X724154Y547132D01*
G01X724152Y547126D02*
X724153Y547128D01*
G01X724154Y543983D02*
Y543990D01*
G01X724153Y543978D02*
X724154Y543983D01*
G01X724152Y543976D02*
X724153Y543978D01*
G01X724154Y540833D02*
Y540840D01*
G01X724153Y540828D02*
X724154Y540833D01*
G01X724152Y540827D02*
X724153Y540828D01*
G01X724154Y537683D02*
Y537691D01*
G01X724153Y537679D02*
X724154Y537683D01*
G01X724152Y537677D02*
X724153Y537679D01*
G01X723169Y546018D02*
Y546010D01*
G01X723168Y546022D02*
X723169Y546018D01*
G01X723167Y546019D02*
X723168Y546022D01*
G01X723169Y539719D02*
Y539711D01*
G01X723168Y539723D02*
X723169Y539719D01*
G01X723167Y539721D02*
X723168Y539723D01*
G01X724114Y556619D02*
Y556625D01*
G01X724113Y556615D02*
X724114Y556619D01*
G01X724113Y556614D02*
Y556615D01*
G01X724114Y553470D02*
Y553476D01*
G01X724113Y553466D02*
X724114Y553470D01*
G01X724113Y553465D02*
Y553466D01*
G01X724114Y550320D02*
Y550326D01*
G01X724113Y550316D02*
X724114Y550320D01*
G01X724113Y550315D02*
Y550316D01*
G01X724114Y547170D02*
Y547176D01*
G01X724113Y547167D02*
X724114Y547170D01*
G01X724113Y547165D02*
Y547167D01*
G01X724114Y544021D02*
Y544027D01*
G01X724113Y544017D02*
X724114Y544021D01*
G01X724113Y544016D02*
Y544017D01*
G01X724114Y540871D02*
Y540877D01*
G01X724113Y540867D02*
X724114Y540871D01*
G01X724113Y540866D02*
Y540867D01*
G01X724114Y537722D02*
Y537728D01*
G01X724113Y537718D02*
X724114Y537722D01*
G01X724113Y537717D02*
Y537718D01*
G01X723172Y540846D02*
X723167Y540827D01*
G01X723187Y540861D02*
X723172Y540846D01*
G01X723206Y540866D02*
X723187Y540861D01*
G01X723172Y543996D02*
X723167Y543976D01*
G01X723187Y544010D02*
X723172Y543996D01*
G01X723206Y544016D02*
X723187Y544010D01*
G01X723172Y547146D02*
X723167Y547126D01*
G01X723187Y547160D02*
X723172Y547146D01*
G01X723206Y547165D02*
X723187Y547160D01*
G01X723172Y550295D02*
X723167Y550276D01*
G01X723187Y550309D02*
X723172Y550295D01*
G01X723206Y550315D02*
X723187Y550309D01*
G01X723172Y553445D02*
X723167Y553425D01*
G01X723187Y553459D02*
X723172Y553445D01*
G01X723206Y553465D02*
X723187Y553459D01*
G01X723172Y556594D02*
X723167Y556575D01*
G01X723187Y556609D02*
X723172Y556594D01*
G01X723206Y556614D02*
X723187Y556609D01*
G01X724147Y539705D02*
X724152Y539724D01*
G01X724132Y539690D02*
X724147Y539705D01*
G01X724113Y539685D02*
X724132Y539690D01*
G01X724147Y542854D02*
X724152Y542874D01*
G01X724132Y542840D02*
X724147Y542854D01*
G01X724113Y542835D02*
X724132Y542840D01*
G01X724147Y546004D02*
X724152Y546024D01*
G01X724132Y545989D02*
X724147Y546004D01*
G01X724113Y545984D02*
X724132Y545989D01*
G01X724147Y549154D02*
X724152Y549173D01*
G01X724132Y549139D02*
X724147Y549154D01*
G01X724113Y549134D02*
X724132Y549139D01*
G01X724147Y552303D02*
X724152Y552323D01*
G01X724132Y552289D02*
X724147Y552303D01*
G01X724113Y552283D02*
X724132Y552289D01*
G01X724147Y555453D02*
X724152Y555472D01*
G01X724132Y555438D02*
X724147Y555453D01*
G01X724113Y555433D02*
X724132Y555438D01*
G01X737579Y568378D02*
Y568369D01*
G01X737580Y568384D02*
X737579Y568378D01*
G01X737581Y568386D02*
X737580Y568384D01*
G01X737579Y563378D02*
Y563369D01*
G01X737580Y563384D02*
X737579Y563378D01*
G01X737581Y563386D02*
X737580Y563384D01*
G01X737579Y558378D02*
Y558369D01*
G01X737580Y558384D02*
X737579Y558378D01*
G01X737581Y558386D02*
X737580Y558384D01*
G01X737579Y533378D02*
Y533369D01*
G01X737580Y533384D02*
X737579Y533378D01*
G01X737581Y533386D02*
X737580Y533384D01*
G01X737579Y528378D02*
Y528369D01*
G01X737580Y528384D02*
X737579Y528378D01*
G01X737581Y528386D02*
X737580Y528384D01*
G01X737579Y523378D02*
Y523369D01*
G01X737580Y523384D02*
X737579Y523378D01*
G01X737581Y523386D02*
X737580Y523384D01*
G01X737579Y518378D02*
Y518369D01*
G01X737580Y518384D02*
X737579Y518378D01*
G01X737581Y518386D02*
X737580Y518384D01*
G01X737579Y513378D02*
Y513369D01*
G01X737580Y513384D02*
X737579Y513378D01*
G01X737581Y513386D02*
X737580Y513384D01*
G01X737579Y508378D02*
Y508369D01*
G01X737580Y508384D02*
X737579Y508378D01*
G01X737581Y508386D02*
X737580Y508384D01*
G01X737579Y503378D02*
Y503369D01*
G01X737580Y503384D02*
X737579Y503378D01*
G01X737581Y503386D02*
X737580Y503384D01*
G01X723169Y556581D02*
Y556588D01*
G01X723168Y556576D02*
X723169Y556581D01*
G01X723167Y556575D02*
X723168Y556576D01*
G01X723169Y553431D02*
Y553439D01*
G01X723168Y553427D02*
X723169Y553431D01*
G01X723167Y553425D02*
X723168Y553427D01*
G01X723169Y550281D02*
Y550289D01*
G01X723168Y550277D02*
X723169Y550281D01*
G01X723167Y550276D02*
X723168Y550277D01*
G01X723169Y547132D02*
Y547139D01*
G01X723168Y547128D02*
X723169Y547132D01*
G01X723167Y547126D02*
X723168Y547128D01*
G01X723169Y543982D02*
Y543990D01*
G01X723168Y543978D02*
X723169Y543982D01*
G01X723167Y543976D02*
X723168Y543978D01*
G01X723169Y540833D02*
Y540840D01*
G01X723168Y540828D02*
X723169Y540833D01*
G01X723167Y540827D02*
X723168Y540828D01*
G01X723169Y537683D02*
Y537691D01*
G01X723168Y537679D02*
X723169Y537683D01*
G01X723167Y537677D02*
X723168Y537679D01*
G01X724151Y555446D02*
X724154Y555459D01*
G01X724144Y555435D02*
X724151Y555446D01*
G01X724134Y555427D02*
X724144Y555435D01*
G01X724151Y549147D02*
X724154Y549159D01*
G01X724144Y549136D02*
X724151Y549147D01*
G01X724134Y549128D02*
X724144Y549136D01*
G01X724151Y545998D02*
X724154Y546010D01*
G01X724144Y545986D02*
X724151Y545998D01*
G01X724134Y545978D02*
X724144Y545986D01*
G01X724151Y542848D02*
X724154Y542860D01*
G01X724144Y542837D02*
X724151Y542848D01*
G01X724134Y542829D02*
X724144Y542837D01*
G01X724151Y539698D02*
X724154Y539711D01*
G01X724144Y539687D02*
X724151Y539698D01*
G01X724134Y539679D02*
X724144Y539687D01*
G01X724151Y536549D02*
X724154Y536561D01*
G01X724144Y536537D02*
X724151Y536549D01*
G01X724134Y536530D02*
X724144Y536537D01*
G01X723208Y556619D02*
Y556625D01*
G01Y556615D02*
Y556619D01*
G01X723206Y556614D02*
X723208Y556615D01*
G01Y553469D02*
Y553476D01*
G01Y553466D02*
Y553469D01*
G01X723206Y553465D02*
X723208Y553466D01*
G01Y550320D02*
Y550326D01*
G01Y550316D02*
Y550320D01*
G01X723206Y550315D02*
X723208Y550316D01*
G01Y547170D02*
Y547176D01*
G01Y547167D02*
Y547170D01*
G01X723206Y547165D02*
X723208Y547167D01*
G01Y544020D02*
Y544027D01*
G01Y544017D02*
Y544020D01*
G01X723206Y544016D02*
X723208Y544017D01*
G01Y540871D02*
Y540877D01*
G01Y540867D02*
Y540871D01*
G01X723206Y540866D02*
X723208Y540867D01*
G01Y537721D02*
Y537728D01*
G01Y537718D02*
Y537721D01*
G01X723206Y537717D02*
X723208Y537718D01*
G01X723170Y556594D02*
X723169Y556588D01*
G01X723172Y556601D02*
X723170Y556594D01*
G01X723174Y556607D02*
X723172Y556601D01*
G01X723178Y556612D02*
X723174Y556607D01*
G01X723183Y556617D02*
X723178Y556612D01*
G01X723189Y556620D02*
X723183Y556617D01*
G01X723170Y553445D02*
X723169Y553439D01*
G01X723172Y553451D02*
X723170Y553445D01*
G01X723174Y553457D02*
X723172Y553451D01*
G01X723178Y553462D02*
X723174Y553457D01*
G01X723183Y553467D02*
X723178Y553462D01*
G01X723189Y553470D02*
X723183Y553467D01*
G01X723170Y550295D02*
X723169Y550289D01*
G01X723172Y550302D02*
X723170Y550295D01*
G01X723174Y550307D02*
X723172Y550302D01*
G01X723178Y550313D02*
X723174Y550307D01*
G01X723183Y550317D02*
X723178Y550313D01*
G01X723189Y550321D02*
X723183Y550317D01*
G01X723170Y547146D02*
X723169Y547139D01*
G01X723172Y547152D02*
X723170Y547146D01*
G01X723174Y547158D02*
X723172Y547152D01*
G01X723178Y547163D02*
X723174Y547158D01*
G01X723183Y547168D02*
X723178Y547163D01*
G01X723189Y547171D02*
X723183Y547168D01*
G01X723170Y543996D02*
X723169Y543990D01*
G01X723172Y544002D02*
X723170Y543996D01*
G01X723174Y544008D02*
X723172Y544002D01*
G01X723178Y544013D02*
X723174Y544008D01*
G01X723183Y544018D02*
X723178Y544013D01*
G01X723189Y544022D02*
X723183Y544018D01*
G01X723170Y540846D02*
X723169Y540840D01*
G01X723172Y540853D02*
X723170Y540846D01*
G01X723174Y540859D02*
X723172Y540853D01*
G01X723178Y540864D02*
X723174Y540859D01*
G01X723183Y540869D02*
X723178Y540864D01*
G01X723189Y540872D02*
X723183Y540869D01*
G01X723170Y537697D02*
X723169Y537691D01*
G01X723172Y537703D02*
X723170Y537697D01*
G01X723174Y537709D02*
X723172Y537703D01*
G01X723178Y537714D02*
X723174Y537709D01*
G01X723183Y537719D02*
X723178Y537714D01*
G01X723189Y537722D02*
X723183Y537719D01*
G01X724125Y555435D02*
X724113Y555433D01*
G01X724135Y555440D02*
X724125Y555435D01*
G01Y552285D02*
X724113Y552283D01*
G01X724135Y552290D02*
X724125Y552285D01*
G01Y549136D02*
X724113Y549134D01*
G01X724135Y549141D02*
X724125Y549136D01*
G01Y545986D02*
X724113Y545984D01*
G01X724135Y545991D02*
X724125Y545986D01*
G01Y542837D02*
X724113Y542835D01*
G01X724135Y542841D02*
X724125Y542837D01*
G01Y539687D02*
X724113Y539685D01*
G01X724135Y539692D02*
X724125Y539687D01*
G01Y536537D02*
X724113Y536535D01*
G01X724135Y536542D02*
X724125Y536537D01*
G01X728150Y477894D02*
G03X728740Y477303I590J-1D01*
G01X735433D02*
G03X736024Y477894I0J591D01*
G01X733268Y479075D02*
G03Y481043I0J984D01*
G01X730906D02*
G03Y479075I0J-984D01*
G01X733189Y492264D02*
G03I-1102J0D01*
G01X734646Y486988D02*
G03X735827Y488169I0J1181D01*
G01X728346D02*
G03X729528Y486988I1181J0D01*
G01X733661Y492264D02*
G03I-1574J0D01*
G01X721260Y478484D02*
G03X723228Y476516I1968J0D01*
G01X740945D02*
G03X742913Y478484I0J1968D01*
G01X727559Y500256D02*
X726378Y499075D01*
G01X724606Y497579D02*
X721260Y494232D01*
G01X737008Y556437D02*
X738189Y557618D01*
G01X733071Y556437D02*
X734252Y557618D01*
G01X734571Y495335D02*
X733268Y493366D01*
G01X728595Y487444D02*
X730906Y491673D01*
G01X723056Y555472D02*
X723168Y555464D01*
G01X723167Y546019D02*
X723056Y546024D01*
G01X723167Y539721D02*
X723056Y539724D01*
G01X723167Y549170D02*
X723056Y549173D01*
G01X737579Y570256D02*
X736594D01*
G01X736596Y569764D02*
X741929D01*
G01Y569724D02*
X737581D01*
G01X741929Y568386D02*
X736596D01*
G01X736594Y567894D02*
X737579D01*
G01Y565256D02*
X736594D01*
G01X736596Y564764D02*
X741929D01*
G01Y564724D02*
X737581D01*
G01X741929Y563386D02*
X736596D01*
G01X736594Y562894D02*
X737579D01*
G01Y560256D02*
X736594D01*
G01X736596Y559764D02*
X741929D01*
G01Y559724D02*
X737581D01*
G01X724606Y558780D02*
X721260D01*
G01X741929Y558386D02*
X736596D01*
G01X736594Y557894D02*
X737579D01*
G01X734252Y557618D02*
X738189D01*
G01X724114Y556811D02*
X723209D01*
G01X724154Y556772D02*
X723169D01*
G01X724113Y556614D02*
X718228D01*
G01Y556575D02*
X724152D01*
G01X733071Y556437D02*
X737008D01*
G01X724152Y555472D02*
X718228D01*
G01X724113Y555433D02*
X718228D01*
G01X723169Y555276D02*
X724154D01*
G01X723209Y555236D02*
X724114D01*
G01Y553661D02*
X723209D01*
G01X724154Y553622D02*
X723169D01*
G01X724113Y553465D02*
X718228D01*
G01Y553425D02*
X724152D01*
G01Y552323D02*
X718228D01*
G01X724113Y552283D02*
X718228D01*
G01X723169Y552126D02*
X724154D01*
G01X723209Y552087D02*
X724114D01*
G01Y550512D02*
X723209D01*
G01X724154Y550472D02*
X723169D01*
G01X724113Y550315D02*
X718228D01*
G01Y550276D02*
X724152D01*
G01Y549173D02*
X718228D01*
G01X724113Y549134D02*
X718228D01*
G01X723169Y548976D02*
X724154D01*
G01X723209Y548937D02*
X724114D01*
G01Y547362D02*
X723209D01*
G01X724154Y547323D02*
X723169D01*
G01X724113Y547165D02*
X718228D01*
G01Y547126D02*
X724152D01*
G01Y546024D02*
X718228D01*
G01X724113Y545984D02*
X718228D01*
G01X723169Y545827D02*
X724154D01*
G01X723209Y545787D02*
X724114D01*
G01Y544213D02*
X723209D01*
G01X724154Y544173D02*
X723169D01*
G01X724113Y544016D02*
X718228D01*
G01Y543976D02*
X724152D01*
G01Y542874D02*
X718228D01*
G01X724113Y542835D02*
X718228D01*
G01X723169Y542677D02*
X724154D01*
G01X723209Y542638D02*
X724114D01*
G01Y541063D02*
X723209D01*
G01X724154Y541024D02*
X723169D01*
G01X724113Y540866D02*
X718228D01*
G01Y540827D02*
X724152D01*
G01Y539724D02*
X718228D01*
G01X724113Y539685D02*
X718228D01*
G01X723169Y539528D02*
X724154D01*
G01X723209Y539488D02*
X724114D01*
G01Y537913D02*
X723209D01*
G01X724154Y537874D02*
X723169D01*
G01X724113Y537717D02*
X718228D01*
G01Y537677D02*
X724152D01*
G01X737008Y536713D02*
X733071D01*
G01X724152Y536575D02*
X718228D01*
G01X724113Y536535D02*
X718228D01*
G01X723169Y536378D02*
X724154D01*
G01X723209Y536339D02*
X724114D01*
G01X738189Y535531D02*
X734252D01*
G01X737579Y535256D02*
X736594D01*
G01X736596Y534764D02*
X741929D01*
G01Y534724D02*
X737581D01*
G01X724606Y534370D02*
X721260D01*
G01X741929Y533386D02*
X736596D01*
G01X736594Y532894D02*
X737579D01*
G01Y530256D02*
X736594D01*
G01X736596Y529764D02*
X741929D01*
G01Y529724D02*
X737581D01*
G01X741929Y528386D02*
X736596D01*
G01X736594Y569959D02*
X737550Y569961D01*
G01X737579Y568190D02*
X736594Y568189D01*
G01Y564959D02*
X737550Y564961D01*
G01X737579Y563190D02*
X736594Y563189D01*
G01Y559959D02*
X737550Y559961D01*
G01X737579Y558190D02*
X736594Y558189D01*
G01Y534959D02*
X737550Y534961D01*
G01X737579Y533190D02*
X736594Y533189D01*
G01Y529959D02*
X737550Y529961D01*
G01X737579Y528190D02*
X736594Y528189D01*
G01X737579Y504738D02*
Y504746D01*
G01Y509738D02*
Y509746D01*
G01Y514738D02*
Y514746D01*
G01Y519738D02*
Y519746D01*
G01Y524738D02*
Y524746D01*
G01Y529738D02*
Y529746D01*
G01Y534738D02*
Y534746D01*
G01Y559738D02*
Y559746D01*
G01Y564738D02*
Y564746D01*
G01Y569738D02*
Y569746D01*
G01X742913Y478484D02*
Y494232D01*
G01X741929Y568386D02*
Y569764D01*
G01Y563386D02*
Y564764D01*
G01Y558386D02*
Y559764D01*
G01Y533386D02*
Y534764D01*
G01Y528386D02*
Y529764D01*
G01Y523386D02*
Y524764D01*
G01Y518386D02*
Y519764D01*
G01Y513386D02*
Y514764D01*
G01Y508386D02*
Y509764D01*
G01Y503386D02*
Y504764D01*
G01X739567Y635571D02*
Y497579D01*
G01X738976Y637815D02*
Y495335D01*
G01X738760Y504764D02*
Y503386D01*
G01Y509764D02*
Y508386D01*
G01Y514764D02*
Y513386D01*
G01Y519764D02*
Y518386D01*
G01Y524764D02*
Y523386D01*
G01Y529764D02*
Y528386D01*
G01Y534764D02*
Y533386D01*
G01Y559764D02*
Y558386D01*
G01Y564764D02*
Y563386D01*
G01Y569764D02*
Y568386D01*
G01X738189Y557618D02*
Y535531D01*
G01X737579Y504738D02*
Y504881D01*
G01Y509738D02*
Y509881D01*
G01Y514738D02*
Y514881D01*
G01Y519738D02*
Y519881D01*
G01Y524738D02*
Y524881D01*
G01Y529738D02*
Y529881D01*
G01Y534738D02*
Y534881D01*
G01Y559738D02*
Y559881D01*
G01Y564738D02*
Y564881D01*
G01Y567894D02*
Y570256D01*
G01Y562894D02*
Y565256D01*
G01Y557894D02*
Y560256D01*
G01Y532894D02*
Y535256D01*
G01Y527894D02*
Y530256D01*
G01Y522894D02*
Y525256D01*
G01Y517894D02*
Y520256D01*
G01Y512894D02*
Y515256D01*
G01Y507894D02*
Y510256D01*
G01Y502894D02*
Y505256D01*
G01X737008Y556437D02*
Y536713D01*
G01X736594Y505256D02*
Y502894D01*
G01Y510256D02*
Y507894D01*
G01Y515256D02*
Y512894D01*
G01Y520256D02*
Y517894D01*
G01Y525256D02*
Y522894D01*
G01Y530256D02*
Y527894D01*
G01Y535256D02*
Y532894D01*
G01Y560256D02*
Y557894D01*
G01Y565256D02*
Y562894D01*
G01Y570256D02*
Y567894D01*
G01X736024Y483996D02*
Y477894D01*
G01X735827Y496713D02*
Y488169D01*
G01X734252Y535531D02*
Y499075D01*
G01Y634075D02*
Y557618D01*
G01X733268Y493366D02*
Y491673D01*
G01X733071Y536713D02*
Y500256D01*
G01Y632894D02*
Y556437D01*
G01X724113Y552283D02*
X724116Y552272D01*
G01X736594Y527894D02*
X737579D01*
G01Y525256D02*
X736594D01*
G01X736596Y524764D02*
X741929D01*
G01Y524724D02*
X737581D01*
G01X741929Y523386D02*
X736596D01*
G01X736594Y522894D02*
X737579D01*
G01Y520256D02*
X736594D01*
G01X736596Y519764D02*
X741929D01*
G01Y519724D02*
X737581D01*
G01X741929Y518386D02*
X736596D01*
G01X736594Y517894D02*
X737579D01*
G01Y515256D02*
X736594D01*
G01X736596Y514764D02*
X741929D01*
G01Y514724D02*
X737581D01*
G01X741929Y513386D02*
X736596D01*
G01X736594Y512894D02*
X737579D01*
G01Y510256D02*
X736594D01*
G01X736596Y509764D02*
X741929D01*
G01Y509724D02*
X737581D01*
G01X741929Y508386D02*
X736596D01*
G01X736594Y507894D02*
X737579D01*
G01Y505256D02*
X736594D01*
G01X736596Y504764D02*
X741929D01*
G01Y504724D02*
X737581D01*
G01X741929Y503386D02*
X736596D01*
G01X736594Y502894D02*
X737579D01*
G01X733071Y500256D02*
X727559D01*
G01X734252Y499075D02*
X726378D01*
G01X739567Y497579D02*
X724606D01*
G01X735827Y496713D02*
X738976D01*
G01X728346D02*
X724606D01*
G01Y495335D02*
X738976D01*
G01X733268Y493366D02*
X730906D01*
G01X733268Y491673D02*
X730906D01*
G01X734646Y486988D02*
X729528D01*
G01X742913Y486949D02*
X721260D01*
G01X736024Y483996D02*
X728150D01*
G01Y482421D02*
X736024D01*
G01X733268Y481043D02*
X730906D01*
G01Y479075D02*
X733268D01*
G01X735433Y477303D02*
X728740D01*
G01X740945Y476516D02*
X723228D01*
G01X736594Y524959D02*
X737550Y524961D01*
G01X737579Y523190D02*
X736594Y523189D01*
G01Y519959D02*
X737550Y519961D01*
G01X737579Y518190D02*
X736594Y518189D01*
G01Y514959D02*
X737550Y514961D01*
G01X737579Y513190D02*
X736594Y513189D01*
G01Y509959D02*
X737550Y509961D01*
G01X737579Y508190D02*
X736594Y508189D01*
G01Y504959D02*
X737550Y504961D01*
G01X737579Y503190D02*
X736594Y503189D01*
G01X724153Y537679D02*
X724154Y537691D01*
G01X724153Y540829D02*
X724154Y540840D01*
G01X724153Y543978D02*
X724154Y543990D01*
G01X724153Y547128D02*
X724154Y547139D01*
G01X724153Y550278D02*
X724154Y550289D01*
G01X724153Y553427D02*
X724154Y553439D01*
G01X724153Y556577D02*
X724154Y556588D01*
G01X730906Y491673D02*
Y493366D01*
G01X728346Y488169D02*
Y496713D01*
G01X728150Y483996D02*
Y477894D01*
G01X727559Y500256D02*
Y632894D01*
G01X726378Y499075D02*
Y634075D01*
G01X724606Y534370D02*
Y495335D01*
G01Y637815D02*
Y558780D01*
G01X724154Y555275D02*
Y556772D01*
G01Y552126D02*
Y553622D01*
G01Y548976D02*
Y550472D01*
G01Y545826D02*
Y547323D01*
G01Y542677D02*
Y544173D01*
G01Y539527D02*
Y541024D01*
G01Y536378D02*
Y537874D01*
G01X724114Y536524D02*
Y536377D01*
G01Y539674D02*
Y539527D01*
G01Y541024D02*
Y540877D01*
G01Y537874D02*
Y537728D01*
G01Y545973D02*
Y545826D01*
G01Y542823D02*
Y542676D01*
G01Y544174D02*
Y544027D01*
G01Y549122D02*
Y548976D01*
G01Y550473D02*
Y550326D01*
G01Y547323D02*
Y547176D01*
G01Y555422D02*
Y555275D01*
G01Y552272D02*
Y552125D01*
G01Y553622D02*
Y553476D01*
G01Y556772D02*
Y556625D01*
G01X723209D02*
Y556772D01*
G01Y555275D02*
Y555422D01*
G01Y552125D02*
Y552272D01*
G01Y553476D02*
Y553622D01*
G01Y548976D02*
Y549122D01*
G01Y550326D02*
Y550473D01*
G01Y547176D02*
Y547323D01*
G01Y545826D02*
Y545973D01*
G01Y542676D02*
Y542823D01*
G01Y544027D02*
Y544174D01*
G01Y539527D02*
Y539674D01*
G01Y540877D02*
Y541024D01*
G01Y537728D02*
Y537874D01*
G01Y536377D02*
Y536524D01*
G01X723169Y541024D02*
Y539528D01*
G01Y537874D02*
Y536378D01*
G01Y544173D02*
Y542677D01*
G01Y550472D02*
Y548976D01*
G01Y547323D02*
Y545827D01*
G01Y553622D02*
Y552126D01*
G01Y556772D02*
Y555276D01*
G01X721988Y537717D02*
Y536535D01*
G01Y540866D02*
Y539685D01*
G01Y547165D02*
Y545984D01*
G01Y544016D02*
Y542835D01*
G01Y550315D02*
Y549134D01*
G01Y556614D02*
Y555433D01*
G01Y553465D02*
Y552283D01*
G01X721654Y558780D02*
Y534370D01*
G01X721260D02*
Y558780D01*
G01Y494232D02*
Y478484D01*
G01X718228Y555433D02*
Y556614D01*
G01Y552283D02*
Y553465D01*
G01Y549134D02*
Y550315D01*
G01Y545984D02*
Y547165D01*
G01Y542835D02*
Y544016D01*
G01Y539685D02*
Y540866D01*
G01Y536535D02*
Y537717D01*
G01X724154Y555459D02*
X724153Y555470D01*
G01X724154Y552309D02*
X724153Y552320D01*
G01X724154Y549160D02*
X724153Y549170D01*
G01X724154Y546010D02*
X724153Y546021D01*
G01X724154Y542861D02*
X724153Y542871D01*
G01X724154Y539711D02*
X724153Y539722D01*
G01X724154Y536561D02*
X724153Y536572D01*
G01X733268Y491673D02*
X735578Y487444D01*
G01X730906Y493366D02*
X729602Y495335D01*
G01X737008Y536713D02*
X738189Y535531D01*
G01X733071Y536713D02*
X734252Y535531D01*
G01X739567Y497579D02*
X742913Y494232D01*
G01X733071Y500256D02*
X734252Y499075D01*
G01X737546Y574862D02*
X737550Y574961D01*
G01X737540Y574790D02*
X737546Y574862D01*
G01X737542Y574764D02*
X737540Y574790D01*
G01X737546Y579862D02*
X737550Y579961D01*
G01X737540Y579790D02*
X737546Y579862D01*
G01X737542Y579764D02*
X737540Y579790D01*
G01X737546Y584862D02*
X737550Y584961D01*
G01X737540Y584790D02*
X737546Y584862D01*
G01X737542Y584764D02*
X737540Y584790D01*
G01X737546Y589862D02*
X737550Y589961D01*
G01X737540Y589790D02*
X737546Y589862D01*
G01X737542Y589764D02*
X737540Y589790D01*
G01X737546Y594862D02*
X737550Y594961D01*
G01X737540Y594790D02*
X737546Y594862D01*
G01X737542Y594764D02*
X737540Y594790D01*
G01X737546Y599862D02*
X737550Y599961D01*
G01X737540Y599790D02*
X737546Y599862D01*
G01X737542Y599764D02*
X737540Y599790D01*
G01X737546Y604862D02*
X737550Y604961D01*
G01X737540Y604790D02*
X737546Y604862D01*
G01X737542Y604764D02*
X737540Y604790D01*
G01X737546Y609862D02*
X737550Y609961D01*
G01X737540Y609790D02*
X737546Y609862D01*
G01X737542Y609764D02*
X737540Y609790D01*
G01X737546Y614862D02*
X737550Y614961D01*
G01X737540Y614790D02*
X737546Y614862D01*
G01X737542Y614764D02*
X737540Y614790D01*
G01X737546Y619862D02*
X737550Y619961D01*
G01X737540Y619790D02*
X737546Y619862D01*
G01X737542Y619764D02*
X737540Y619790D01*
G01X737546Y624862D02*
X737550Y624961D01*
G01X737540Y624790D02*
X737546Y624862D01*
G01X737542Y624764D02*
X737540Y624790D01*
G01X737546Y629862D02*
X737550Y629961D01*
G01X737540Y629790D02*
X737546Y629862D01*
G01X737542Y629764D02*
X737540Y629790D01*
G01X737566Y574755D02*
X737577Y574740D01*
G01X737542Y574764D02*
X737566Y574755D01*
G01Y579755D02*
X737577Y579740D01*
G01X737542Y579764D02*
X737566Y579755D01*
G01Y584755D02*
X737577Y584740D01*
G01X737542Y584764D02*
X737566Y584755D01*
G01Y589755D02*
X737577Y589740D01*
G01X737542Y589764D02*
X737566Y589755D01*
G01X737579Y574731D02*
Y574738D01*
G01X737580Y574726D02*
X737579Y574731D01*
G01X737581Y574724D02*
X737580Y574726D01*
G01X737579Y579731D02*
Y579738D01*
G01X737580Y579726D02*
X737579Y579731D01*
G01X737581Y579724D02*
X737580Y579726D01*
G01X737579Y584731D02*
Y584738D01*
G01X737580Y584726D02*
X737579Y584731D01*
G01X737581Y584724D02*
X737580Y584726D01*
G01X737579Y589731D02*
Y589738D01*
G01X737580Y589726D02*
X737579Y589731D01*
G01X737581Y589724D02*
X737580Y589726D01*
G01X737579Y594731D02*
Y594738D01*
G01X737580Y594726D02*
X737579Y594731D01*
G01X737581Y594724D02*
X737580Y594726D01*
G01X737579Y599731D02*
Y599738D01*
G01X737580Y599726D02*
X737579Y599731D01*
G01X737581Y599724D02*
X737580Y599726D01*
G01X737579Y604731D02*
Y604738D01*
G01X737580Y604726D02*
X737579Y604731D01*
G01X737581Y604724D02*
X737580Y604726D01*
G01X737579Y609731D02*
Y609738D01*
G01X737580Y609726D02*
X737579Y609731D01*
G01X737581Y609724D02*
X737580Y609726D01*
G01X737579Y614731D02*
Y614738D01*
G01X737580Y614726D02*
X737579Y614731D01*
G01X737581Y614724D02*
X737580Y614726D01*
G01X737579Y619731D02*
Y619738D01*
G01X737580Y619726D02*
X737579Y619731D01*
G01X737581Y619724D02*
X737580Y619726D01*
G01X737579Y624731D02*
Y624738D01*
G01X737580Y624726D02*
X737579Y624731D01*
G01X737581Y624724D02*
X737580Y624726D01*
G01X737579Y629731D02*
Y629738D01*
G01X737580Y629726D02*
X737579Y629731D01*
G01X737581Y629724D02*
X737580Y629726D01*
G01X736594Y574771D02*
Y574780D01*
G01X736595Y574765D02*
X736594Y574771D01*
G01X736596Y574764D02*
X736595Y574765D01*
G01X736594Y579771D02*
Y579780D01*
G01X736595Y579765D02*
X736594Y579771D01*
G01X736596Y579764D02*
X736595Y579765D01*
G01X736594Y584771D02*
Y584780D01*
G01X736595Y584765D02*
X736594Y584771D01*
G01X736596Y584764D02*
X736595Y584765D01*
G01X736594Y589771D02*
Y589780D01*
G01X736595Y589765D02*
X736594Y589771D01*
G01X736596Y589764D02*
X736595Y589765D01*
G01X736594Y594771D02*
Y594780D01*
G01X736595Y594765D02*
X736594Y594771D01*
G01X736596Y594764D02*
X736595Y594765D01*
G01X736594Y599771D02*
Y599780D01*
G01X736595Y599765D02*
X736594Y599771D01*
G01X736596Y599764D02*
X736595Y599765D01*
G01X736594Y604771D02*
Y604780D01*
G01X736595Y604765D02*
X736594Y604771D01*
G01X736596Y604764D02*
X736595Y604765D01*
G01X736594Y609771D02*
Y609780D01*
G01X736595Y609765D02*
X736594Y609771D01*
G01X736596Y609764D02*
X736595Y609765D01*
G01X736594Y614771D02*
Y614780D01*
G01X736595Y614765D02*
X736594Y614771D01*
G01X736596Y614764D02*
X736595Y614765D01*
G01X736594Y619771D02*
Y619780D01*
G01X736595Y619765D02*
X736594Y619771D01*
G01X736596Y619764D02*
X736595Y619765D01*
G01X736594Y624771D02*
Y624780D01*
G01X736595Y624765D02*
X736594Y624771D01*
G01X736596Y624764D02*
X736595Y624765D01*
G01X736594Y629771D02*
Y629780D01*
G01X736595Y629765D02*
X736594Y629771D01*
G01X736596Y629764D02*
X736595Y629765D01*
G01X737571Y574907D02*
X737579Y574881D01*
G01X737561Y574934D02*
X737571Y574907D01*
G01X737550Y574961D02*
X737561Y574934D01*
G01X737571Y579907D02*
X737579Y579881D01*
G01X737561Y579934D02*
X737571Y579907D01*
G01X737550Y579961D02*
X737561Y579934D01*
G01X737571Y584907D02*
X737579Y584881D01*
G01X737561Y584934D02*
X737571Y584907D01*
G01X737550Y584961D02*
X737561Y584934D01*
G01X737571Y589907D02*
X737579Y589881D01*
G01X737561Y589934D02*
X737571Y589907D01*
G01X737550Y589961D02*
X737561Y589934D01*
G01X737571Y594907D02*
X737579Y594881D01*
G01X737561Y594934D02*
X737571Y594907D01*
G01X737550Y594961D02*
X737561Y594934D01*
G01X737571Y599907D02*
X737579Y599881D01*
G01X737561Y599934D02*
X737571Y599907D01*
G01X737550Y599961D02*
X737561Y599934D01*
G01X737571Y604907D02*
X737579Y604881D01*
G01X737561Y604934D02*
X737571Y604907D01*
G01X737550Y604961D02*
X737561Y604934D01*
G01X737571Y609907D02*
X737579Y609881D01*
G01X737561Y609934D02*
X737571Y609907D01*
G01X737550Y609961D02*
X737561Y609934D01*
G01X737571Y614907D02*
X737579Y614881D01*
G01X737561Y614934D02*
X737571Y614907D01*
G01X737550Y614961D02*
X737561Y614934D01*
G01X737571Y619907D02*
X737579Y619881D01*
G01X737561Y619934D02*
X737571Y619907D01*
G01X737550Y619961D02*
X737561Y619934D01*
G01X737571Y624907D02*
X737579Y624881D01*
G01X737561Y624934D02*
X737571Y624907D01*
G01X737550Y624961D02*
X737561Y624934D01*
G01X737571Y629907D02*
X737579Y629881D01*
G01X737561Y629934D02*
X737571Y629907D01*
G01X737550Y629961D02*
X737561Y629934D01*
G01Y574759D02*
X737542Y574764D01*
G01X737576Y574744D02*
X737561Y574759D01*
G01X737581Y574724D02*
X737576Y574744D01*
G01X737561Y579759D02*
X737542Y579764D01*
G01X737576Y579744D02*
X737561Y579759D01*
G01X737581Y579724D02*
X737576Y579744D01*
G01X737561Y584759D02*
X737542Y584764D01*
G01X737576Y584744D02*
X737561Y584759D01*
G01X737581Y584724D02*
X737576Y584744D01*
G01X737561Y589759D02*
X737542Y589764D01*
G01X737576Y589744D02*
X737561Y589759D01*
G01X737581Y589724D02*
X737576Y589744D01*
G01X737561Y594759D02*
X737542Y594764D01*
G01X737576Y594744D02*
X737561Y594759D01*
G01X737581Y594724D02*
X737576Y594744D01*
G01X737561Y599759D02*
X737542Y599764D01*
G01X737576Y599744D02*
X737561Y599759D01*
G01X737581Y599724D02*
X737576Y599744D01*
G01X737561Y604759D02*
X737542Y604764D01*
G01X737576Y604744D02*
X737561Y604759D01*
G01X737581Y604724D02*
X737576Y604744D01*
G01X737561Y609759D02*
X737542Y609764D01*
G01X737576Y609744D02*
X737561Y609759D01*
G01X737581Y609724D02*
X737576Y609744D01*
G01X737561Y614759D02*
X737542Y614764D01*
G01X737576Y614744D02*
X737561Y614759D01*
G01X737581Y614724D02*
X737576Y614744D01*
G01X737561Y619759D02*
X737542Y619764D01*
G01X737576Y619744D02*
X737561Y619759D01*
G01X737581Y619724D02*
X737576Y619744D01*
G01X737561Y624759D02*
X737542Y624764D01*
G01X737576Y624744D02*
X737561Y624759D01*
G01X737581Y624724D02*
X737576Y624744D01*
G01X737561Y629759D02*
X737542Y629764D01*
G01X737576Y629744D02*
X737561Y629759D01*
G01X737581Y629724D02*
X737576Y629744D01*
G01X736595Y628384D02*
X736596Y628386D01*
G01X736594Y628378D02*
X736595Y628384D01*
G01X736594Y628370D02*
Y628378D01*
G01X736595Y623384D02*
X736596Y623386D01*
G01X736594Y623378D02*
X736595Y623384D01*
G01X736594Y623370D02*
Y623378D01*
G01X736595Y618384D02*
X736596Y618386D01*
G01X736594Y618378D02*
X736595Y618384D01*
G01X736594Y618370D02*
Y618378D01*
G01X736595Y613384D02*
X736596Y613386D01*
G01X736594Y613378D02*
X736595Y613384D01*
G01X736594Y613370D02*
Y613378D01*
G01X736595Y608384D02*
X736596Y608386D01*
G01X736594Y608378D02*
X736595Y608384D01*
G01X736594Y608370D02*
Y608378D01*
G01X736595Y603384D02*
X736596Y603386D01*
G01X736594Y603378D02*
X736595Y603384D01*
G01X736594Y603370D02*
Y603378D01*
G01X736595Y598384D02*
X736596Y598386D01*
G01X736594Y598378D02*
X736595Y598384D01*
G01X736594Y598370D02*
Y598378D01*
G01X736595Y593384D02*
X736596Y593386D01*
G01X736594Y593378D02*
X736595Y593384D01*
G01X736594Y593370D02*
Y593378D01*
G01X736595Y588384D02*
X736596Y588386D01*
G01X736594Y588378D02*
X736595Y588384D01*
G01X736594Y588370D02*
Y588378D01*
G01X736595Y583384D02*
X736596Y583386D01*
G01X736594Y583378D02*
X736595Y583384D01*
G01X736594Y583370D02*
Y583378D01*
G01X736595Y578384D02*
X736596Y578386D01*
G01X736594Y578378D02*
X736595Y578384D01*
G01X736594Y578370D02*
Y578378D01*
G01X736595Y573384D02*
X736596Y573386D01*
G01X736594Y573378D02*
X736595Y573384D01*
G01X736594Y573370D02*
Y573378D01*
G01X737566Y594755D02*
X737577Y594740D01*
G01X737542Y594764D02*
X737566Y594755D01*
G01Y599755D02*
X737577Y599740D01*
G01X737542Y599764D02*
X737566Y599755D01*
G01Y604755D02*
X737577Y604740D01*
G01X737542Y604764D02*
X737566Y604755D01*
G01Y609755D02*
X737577Y609740D01*
G01X737542Y609764D02*
X737566Y609755D01*
G01Y614755D02*
X737577Y614740D01*
G01X737542Y614764D02*
X737566Y614755D01*
G01Y619755D02*
X737577Y619740D01*
G01X737542Y619764D02*
X737566Y619755D01*
G01Y624755D02*
X737577Y624740D01*
G01X737542Y624764D02*
X737566Y624755D01*
G01Y629755D02*
X737577Y629740D01*
G01X737542Y629764D02*
X737566Y629755D01*
G01X737579Y628378D02*
Y628369D01*
G01X737580Y628384D02*
X737579Y628378D01*
G01X737581Y628386D02*
X737580Y628384D01*
G01X737579Y623378D02*
Y623369D01*
G01X737580Y623384D02*
X737579Y623378D01*
G01X737581Y623386D02*
X737580Y623384D01*
G01X737579Y618378D02*
Y618369D01*
G01X737580Y618384D02*
X737579Y618378D01*
G01X737581Y618386D02*
X737580Y618384D01*
G01X737579Y613378D02*
Y613369D01*
G01X737580Y613384D02*
X737579Y613378D01*
G01X737581Y613386D02*
X737580Y613384D01*
G01X737579Y608378D02*
Y608369D01*
G01X737580Y608384D02*
X737579Y608378D01*
G01X737581Y608386D02*
X737580Y608384D01*
G01X737579Y603378D02*
Y603369D01*
G01X737580Y603384D02*
X737579Y603378D01*
G01X737581Y603386D02*
X737580Y603384D01*
G01X737579Y598378D02*
Y598369D01*
G01X737580Y598384D02*
X737579Y598378D01*
G01X737581Y598386D02*
X737580Y598384D01*
G01X737579Y593378D02*
Y593369D01*
G01X737580Y593384D02*
X737579Y593378D01*
G01X737581Y593386D02*
X737580Y593384D01*
G01X737579Y588378D02*
Y588369D01*
G01X737580Y588384D02*
X737579Y588378D01*
G01X737581Y588386D02*
X737580Y588384D01*
G01X737579Y583378D02*
Y583369D01*
G01X737580Y583384D02*
X737579Y583378D01*
G01X737581Y583386D02*
X737580Y583384D01*
G01X737579Y578378D02*
Y578369D01*
G01X737580Y578384D02*
X737579Y578378D01*
G01X737581Y578386D02*
X737580Y578384D01*
G01X737579Y573378D02*
Y573369D01*
G01X737580Y573384D02*
X737579Y573378D01*
G01X737581Y573386D02*
X737580Y573384D01*
G01X736024Y655256D02*
G03X735433Y655846I-591J-1D01*
G01X728740D02*
G03X728150Y655256I0J-590D01*
G01X730906Y654075D02*
G03Y652106I0J-985D01*
G01X733268D02*
G03Y654075I0J984D01*
G01X729528Y646161D02*
G03X728346Y644980I-1J-1181D01*
G01X735827D02*
G03X734646Y646161I-1181J0D01*
G01X733976Y640886D02*
G03I-1889J0D01*
G01X742913Y654665D02*
G03X740945Y656634I-1968J1D01*
G01X723228D02*
G03X721260Y654665I1J-1969D01*
G01X734449Y640886D02*
G03I-2362J0D01*
G01X742913Y638917D02*
X739567Y635571D01*
G01X740945Y656634D02*
X723228D01*
G01X735433Y655846D02*
X728740D01*
G01X733268Y654075D02*
X730906D01*
G01Y652106D02*
X733268D01*
G01X736024Y650728D02*
X728150D01*
G01Y649154D02*
X736024D01*
G01X742913Y646201D02*
X721260D01*
G01X729528Y646161D02*
X734646D01*
G01X730906Y641476D02*
X733268D01*
G01X730906Y639783D02*
X733268D01*
G01X724606Y637815D02*
X738976D01*
G01X724606Y636437D02*
X728346D01*
G01X738976D02*
X735827D01*
G01X724606Y635571D02*
X739567D01*
G01X726378Y634075D02*
X734252D01*
G01X727559Y632894D02*
X733071D01*
G01X737579Y630256D02*
X736594D01*
G01X736596Y629764D02*
X741929D01*
G01Y629724D02*
X737581D01*
G01X741929Y628386D02*
X736596D01*
G01X736594Y627894D02*
X737579D01*
G01Y625256D02*
X736594D01*
G01X736596Y624764D02*
X741929D01*
G01Y624724D02*
X737581D01*
G01X741929Y623386D02*
X736596D01*
G01X736594Y622894D02*
X737579D01*
G01Y620256D02*
X736594D01*
G01X736596Y619764D02*
X741929D01*
G01Y619724D02*
X737581D01*
G01X741929Y618386D02*
X736596D01*
G01X736594Y617894D02*
X737579D01*
G01Y615256D02*
X736594D01*
G01X736596Y614764D02*
X741929D01*
G01Y614724D02*
X737581D01*
G01X741929Y613386D02*
X736596D01*
G01X736594Y612894D02*
X737579D01*
G01Y610256D02*
X736594D01*
G01Y629959D02*
X737550Y629961D01*
G01X737579Y628190D02*
X736594Y628189D01*
G01Y624959D02*
X737550Y624961D01*
G01X737579Y623190D02*
X736594Y623189D01*
G01Y619959D02*
X737550Y619961D01*
G01X737579Y618190D02*
X736594Y618189D01*
G01Y614959D02*
X737550Y614961D01*
G01X737579Y613190D02*
X736594Y613189D01*
G01Y609959D02*
X737550Y609961D01*
G01X733071Y632894D02*
X734252Y634075D01*
G01X729602Y637815D02*
X730906Y639783D01*
G01X735578Y645706D02*
X733268Y641476D01*
G01X736596Y609764D02*
X741929D01*
G01Y609724D02*
X737581D01*
G01X741929Y608386D02*
X736596D01*
G01X736594Y607894D02*
X737579D01*
G01Y605256D02*
X736594D01*
G01X736596Y604764D02*
X741929D01*
G01Y604724D02*
X737581D01*
G01X741929Y603386D02*
X736596D01*
G01X736594Y602894D02*
X737579D01*
G01Y600256D02*
X736594D01*
G01X736596Y599764D02*
X741929D01*
G01Y599724D02*
X737581D01*
G01X741929Y598386D02*
X736596D01*
G01X736594Y597894D02*
X737579D01*
G01Y595256D02*
X736594D01*
G01X736596Y594764D02*
X741929D01*
G01Y594724D02*
X737581D01*
G01X741929Y593386D02*
X736596D01*
G01X736594Y592894D02*
X737579D01*
G01Y590256D02*
X736594D01*
G01X736596Y589764D02*
X741929D01*
G01Y589724D02*
X737581D01*
G01X741929Y588386D02*
X736596D01*
G01X736594Y587894D02*
X737579D01*
G01Y585256D02*
X736594D01*
G01X736596Y584764D02*
X741929D01*
G01Y584724D02*
X737581D01*
G01X741929Y583386D02*
X736596D01*
G01X736594Y582894D02*
X737579D01*
G01Y580256D02*
X736594D01*
G01X736596Y579764D02*
X741929D01*
G01Y579724D02*
X737581D01*
G01X741929Y578386D02*
X736596D01*
G01X736594Y577894D02*
X737579D01*
G01Y575256D02*
X736594D01*
G01X736596Y574764D02*
X741929D01*
G01Y574724D02*
X737581D01*
G01X741929Y573386D02*
X736596D01*
G01X736594Y572894D02*
X737579D01*
G01Y608190D02*
X736594Y608189D01*
G01Y604959D02*
X737550Y604961D01*
G01X737579Y603190D02*
X736594Y603189D01*
G01Y599959D02*
X737550Y599961D01*
G01X737579Y598190D02*
X736594Y598189D01*
G01Y594959D02*
X737550Y594961D01*
G01X737579Y593190D02*
X736594Y593189D01*
G01Y589959D02*
X737550Y589961D01*
G01X737579Y588190D02*
X736594Y588189D01*
G01Y584959D02*
X737550Y584961D01*
G01X737579Y583190D02*
X736594Y583189D01*
G01Y579959D02*
X737550Y579961D01*
G01X737579Y578190D02*
X736594Y578189D01*
G01Y574959D02*
X737550Y574961D01*
G01X737579Y573190D02*
X736594Y573189D01*
G01X737579Y574738D02*
Y574746D01*
G01Y579738D02*
Y579746D01*
G01Y584738D02*
Y584746D01*
G01Y589738D02*
Y589746D01*
G01Y594738D02*
Y594746D01*
G01Y599738D02*
Y599746D01*
G01Y604738D02*
Y604746D01*
G01Y609738D02*
Y609746D01*
G01Y614738D02*
Y614746D01*
G01Y619738D02*
Y619746D01*
G01Y624738D02*
Y624746D01*
G01Y629738D02*
Y629746D01*
G01X742913Y638917D02*
Y654665D01*
G01X741929Y628386D02*
Y629764D01*
G01Y623386D02*
Y624764D01*
G01Y618386D02*
Y619764D01*
G01Y613386D02*
Y614764D01*
G01Y608386D02*
Y609764D01*
G01Y603386D02*
Y604764D01*
G01Y598386D02*
Y599764D01*
G01Y593386D02*
Y594764D01*
G01Y588386D02*
Y589764D01*
G01Y583386D02*
Y584764D01*
G01Y578386D02*
Y579764D01*
G01Y573386D02*
Y574764D01*
G01X738760D02*
Y573386D01*
G01Y579764D02*
Y578386D01*
G01Y584764D02*
Y583386D01*
G01Y589764D02*
Y588386D01*
G01Y594764D02*
Y593386D01*
G01Y599764D02*
Y598386D01*
G01Y604764D02*
Y603386D01*
G01Y609764D02*
Y608386D01*
G01Y614764D02*
Y613386D01*
G01Y619764D02*
Y618386D01*
G01Y624764D02*
Y623386D01*
G01Y629764D02*
Y628386D01*
G01X737579Y627894D02*
Y630256D01*
G01Y622894D02*
Y625256D01*
G01Y617894D02*
Y620256D01*
G01Y612894D02*
Y615256D01*
G01Y607894D02*
Y610256D01*
G01Y602894D02*
Y605256D01*
G01Y597894D02*
Y600256D01*
G01Y592894D02*
Y595256D01*
G01Y587894D02*
Y590256D01*
G01Y582894D02*
Y585256D01*
G01Y577894D02*
Y580256D01*
G01Y572894D02*
Y575256D01*
G01X736594D02*
Y572894D01*
G01Y580256D02*
Y577894D01*
G01Y585256D02*
Y582894D01*
G01Y590256D02*
Y587894D01*
G01Y595256D02*
Y592894D01*
G01Y600256D02*
Y597894D01*
G01Y605256D02*
Y602894D01*
G01Y610256D02*
Y607894D01*
G01Y615256D02*
Y612894D01*
G01Y620256D02*
Y617894D01*
G01Y625256D02*
Y622894D01*
G01Y630256D02*
Y627894D01*
G01X736024Y649154D02*
Y655256D01*
G01X735827Y644980D02*
Y636437D01*
G01X733268Y641476D02*
Y639783D01*
G01X730906Y641476D02*
X728595Y645706D01*
G01X733268Y639783D02*
X734571Y637815D01*
G01X726378Y634075D02*
X727559Y632894D01*
G01X721260Y638917D02*
X724606Y635571D01*
G01X730906Y639783D02*
Y641476D01*
G01X728346Y636437D02*
Y644980D01*
G01X728150Y649154D02*
Y655256D01*
G01X721260Y654665D02*
Y638917D01*
G01X737579Y599734D02*
Y599737D01*
G01Y594734D02*
Y594737D01*
G01X692126Y713386D02*
G03X693307I591J0D01*
G01Y707087D02*
G03X692126I-590J0D01*
G01X690157D02*
G03X688976I-590J0D01*
G01Y713386D02*
G03X690157I590J0D01*
G01X692126D02*
G03X693307I591J0D01*
G01Y707087D02*
G03X692126I-590J0D01*
G01X690157D02*
G03X688976I-590J0D01*
G01Y713386D02*
G03X690157I590J0D01*
G01X688976D02*
X688189D01*
G01X688976D02*
X688189D01*
G01X692126D02*
X690157D01*
G01X694094D02*
X693307D01*
G01X692126D02*
X690157D01*
G01X694094D02*
X693307D01*
G01X694094Y712402D02*
X688189D01*
G01Y712205D02*
X694094D01*
G01X688189Y708268D02*
X694094D01*
G01Y708071D02*
X688189D01*
G01X693307Y707087D02*
X694094D01*
G01X690157D02*
X692126D01*
G01X693307D02*
X694094D01*
G01X690157D02*
X692126D01*
G01X688189D02*
X688976D01*
G01X688189D02*
X688976D01*
G01X694094D02*
Y713386D01*
G01Y707087D02*
Y713386D01*
G01X688189Y707087D02*
Y713386D01*
G01D02*
Y707087D01*
G01X730339Y816680D02*
G03X764149I16905J-13531D01*
G01X757225Y829811D02*
G03X764149Y816680I37663J11469D01*
G01X757225Y829811D02*
G03X737264I-9981J-3039D01*
G01X730339Y816680D02*
G03X737264Y829811I-30737J24602D01*
G01X757224D02*
G03X737264I-9980J-3040D01*
G01X730339Y816680D02*
G03X764150I16905J-13531D01*
G01X757224Y829811D02*
G03X764150Y816680I37662J11473D01*
G01X730339D02*
G03X737264Y829811I-30737J24602D01*
G01X728150Y930650D02*
G03X728740Y930059I590J-1D01*
G01X735433D02*
G03X736024Y930650I0J591D01*
G01X733268Y931831D02*
G03Y933799I0J984D01*
G01X730906D02*
G03Y931831I0J-984D01*
G01X733189Y945020D02*
G03I-1102J0D01*
G01X734646Y939744D02*
G03X735827Y940925I0J1181D01*
G01X728346D02*
G03X729528Y939744I1181J0D01*
G01X733661Y945020D02*
G03I-1574J0D01*
G01X721260Y931240D02*
G03X723228Y929272I1968J0D01*
G01X740945D02*
G03X742913Y931240I0J1968D01*
G01X734252Y951831D02*
X726378D01*
G01X739567Y950335D02*
X724606D01*
G01X735827Y949469D02*
X738976D01*
G01X728346D02*
X724606D01*
G01Y948091D02*
X738976D01*
G01X733268Y946122D02*
X730906D01*
G01X733268Y944429D02*
X730906D01*
G01X734646Y939744D02*
X729528D01*
G01X742913Y939705D02*
X721260D01*
G01X736024Y936752D02*
X728150D01*
G01Y935177D02*
X736024D01*
G01X733268Y933799D02*
X730906D01*
G01Y931831D02*
X733268D01*
G01X735433Y930059D02*
X728740D01*
G01X740945Y929272D02*
X723228D01*
G01X739567Y950335D02*
X742913Y946988D01*
G01X733071Y953012D02*
X734252Y951831D01*
G01X733268Y944429D02*
X735578Y940200D01*
G01X730906Y946122D02*
X729602Y948091D01*
G01X742913Y931240D02*
Y946988D01*
G01X739567Y1088327D02*
Y950335D01*
G01X738976Y1090571D02*
Y948091D01*
G01X736024Y936752D02*
Y930650D01*
G01X735827Y949469D02*
Y940925D01*
G01X734252Y988287D02*
Y951831D01*
G01X733268Y946122D02*
Y944429D01*
G01X727559Y953012D02*
X726378Y951831D01*
G01X724606Y950335D02*
X721260Y946988D01*
G01X734571Y948091D02*
X733268Y946122D01*
G01X728595Y940200D02*
X730906Y944429D01*
G01D02*
Y946122D01*
G01X728346Y940925D02*
Y949469D01*
G01X728150Y936752D02*
Y930650D01*
G01X726378Y951831D02*
Y1086831D01*
G01X724606Y987126D02*
Y948091D01*
G01X721260Y946988D02*
Y931240D01*
G01X724154Y1009337D02*
Y1009344D01*
G01X724153Y1009332D02*
X724154Y1009337D01*
G01X724152Y1009331D02*
X724153Y1009332D01*
G01X724154Y1006187D02*
Y1006194D01*
G01X724153Y1006183D02*
X724154Y1006187D01*
G01X724152Y1006181D02*
X724153Y1006183D01*
G01X724154Y1003038D02*
Y1003045D01*
G01X724153Y1003033D02*
X724154Y1003038D01*
G01X724152Y1003031D02*
X724153Y1003033D01*
G01X724154Y999888D02*
Y999895D01*
G01X724153Y999883D02*
X724154Y999888D01*
G01X724152Y999882D02*
X724153Y999883D01*
G01X723169Y998774D02*
Y998766D01*
G01X723168Y998778D02*
X723169Y998774D01*
G01X723167Y998775D02*
X723168Y998778D01*
G01X723169Y992474D02*
Y992467D01*
G01X723168Y992479D02*
X723169Y992474D01*
G01X723167Y992477D02*
X723168Y992479D01*
G01X724114Y1009375D02*
Y1009381D01*
G01X724113Y1009371D02*
X724114Y1009375D01*
G01X724113Y1009370D02*
Y1009371D01*
G01X724114Y1006226D02*
Y1006231D01*
G01X724113Y1006222D02*
X724114Y1006226D01*
G01X724113Y1006220D02*
Y1006222D01*
G01X724114Y1003076D02*
Y1003082D01*
G01X724113Y1003072D02*
X724114Y1003076D01*
G01X724113Y1003071D02*
Y1003072D01*
G01X724114Y999926D02*
Y999932D01*
G01X724113Y999922D02*
X724114Y999926D01*
G01X724113Y999921D02*
Y999922D01*
G01X724114Y996777D02*
Y996783D01*
G01X724113Y996773D02*
X724114Y996777D01*
G01X724113Y996772D02*
Y996773D01*
G01X724114Y993627D02*
Y993633D01*
G01X724113Y993623D02*
X724114Y993627D01*
G01X724113Y993622D02*
Y993623D01*
G01X724114Y990478D02*
Y990483D01*
G01X724113Y990474D02*
X724114Y990478D01*
G01X724113Y990472D02*
Y990474D01*
G01X737579Y1046134D02*
Y1046125D01*
G01X737580Y1046140D02*
X737579Y1046134D01*
G01X737581Y1046142D02*
X737580Y1046140D01*
G01X737579Y1041134D02*
Y1041125D01*
G01X737580Y1041140D02*
X737579Y1041134D01*
G01X737581Y1041142D02*
X737580Y1041140D01*
G01X737579Y1036134D02*
Y1036125D01*
G01X737580Y1036140D02*
X737579Y1036134D01*
G01X737581Y1036142D02*
X737580Y1036140D01*
G01X737579Y1031134D02*
Y1031125D01*
G01X737580Y1031140D02*
X737579Y1031134D01*
G01X737581Y1031142D02*
X737580Y1031140D01*
G01X737579Y1026134D02*
Y1026125D01*
G01X737580Y1026140D02*
X737579Y1026134D01*
G01X737581Y1026142D02*
X737580Y1026140D01*
G01X737579Y1021134D02*
Y1021125D01*
G01X737580Y1021140D02*
X737579Y1021134D01*
G01X737581Y1021142D02*
X737580Y1021140D01*
G01X737579Y1016134D02*
Y1016125D01*
G01X737580Y1016140D02*
X737579Y1016134D01*
G01X737581Y1016142D02*
X737580Y1016140D01*
G01X737579Y1011134D02*
Y1011125D01*
G01X737580Y1011140D02*
X737579Y1011134D01*
G01X737581Y1011142D02*
X737580Y1011140D01*
G01X737579Y986134D02*
Y986125D01*
G01X737580Y986140D02*
X737579Y986134D01*
G01X737581Y986142D02*
X737580Y986140D01*
G01X723169Y1009337D02*
Y1009344D01*
G01X723168Y1009332D02*
X723169Y1009337D01*
G01X723167Y1009331D02*
X723168Y1009332D01*
G01X723169Y1006187D02*
Y1006194D01*
G01X723168Y1006183D02*
X723169Y1006187D01*
G01X723167Y1006181D02*
X723168Y1006183D01*
G01X723169Y1003037D02*
Y1003045D01*
G01X723168Y1003033D02*
X723169Y1003037D01*
G01X723167Y1003031D02*
X723168Y1003033D01*
G01X723169Y999888D02*
Y999895D01*
G01X723168Y999883D02*
X723169Y999888D01*
G01X723167Y999882D02*
X723168Y999883D01*
G01X723169Y996738D02*
Y996746D01*
G01X723168Y996734D02*
X723169Y996738D01*
G01X723167Y996732D02*
X723168Y996734D01*
G01X723169Y993589D02*
Y993596D01*
G01X723168Y993584D02*
X723169Y993589D01*
G01X723167Y993583D02*
X723168Y993584D01*
G01X723169Y990439D02*
Y990446D01*
G01X723168Y990435D02*
X723169Y990439D01*
G01X723167Y990433D02*
X723168Y990435D01*
G01X724151Y1008202D02*
X724154Y1008215D01*
G01X724144Y1008191D02*
X724151Y1008202D01*
G01X724134Y1008183D02*
X724144Y1008191D01*
G01X724151Y1001903D02*
X724154Y1001915D01*
G01X724144Y1001892D02*
X724151Y1001903D01*
G01X724134Y1001884D02*
X724144Y1001892D01*
G01X724151Y998754D02*
X724154Y998766D01*
G01X724144Y998742D02*
X724151Y998754D01*
G01X724134Y998734D02*
X724144Y998742D01*
G01X724151Y995604D02*
X724154Y995616D01*
G01X724144Y995593D02*
X724151Y995604D01*
G01X724134Y995585D02*
X724144Y995593D01*
G01X724151Y992454D02*
X724154Y992467D01*
G01X724144Y992443D02*
X724151Y992454D01*
G01X724134Y992435D02*
X724144Y992443D01*
G01X724151Y989305D02*
X724154Y989317D01*
G01X724144Y989293D02*
X724151Y989305D01*
G01X724134Y989285D02*
X724144Y989293D01*
G01X723208Y1009375D02*
Y1009381D01*
G01Y1009371D02*
Y1009375D01*
G01X723206Y1009370D02*
X723208Y1009371D01*
G01Y1006225D02*
Y1006231D01*
G01Y1006222D02*
Y1006225D01*
G01X723206Y1006220D02*
X723208Y1006222D01*
G01Y1003076D02*
Y1003082D01*
G01Y1003072D02*
Y1003076D01*
G01X723206Y1003071D02*
X723208Y1003072D01*
G01Y999926D02*
Y999932D01*
G01Y999922D02*
Y999926D01*
G01X723206Y999921D02*
X723208Y999922D01*
G01Y996776D02*
Y996783D01*
G01Y996773D02*
Y996776D01*
G01X723206Y996772D02*
X723208Y996773D01*
G01Y993627D02*
Y993633D01*
G01Y993623D02*
Y993627D01*
G01X723206Y993622D02*
X723208Y993623D01*
G01Y990477D02*
Y990483D01*
G01Y990474D02*
Y990477D01*
G01X723206Y990472D02*
X723208Y990474D01*
G01X723170Y1009350D02*
X723169Y1009344D01*
G01X723172Y1009357D02*
X723170Y1009350D01*
G01X723174Y1009363D02*
X723172Y1009357D01*
G01X723178Y1009368D02*
X723174Y1009363D01*
G01X723183Y1009372D02*
X723178Y1009368D01*
G01X723189Y1009376D02*
X723183Y1009372D01*
G01X723170Y1006201D02*
X723169Y1006194D01*
G01X723172Y1006207D02*
X723170Y1006201D01*
G01X723174Y1006213D02*
X723172Y1006207D01*
G01X723178Y1006218D02*
X723174Y1006213D01*
G01X723183Y1006223D02*
X723178Y1006218D01*
G01X723189Y1006226D02*
X723183Y1006223D01*
G01X723170Y1003051D02*
X723169Y1003045D01*
G01X723172Y1003057D02*
X723170Y1003051D01*
G01X723174Y1003063D02*
X723172Y1003057D01*
G01X723178Y1003069D02*
X723174Y1003063D01*
G01X723183Y1003073D02*
X723178Y1003069D01*
G01X723189Y1003077D02*
X723183Y1003073D01*
G01X723170Y999902D02*
X723169Y999895D01*
G01X723172Y999908D02*
X723170Y999902D01*
G01X723174Y999914D02*
X723172Y999908D01*
G01X723178Y999919D02*
X723174Y999914D01*
G01X723183Y999924D02*
X723178Y999919D01*
G01X723189Y999927D02*
X723183Y999924D01*
G01X723170Y996752D02*
X723169Y996746D01*
G01X723172Y996758D02*
X723170Y996752D01*
G01X723174Y996764D02*
X723172Y996758D01*
G01X723178Y996769D02*
X723174Y996764D01*
G01X723183Y996774D02*
X723178Y996769D01*
G01X723189Y996778D02*
X723183Y996774D01*
G01X723170Y993602D02*
X723169Y993596D01*
G01X723172Y993609D02*
X723170Y993602D01*
G01X723174Y993615D02*
X723172Y993609D01*
G01X723178Y993620D02*
X723174Y993615D01*
G01X723183Y993624D02*
X723178Y993620D01*
G01X723189Y993628D02*
X723183Y993624D01*
G01X723170Y990453D02*
X723169Y990446D01*
G01X723172Y990459D02*
X723170Y990453D01*
G01X723174Y990465D02*
X723172Y990459D01*
G01X723178Y990470D02*
X723174Y990465D01*
G01X723183Y990475D02*
X723178Y990470D01*
G01X723189Y990478D02*
X723183Y990475D01*
G01X724125Y1008191D02*
X724113Y1008189D01*
G01X724135Y1008196D02*
X724125Y1008191D01*
G01Y1005041D02*
X724113Y1005039D01*
G01X724135Y1005046D02*
X724125Y1005041D01*
G01Y1001892D02*
X724113Y1001890D01*
G01X724135Y1001896D02*
X724125Y1001892D01*
G01Y998742D02*
X724113Y998740D01*
G01X724135Y998747D02*
X724125Y998742D01*
G01X723169Y1001923D02*
Y1001916D01*
G01X723168Y1001928D02*
X723169Y1001923D01*
G01Y1001918D02*
X723168Y1001928D01*
G01X723209Y1009554D02*
Y1009567D01*
G01X723206Y1009541D02*
X723209Y1009554D01*
G01X723206Y1009528D02*
Y1009541D01*
G01X723209Y1006405D02*
Y1006417D01*
G01X723206Y1006392D02*
X723209Y1006405D01*
G01X723206Y1006378D02*
Y1006392D01*
G01X723209Y1003255D02*
Y1003268D01*
G01X723206Y1003242D02*
X723209Y1003255D01*
G01X723206Y1003228D02*
Y1003242D01*
G01X723209Y1000106D02*
Y1000118D01*
G01X723206Y1000093D02*
X723209Y1000106D01*
G01X723206Y1000079D02*
Y1000093D01*
G01X723209Y996956D02*
Y996969D01*
G01X723206Y996943D02*
X723209Y996956D01*
G01X723206Y996929D02*
Y996943D01*
G01X723209Y993806D02*
Y993819D01*
G01X723206Y993793D02*
X723209Y993806D01*
G01X723206Y993780D02*
Y993793D01*
G01X723209Y990657D02*
Y990669D01*
G01X723206Y990644D02*
X723209Y990657D01*
G01X723206Y990630D02*
Y990644D01*
G01X736595Y1046140D02*
X736596Y1046142D01*
G01X736594Y1046134D02*
X736595Y1046140D01*
G01X736594Y1046126D02*
Y1046134D01*
G01X736595Y1041140D02*
X736596Y1041142D01*
G01X736594Y1041134D02*
X736595Y1041140D01*
G01X736594Y1041126D02*
Y1041134D01*
G01X736595Y1036140D02*
X736596Y1036142D01*
G01X736594Y1036134D02*
X736595Y1036140D01*
G01X736594Y1036126D02*
Y1036134D01*
G01X723169Y1008222D02*
Y1008215D01*
G01X723168Y1008227D02*
X723169Y1008222D01*
G01X723168Y1008219D02*
Y1008227D01*
G01X723206Y1008017D02*
X723205Y1008031D01*
G01X723209Y1008005D02*
X723206Y1008017D01*
G01X723209Y1007992D02*
Y1008005D01*
G01X723206Y1004868D02*
X723205Y1004881D01*
G01X723209Y1004855D02*
X723206Y1004868D01*
G01X723209Y1004843D02*
Y1004855D01*
G01X723206Y1001718D02*
X723205Y1001732D01*
G01X723209Y1001706D02*
X723206Y1001718D01*
G01X723209Y1001693D02*
Y1001706D01*
G01X723206Y998569D02*
X723205Y998582D01*
G01X723209Y998556D02*
X723206Y998569D01*
G01X723209Y998543D02*
Y998556D01*
G01X723206Y995419D02*
X723205Y995433D01*
G01X723209Y995406D02*
X723206Y995419D01*
G01X723209Y995394D02*
Y995406D01*
G01X723206Y992269D02*
X723205Y992283D01*
G01X723209Y992257D02*
X723206Y992269D01*
G01X723209Y992244D02*
Y992257D01*
G01X723206Y989120D02*
X723205Y989133D01*
G01X723209Y989107D02*
X723206Y989120D01*
G01X723209Y989094D02*
Y989107D01*
G01X724117Y1009541D02*
X724118Y1009528D01*
G01X724113Y1009554D02*
X724117Y1009541D01*
G01X724114Y1009567D02*
X724113Y1009554D01*
G01X724117Y1006392D02*
X724118Y1006378D01*
G01X724113Y1006405D02*
X724117Y1006392D01*
G01X724114Y1006417D02*
X724113Y1006405D01*
G01X724117Y1003242D02*
X724118Y1003228D01*
G01X724113Y1003255D02*
X724117Y1003242D01*
G01X724114Y1003268D02*
X724113Y1003255D01*
G01X724117Y1000093D02*
X724118Y1000079D01*
G01X724113Y1000106D02*
X724117Y1000093D01*
G01X724114Y1000118D02*
X724113Y1000106D01*
G01X724117Y996943D02*
X724118Y996929D01*
G01X724113Y996956D02*
X724117Y996943D01*
G01X724114Y996969D02*
X724113Y996956D01*
G01X724117Y993793D02*
X724118Y993780D01*
G01X724113Y993806D02*
X724117Y993793D01*
G01X724114Y993819D02*
X724113Y993806D01*
G01X724117Y990644D02*
X724118Y990630D01*
G01X724113Y990657D02*
X724117Y990644D01*
G01X724114Y990669D02*
X724113Y990657D01*
G01X723169Y995624D02*
Y995617D01*
G01X723168Y995628D02*
X723169Y995624D01*
G01X723168Y995621D02*
Y995628D01*
G01X723169Y1005073D02*
Y1005065D01*
G01X723168Y1005077D02*
X723169Y1005073D01*
G01X723168Y1005070D02*
Y1005077D01*
G01X724113Y1008005D02*
X724114Y1007992D01*
G01X724116Y1008017D02*
X724113Y1008005D01*
G01X724117Y1008031D02*
X724116Y1008017D01*
G01X724113Y1004855D02*
X724114Y1004843D01*
G01X724116Y1004868D02*
X724113Y1004855D01*
G01X724117Y1004881D02*
X724116Y1004868D01*
G01X724113Y1001706D02*
X724114Y1001693D01*
G01X724116Y1001718D02*
X724113Y1001706D01*
G01X724117Y1001732D02*
X724116Y1001718D01*
G01X724113Y998556D02*
X724114Y998543D01*
G01X724116Y998569D02*
X724113Y998556D01*
G01X724117Y998582D02*
X724116Y998569D01*
G01X724113Y995406D02*
X724114Y995394D01*
G01X724116Y995419D02*
X724113Y995406D01*
G01X724117Y995433D02*
X724116Y995419D01*
G01X724113Y992257D02*
X724114Y992244D01*
G01X724116Y992269D02*
X724113Y992257D01*
G01X724117Y992283D02*
X724116Y992269D01*
G01X724113Y989107D02*
X724114Y989094D01*
G01X724116Y989120D02*
X724113Y989107D01*
G01X724117Y989133D02*
X724116Y989120D01*
G01X723169Y989325D02*
Y989317D01*
G01X723168Y989329D02*
X723169Y989325D01*
G01X723168Y989323D02*
Y989329D01*
G01X723182Y1009361D02*
X723206Y1009370D01*
G01X723171Y1009347D02*
X723182Y1009361D01*
G01X723169Y1009340D02*
X723171Y1009347D01*
G01X723182Y1006212D02*
X723206Y1006220D01*
G01X723171Y1006197D02*
X723182Y1006212D01*
G01X723169Y1006191D02*
X723171Y1006197D01*
G01X723182Y1003062D02*
X723206Y1003071D01*
G01X723171Y1003048D02*
X723182Y1003062D01*
G01X723169Y1003041D02*
X723171Y1003048D01*
G01X723182Y999913D02*
X723206Y999921D01*
G01X723171Y999898D02*
X723182Y999913D01*
G01X723169Y999891D02*
X723171Y999898D01*
G01X723182Y996763D02*
X723206Y996772D01*
G01X723171Y996748D02*
X723182Y996763D01*
G01X723169Y996742D02*
X723171Y996748D01*
G01X723182Y993613D02*
X723206Y993622D01*
G01X723171Y993599D02*
X723182Y993613D01*
G01X723169Y993592D02*
X723171Y993599D01*
G01X723182Y990464D02*
X723206Y990472D01*
G01X723171Y990449D02*
X723182Y990464D01*
G01X723169Y990443D02*
X723171Y990449D01*
G01X724154Y996739D02*
Y996746D01*
G01X724153Y996734D02*
X724154Y996739D01*
G01X724152Y996732D02*
X724153Y996734D01*
G01X724154Y993589D02*
Y993596D01*
G01X724153Y993584D02*
X724154Y993589D01*
G01X724152Y993583D02*
X724153Y993584D01*
G01X724154Y990439D02*
Y990446D01*
G01X724153Y990435D02*
X724154Y990439D01*
G01X724152Y990433D02*
X724153Y990435D01*
G01X737579Y981134D02*
Y981125D01*
G01X737580Y981140D02*
X737579Y981134D01*
G01X737581Y981142D02*
X737580Y981140D01*
G01X737579Y976134D02*
Y976125D01*
G01X737580Y976140D02*
X737579Y976134D01*
G01X737581Y976142D02*
X737580Y976140D01*
G01X737579Y971134D02*
Y971125D01*
G01X737580Y971140D02*
X737579Y971134D01*
G01X737581Y971142D02*
X737580Y971140D01*
G01X737579Y966134D02*
Y966125D01*
G01X737580Y966140D02*
X737579Y966134D01*
G01X737581Y966142D02*
X737580Y966140D01*
G01X737579Y961134D02*
Y961125D01*
G01X737580Y961140D02*
X737579Y961134D01*
G01X737581Y961142D02*
X737580Y961140D01*
G01X737579Y956134D02*
Y956125D01*
G01X737580Y956140D02*
X737579Y956134D01*
G01X737581Y956142D02*
X737580Y956140D01*
G01X724125Y995593D02*
X724113Y995591D01*
G01X724135Y995597D02*
X724125Y995593D01*
G01Y992443D02*
X724113Y992441D01*
G01X724135Y992448D02*
X724125Y992443D01*
G01Y989293D02*
X724113Y989291D01*
G01X724135Y989298D02*
X724125Y989293D01*
G01X737546Y957618D02*
X737550Y957717D01*
G01X737540Y957546D02*
X737546Y957618D01*
G01X737542Y957520D02*
X737540Y957546D01*
G01X737546Y962618D02*
X737550Y962717D01*
G01X737540Y962546D02*
X737546Y962618D01*
G01X737542Y962520D02*
X737540Y962546D01*
G01X737546Y967618D02*
X737550Y967717D01*
G01X737540Y967546D02*
X737546Y967618D01*
G01X737542Y967520D02*
X737540Y967546D01*
G01X737546Y972618D02*
X737550Y972717D01*
G01X737540Y972546D02*
X737546Y972618D01*
G01X737542Y972520D02*
X737540Y972546D01*
G01X737546Y977618D02*
X737550Y977717D01*
G01X737540Y977546D02*
X737546Y977618D01*
G01X737542Y977520D02*
X737540Y977546D01*
G01X737546Y982618D02*
X737550Y982717D01*
G01X737540Y982546D02*
X737546Y982618D01*
G01X737542Y982520D02*
X737540Y982546D01*
G01X737546Y987618D02*
X737550Y987717D01*
G01X737540Y987546D02*
X737546Y987618D01*
G01X737542Y987520D02*
X737540Y987546D01*
G01X737546Y1012618D02*
X737550Y1012717D01*
G01X737540Y1012546D02*
X737546Y1012618D01*
G01X737542Y1012520D02*
X737540Y1012546D01*
G01X737546Y1017618D02*
X737550Y1017717D01*
G01X737540Y1017546D02*
X737546Y1017618D01*
G01X737542Y1017520D02*
X737540Y1017546D01*
G01X737546Y1022618D02*
X737550Y1022717D01*
G01X737540Y1022546D02*
X737546Y1022618D01*
G01X737542Y1022520D02*
X737540Y1022546D01*
G01X737546Y1027618D02*
X737550Y1027717D01*
G01X737540Y1027546D02*
X737546Y1027618D01*
G01X737542Y1027520D02*
X737540Y1027546D01*
G01X737546Y1032618D02*
X737550Y1032717D01*
G01X737540Y1032546D02*
X737546Y1032618D01*
G01X737542Y1032520D02*
X737540Y1032546D01*
G01X737546Y1037618D02*
X737550Y1037717D01*
G01X737540Y1037546D02*
X737546Y1037618D01*
G01X737542Y1037520D02*
X737540Y1037546D01*
G01X737546Y1042618D02*
X737550Y1042717D01*
G01X737540Y1042546D02*
X737546Y1042618D01*
G01X737542Y1042520D02*
X737540Y1042546D01*
G01X736595Y1031140D02*
X736596Y1031142D01*
G01X736594Y1031134D02*
X736595Y1031140D01*
G01X736594Y1031126D02*
Y1031134D01*
G01X736595Y1026140D02*
X736596Y1026142D01*
G01X736594Y1026134D02*
X736595Y1026140D01*
G01X736594Y1026126D02*
Y1026134D01*
G01X736595Y1021140D02*
X736596Y1021142D01*
G01X736594Y1021134D02*
X736595Y1021140D01*
G01X736594Y1021126D02*
Y1021134D01*
G01X736595Y1016140D02*
X736596Y1016142D01*
G01X736594Y1016134D02*
X736595Y1016140D01*
G01X736594Y1016126D02*
Y1016134D01*
G01X736595Y1011140D02*
X736596Y1011142D01*
G01X736594Y1011134D02*
X736595Y1011140D01*
G01X736594Y1011126D02*
Y1011134D01*
G01X736595Y986140D02*
X736596Y986142D01*
G01X736594Y986134D02*
X736595Y986140D01*
G01X736594Y986126D02*
Y986134D01*
G01X736595Y981140D02*
X736596Y981142D01*
G01X736594Y981134D02*
X736595Y981140D01*
G01X736594Y981126D02*
Y981134D01*
G01X736595Y976140D02*
X736596Y976142D01*
G01X736594Y976134D02*
X736595Y976140D01*
G01X736594Y976126D02*
Y976134D01*
G01X736595Y971140D02*
X736596Y971142D01*
G01X736594Y971134D02*
X736595Y971140D01*
G01X736594Y971126D02*
Y971134D01*
G01X736595Y966140D02*
X736596Y966142D01*
G01X736594Y966134D02*
X736595Y966140D01*
G01X736594Y966126D02*
Y966134D01*
G01X736595Y961140D02*
X736596Y961142D01*
G01X736594Y961134D02*
X736595Y961140D01*
G01X736594Y961126D02*
Y961134D01*
G01X736595Y956140D02*
X736596Y956142D01*
G01X736594Y956134D02*
X736595Y956140D01*
G01X736594Y956126D02*
Y956134D01*
G01X737561Y957515D02*
X737542Y957520D01*
G01X737576Y957500D02*
X737561Y957515D01*
G01X737581Y957480D02*
X737576Y957500D01*
G01X737561Y962515D02*
X737542Y962520D01*
G01X737576Y962500D02*
X737561Y962515D01*
G01X737581Y962480D02*
X737576Y962500D01*
G01X737561Y967515D02*
X737542Y967520D01*
G01X737576Y967500D02*
X737561Y967515D01*
G01X737581Y967480D02*
X737576Y967500D01*
G01X737561Y972515D02*
X737542Y972520D01*
G01X737576Y972500D02*
X737561Y972515D01*
G01X737581Y972480D02*
X737576Y972500D01*
G01X737561Y977515D02*
X737542Y977520D01*
G01X737576Y977500D02*
X737561Y977515D01*
G01X737581Y977480D02*
X737576Y977500D01*
G01X737561Y982515D02*
X737542Y982520D01*
G01X737576Y982500D02*
X737561Y982515D01*
G01X737581Y982480D02*
X737576Y982500D01*
G01X737561Y987515D02*
X737542Y987520D01*
G01X737576Y987500D02*
X737561Y987515D01*
G01X737581Y987480D02*
X737576Y987500D01*
G01X737561Y1012515D02*
X737542Y1012520D01*
G01X737576Y1012500D02*
X737561Y1012515D01*
G01X737581Y1012480D02*
X737576Y1012500D01*
G01X737561Y1017515D02*
X737542Y1017520D01*
G01X737576Y1017500D02*
X737561Y1017515D01*
G01X737581Y1017480D02*
X737576Y1017500D01*
G01X737561Y1022515D02*
X737542Y1022520D01*
G01X737576Y1022500D02*
X737561Y1022515D01*
G01X737581Y1022480D02*
X737576Y1022500D01*
G01X737561Y1027515D02*
X737542Y1027520D01*
G01X737576Y1027500D02*
X737561Y1027515D01*
G01X737581Y1027480D02*
X737576Y1027500D01*
G01X724146Y996754D02*
X724139Y996762D01*
G01X724151Y996743D02*
X724146Y996754D01*
G01X724152Y996732D02*
X724151Y996743D01*
G01X724146Y990454D02*
X724139Y990463D01*
G01X724151Y990444D02*
X724146Y990454D01*
G01X724152Y990433D02*
X724151Y990444D01*
G01X724146Y993604D02*
X724139Y993612D01*
G01X724151Y993594D02*
X724146Y993604D01*
G01X724152Y993583D02*
X724151Y993594D01*
G01X724146Y999903D02*
X724139Y999911D01*
G01X724151Y999893D02*
X724146Y999903D01*
G01X724152Y999882D02*
X724151Y999893D01*
G01X724146Y1003053D02*
X724139Y1003061D01*
G01X724151Y1003043D02*
X724146Y1003053D01*
G01X724152Y1003031D02*
X724151Y1003043D01*
G01X724146Y1006202D02*
X724139Y1006211D01*
G01X724151Y1006192D02*
X724146Y1006202D01*
G01X724152Y1006181D02*
X724151Y1006192D01*
G01X724146Y1009352D02*
X724139Y1009360D01*
G01X724151Y1009342D02*
X724146Y1009352D01*
G01X724152Y1009331D02*
X724151Y1009342D01*
G01X723192Y992443D02*
X723206Y992441D01*
G01X723181Y992450D02*
X723192Y992443D01*
G01X723169Y992469D02*
X723181Y992450D01*
G01X723192Y1001892D02*
X723206Y1001890D01*
G01X723180Y1001900D02*
X723192Y1001892D01*
G01X723169Y1001918D02*
X723180Y1001900D01*
G01X723192Y995593D02*
X723206Y995591D01*
G01X723180Y995601D02*
X723192Y995593D01*
G01X723168Y995621D02*
X723180Y995601D01*
G01X723192Y1005042D02*
X723206Y1005039D01*
G01X723180Y1005050D02*
X723192Y1005042D01*
G01X723168Y1005070D02*
X723180Y1005050D01*
G01X724154Y989325D02*
Y989317D01*
G01X724153Y989329D02*
X724154Y989325D01*
G01X724152Y989331D02*
X724153Y989329D01*
G01X724154Y992474D02*
Y992467D01*
G01X724153Y992479D02*
X724154Y992474D01*
G01X724152Y992480D02*
X724153Y992479D01*
G01X724154Y995624D02*
Y995616D01*
G01X724153Y995628D02*
X724154Y995624D01*
G01X724152Y995630D02*
X724153Y995628D01*
G01X724154Y998774D02*
Y998766D01*
G01X724153Y998778D02*
X724154Y998774D01*
G01X724152Y998780D02*
X724153Y998778D01*
G01X724154Y1001923D02*
Y1001915D01*
G01X724153Y1001928D02*
X724154Y1001923D01*
G01X724152Y1001929D02*
X724153Y1001928D01*
G01X724154Y1005073D02*
Y1005065D01*
G01X724153Y1005077D02*
X724154Y1005073D01*
G01X724152Y1005079D02*
X724153Y1005077D01*
G01X724154Y1008222D02*
Y1008215D01*
G01X724153Y1008227D02*
X724154Y1008222D01*
G01X724152Y1008228D02*
X724153Y1008227D01*
G01X723192Y1008192D02*
X723206Y1008189D01*
G01X723179Y1008200D02*
X723192Y1008192D01*
G01X723168Y1008220D02*
X723179Y1008200D01*
G01X723191Y989294D02*
X723206Y989291D01*
G01X723178Y989303D02*
X723191Y989294D01*
G01X723168Y989323D02*
X723178Y989303D01*
G01X724153Y990453D02*
X724154Y990446D01*
G01X724151Y990459D02*
X724153Y990453D01*
G01X724148Y990465D02*
X724151Y990459D01*
G01X724153Y993603D02*
X724154Y993596D01*
G01X724151Y993609D02*
X724153Y993603D01*
G01X724148Y993615D02*
X724151Y993609D01*
G01X724153Y996752D02*
X724154Y996746D01*
G01X724151Y996759D02*
X724153Y996752D01*
G01X724148Y996765D02*
X724151Y996759D01*
G01X724153Y999902D02*
X724154Y999895D01*
G01X724151Y999908D02*
X724153Y999902D01*
G01X724148Y999914D02*
X724151Y999908D01*
G01X724153Y1003052D02*
X724154Y1003045D01*
G01X724151Y1003058D02*
X724153Y1003052D01*
G01X724148Y1003064D02*
X724151Y1003058D01*
G01X724153Y1006201D02*
X724154Y1006194D01*
G01X724151Y1006207D02*
X724153Y1006201D01*
G01X724148Y1006213D02*
X724151Y1006207D01*
G01X724153Y1009351D02*
X724154Y1009344D01*
G01X724151Y1009357D02*
X724153Y1009351D01*
G01X724148Y1009363D02*
X724151Y1009357D01*
G01X724115Y989286D02*
Y989280D01*
G01X724113Y989290D02*
X724115Y989286D01*
G01X724113Y989291D02*
Y989290D01*
G01X724115Y992436D02*
Y992430D01*
G01X724113Y992439D02*
X724115Y992436D01*
G01X724113Y992441D02*
Y992439D01*
G01X724115Y995585D02*
Y995579D01*
G01X724113Y995589D02*
X724115Y995585D01*
G01X724113Y995591D02*
Y995589D01*
G01X724115Y998735D02*
Y998729D01*
G01X724113Y998739D02*
X724115Y998735D01*
G01X724113Y998740D02*
Y998739D01*
G01X724115Y1001885D02*
Y1001878D01*
G01X724113Y1001888D02*
X724115Y1001885D01*
G01X724113Y1001890D02*
Y1001888D01*
G01X724115Y1008184D02*
Y1008178D01*
G01X724113Y1008187D02*
X724115Y1008184D01*
G01X724113Y1008189D02*
Y1008187D01*
G01X736594Y957527D02*
Y957536D01*
G01X736595Y957521D02*
X736594Y957527D01*
G01X736596Y957520D02*
X736595Y957521D01*
G01X736594Y962527D02*
Y962536D01*
G01X736595Y962521D02*
X736594Y962527D01*
G01X736596Y962520D02*
X736595Y962521D01*
G01X736594Y967527D02*
Y967536D01*
G01X736595Y967521D02*
X736594Y967527D01*
G01X736596Y967520D02*
X736595Y967521D01*
G01X736594Y972527D02*
Y972536D01*
G01X736595Y972521D02*
X736594Y972527D01*
G01X736596Y972520D02*
X736595Y972521D01*
G01X736594Y977527D02*
Y977536D01*
G01X736595Y977521D02*
X736594Y977527D01*
G01X736596Y977520D02*
X736595Y977521D01*
G01X736594Y982527D02*
Y982536D01*
G01X736595Y982521D02*
X736594Y982527D01*
G01X736596Y982520D02*
X736595Y982521D01*
G01X736594Y987527D02*
Y987536D01*
G01X736595Y987521D02*
X736594Y987527D01*
G01X736596Y987520D02*
X736595Y987521D01*
G01X736594Y1012527D02*
Y1012536D01*
G01X736595Y1012521D02*
X736594Y1012527D01*
G01X736596Y1012520D02*
X736595Y1012521D01*
G01X736594Y1017527D02*
Y1017536D01*
G01X736595Y1017521D02*
X736594Y1017527D01*
G01X736596Y1017520D02*
X736595Y1017521D01*
G01X736594Y1022527D02*
Y1022536D01*
G01X736595Y1022521D02*
X736594Y1022527D01*
G01X736596Y1022520D02*
X736595Y1022521D01*
G01X736594Y1027527D02*
Y1027536D01*
G01X736595Y1027521D02*
X736594Y1027527D01*
G01X736596Y1027520D02*
X736595Y1027521D01*
G01X736594Y1032527D02*
Y1032536D01*
G01X736595Y1032521D02*
X736594Y1032527D01*
G01X736596Y1032520D02*
X736595Y1032521D01*
G01X736594Y1037527D02*
Y1037536D01*
G01X736595Y1037521D02*
X736594Y1037527D01*
G01X736596Y1037520D02*
X736595Y1037521D01*
G01X736594Y1042527D02*
Y1042536D01*
G01X736595Y1042521D02*
X736594Y1042527D01*
G01X736596Y1042520D02*
X736595Y1042521D01*
G01X736596Y1047520D02*
X736595Y1047521D01*
G01X737571Y957663D02*
X737579Y957637D01*
G01X737561Y957690D02*
X737571Y957663D01*
G01X737550Y957717D02*
X737561Y957690D01*
G01X737571Y962663D02*
X737579Y962637D01*
G01X737561Y962690D02*
X737571Y962663D01*
G01X737550Y962717D02*
X737561Y962690D01*
G01X737571Y967663D02*
X737579Y967637D01*
G01X737561Y967690D02*
X737571Y967663D01*
G01X737550Y967717D02*
X737561Y967690D01*
G01X737571Y972663D02*
X737579Y972637D01*
G01X737561Y972690D02*
X737571Y972663D01*
G01X737550Y972717D02*
X737561Y972690D01*
G01X737571Y977663D02*
X737579Y977637D01*
G01X737561Y977690D02*
X737571Y977663D01*
G01X737550Y977717D02*
X737561Y977690D01*
G01X737571Y982663D02*
X737579Y982637D01*
G01X737561Y982690D02*
X737571Y982663D01*
G01X737550Y982717D02*
X737561Y982690D01*
G01X737571Y987663D02*
X737579Y987637D01*
G01X737561Y987690D02*
X737571Y987663D01*
G01X737550Y987717D02*
X737561Y987690D01*
G01X737571Y1012663D02*
X737579Y1012637D01*
G01X737561Y1012690D02*
X737571Y1012663D01*
G01X737550Y1012717D02*
X737561Y1012690D01*
G01X737571Y1017663D02*
X737579Y1017637D01*
G01X737561Y1017690D02*
X737571Y1017663D01*
G01X737550Y1017717D02*
X737561Y1017690D01*
G01X737571Y1022663D02*
X737579Y1022637D01*
G01X737561Y1022690D02*
X737571Y1022663D01*
G01X737550Y1022717D02*
X737561Y1022690D01*
G01X737571Y1027663D02*
X737579Y1027637D01*
G01X737561Y1027690D02*
X737571Y1027663D01*
G01X737550Y1027717D02*
X737561Y1027690D01*
G01X737571Y1032663D02*
X737579Y1032637D01*
G01X737561Y1032690D02*
X737571Y1032663D01*
G01X737550Y1032717D02*
X737561Y1032690D01*
G01X737571Y1037663D02*
X737579Y1037637D01*
G01X737561Y1037690D02*
X737571Y1037663D01*
G01X737550Y1037717D02*
X737561Y1037690D01*
G01X737571Y1042663D02*
X737579Y1042637D01*
G01X737561Y1042690D02*
X737571Y1042663D01*
G01X737550Y1042717D02*
X737561Y1042690D01*
G01X723187Y998745D02*
X723206Y998740D01*
G01X723174Y998757D02*
X723187Y998745D01*
G01X723167Y998775D02*
X723174Y998757D01*
G01X737561Y1032515D02*
X737542Y1032520D01*
G01X737576Y1032500D02*
X737561Y1032515D01*
G01X737581Y1032480D02*
X737576Y1032500D01*
G01X737561Y1037515D02*
X737542Y1037520D01*
G01X737576Y1037500D02*
X737561Y1037515D01*
G01X737581Y1037480D02*
X737576Y1037500D01*
G01X737561Y1042515D02*
X737542Y1042520D01*
G01X737576Y1042500D02*
X737561Y1042515D01*
G01X737581Y1042480D02*
X737576Y1042500D01*
G01X737561Y1047515D02*
X737542Y1047520D01*
G01X737576Y1047500D02*
X737561Y1047515D01*
G01X737581Y1047480D02*
X737576Y1047500D01*
G01X723208Y989286D02*
X723209Y989280D01*
G01X723207Y989290D02*
X723208Y989286D01*
G01X723206Y989291D02*
X723207Y989290D01*
G01X737579Y957487D02*
Y957494D01*
G01X737580Y957482D02*
X737579Y957487D01*
G01X737581Y957480D02*
X737580Y957482D01*
G01X737579Y962487D02*
Y962494D01*
G01X737580Y962482D02*
X737579Y962487D01*
G01X737581Y962480D02*
X737580Y962482D01*
G01X737579Y967487D02*
Y967494D01*
G01X737580Y967482D02*
X737579Y967487D01*
G01X737581Y967480D02*
X737580Y967482D01*
G01X737579Y972487D02*
Y972494D01*
G01X737580Y972482D02*
X737579Y972487D01*
G01X737581Y972480D02*
X737580Y972482D01*
G01X737579Y977487D02*
Y977494D01*
G01X737580Y977482D02*
X737579Y977487D01*
G01X737581Y977480D02*
X737580Y977482D01*
G01X737579Y982487D02*
Y982494D01*
G01X737580Y982482D02*
X737579Y982487D01*
G01X737581Y982480D02*
X737580Y982482D01*
G01X737579Y987487D02*
Y987494D01*
G01X737580Y987482D02*
X737579Y987487D01*
G01X737581Y987480D02*
X737580Y987482D01*
G01X737579Y1012487D02*
Y1012494D01*
G01X737580Y1012482D02*
X737579Y1012487D01*
G01X737581Y1012480D02*
X737580Y1012482D01*
G01X737579Y1017487D02*
Y1017494D01*
G01X737580Y1017482D02*
X737579Y1017487D01*
G01X737581Y1017480D02*
X737580Y1017482D01*
G01X737579Y1022487D02*
Y1022494D01*
G01X737580Y1022482D02*
X737579Y1022487D01*
G01X737581Y1022480D02*
X737580Y1022482D01*
G01X737579Y1027487D02*
Y1027494D01*
G01X737580Y1027482D02*
X737579Y1027487D01*
G01X737581Y1027480D02*
X737580Y1027482D01*
G01X737579Y1032487D02*
Y1032494D01*
G01X737580Y1032482D02*
X737579Y1032487D01*
G01X737581Y1032480D02*
X737580Y1032482D01*
G01X737579Y1037487D02*
Y1037494D01*
G01X737580Y1037482D02*
X737579Y1037487D01*
G01X737581Y1037480D02*
X737580Y1037482D01*
G01X737579Y1042487D02*
Y1042494D01*
G01X737580Y1042482D02*
X737579Y1042487D01*
G01X737581Y1042480D02*
X737580Y1042482D01*
G01Y1047482D02*
X737579Y1047487D01*
G01X737581Y1047480D02*
X737580Y1047482D01*
G01X724122Y996770D02*
X724113Y996772D01*
G01X724131Y996767D02*
X724122Y996770D01*
G01X724139Y996762D02*
X724131Y996767D01*
G01X724122Y990471D02*
X724113Y990472D01*
G01X724131Y990468D02*
X724122Y990471D01*
G01X724139Y990463D02*
X724131Y990468D01*
G01X724122Y993621D02*
X724113Y993622D01*
G01X724131Y993618D02*
X724122Y993621D01*
G01X724139Y993612D02*
X724131Y993618D01*
G01X724122Y999920D02*
X724113Y999921D01*
G01X724131Y999917D02*
X724122Y999920D01*
G01X724139Y999911D02*
X724131Y999917D01*
G01X724122Y1003070D02*
X724113Y1003071D01*
G01X724131Y1003067D02*
X724122Y1003070D01*
G01X724139Y1003061D02*
X724131Y1003067D01*
G01X724122Y1006219D02*
X724113Y1006220D01*
G01X724131Y1006216D02*
X724122Y1006219D01*
G01X724139Y1006211D02*
X724131Y1006216D01*
G01X724122Y1009369D02*
X724113Y1009370D01*
G01X724131Y1009366D02*
X724122Y1009369D01*
G01X724139Y1009360D02*
X724131Y1009366D01*
G01X723208Y992436D02*
X723209Y992430D01*
G01X723207Y992440D02*
X723208Y992436D01*
G01X723206Y992441D02*
X723207Y992440D01*
G01X723208Y995585D02*
X723209Y995579D01*
G01X723207Y995589D02*
X723208Y995585D01*
G01X723206Y995591D02*
X723207Y995589D01*
G01X723208Y998735D02*
X723209Y998729D01*
G01X723207Y998739D02*
X723208Y998735D01*
G01X723206Y998740D02*
X723207Y998739D01*
G01X723208Y1001885D02*
X723209Y1001878D01*
G01X723207Y1001889D02*
X723208Y1001885D01*
G01X723206Y1001890D02*
X723207Y1001889D01*
G01X723208Y1005034D02*
X723209Y1005028D01*
G01X723207Y1005038D02*
X723208Y1005034D01*
G01X723206Y1005039D02*
X723207Y1005038D01*
G01X723208Y1008184D02*
X723209Y1008178D01*
G01X723207Y1008188D02*
X723208Y1008184D01*
G01X723206Y1008189D02*
X723207Y1008188D01*
G01X723169Y992470D02*
Y992467D01*
G01X723171Y992464D02*
X723169Y992470D01*
G01X723183Y992449D02*
X723171Y992464D01*
G01X723207Y992441D02*
X723183Y992449D01*
G01X723169Y995620D02*
Y995616D01*
G01X723171Y995614D02*
X723169Y995620D01*
G01X723182Y995599D02*
X723171Y995614D01*
G01X723207Y995591D02*
X723182Y995599D01*
G01X723169Y1001919D02*
Y1001915D01*
G01X723171Y1001913D02*
X723169Y1001919D01*
G01X723182Y1001898D02*
X723171Y1001913D01*
G01X723207Y1001890D02*
X723182Y1001898D01*
G01X723169Y1005069D02*
Y1005065D01*
G01X723171Y1005063D02*
X723169Y1005069D01*
G01X723182Y1005048D02*
X723171Y1005063D01*
G01X723207Y1005039D02*
X723182Y1005048D01*
G01X723169Y989321D02*
Y989317D01*
G01X723171Y989315D02*
X723169Y989321D01*
G01X723182Y989300D02*
X723171Y989315D01*
G01X723207Y989291D02*
X723182Y989300D01*
G01X723169Y1008219D02*
Y1008215D01*
G01X723171Y1008213D02*
X723169Y1008219D01*
G01X723182Y1008197D02*
X723171Y1008213D01*
G01X723207Y1008189D02*
X723182Y1008197D01*
G01X737566Y957511D02*
X737577Y957496D01*
G01X737542Y957520D02*
X737566Y957511D01*
G01Y962511D02*
X737577Y962496D01*
G01X737542Y962520D02*
X737566Y962511D01*
G01Y967511D02*
X737577Y967496D01*
G01X737542Y967520D02*
X737566Y967511D01*
G01Y972511D02*
X737577Y972496D01*
G01X737542Y972520D02*
X737566Y972511D01*
G01Y977511D02*
X737577Y977496D01*
G01X737542Y977520D02*
X737566Y977511D01*
G01Y982511D02*
X737577Y982496D01*
G01X737542Y982520D02*
X737566Y982511D01*
G01Y987511D02*
X737577Y987496D01*
G01X737542Y987520D02*
X737566Y987511D01*
G01Y1012511D02*
X737577Y1012496D01*
G01X737542Y1012520D02*
X737566Y1012511D01*
G01Y1017511D02*
X737577Y1017496D01*
G01X737542Y1017520D02*
X737566Y1017511D01*
G01Y1022511D02*
X737577Y1022496D01*
G01X737542Y1022520D02*
X737566Y1022511D01*
G01Y1027511D02*
X737577Y1027496D01*
G01X737542Y1027520D02*
X737566Y1027511D01*
G01X723169Y998770D02*
Y998766D01*
G01X723171Y998764D02*
X723169Y998770D01*
G01X723181Y998750D02*
X723171Y998764D01*
G01X723204Y998740D02*
X723181Y998750D01*
G01X724131Y989283D02*
X724134Y989285D01*
G01X724128Y989282D02*
X724131Y989283D01*
G01X724125Y989281D02*
X724128Y989282D01*
G01X724121Y989281D02*
X724125D01*
G01X724118Y989280D02*
X724121Y989281D01*
G01X724114Y989280D02*
X724118D01*
G01X723192Y990480D02*
X723189Y990478D01*
G01X723195Y990481D02*
X723192Y990480D01*
G01X723198Y990482D02*
X723195Y990481D01*
G01X723202Y990483D02*
X723198Y990482D01*
G01X723205Y990483D02*
X723202D01*
G01X723209D02*
X723205D01*
G01X724131Y992433D02*
X724134Y992435D01*
G01X724128Y992432D02*
X724131Y992433D01*
G01X724125Y992431D02*
X724128Y992432D01*
G01X724121Y992430D02*
X724125Y992431D01*
G01X724118Y992430D02*
X724121D01*
G01X724114D02*
X724118D01*
G01X723192Y993630D02*
X723189Y993628D01*
G01X723195Y993631D02*
X723192Y993630D01*
G01X723198Y993632D02*
X723195Y993631D01*
G01X723202Y993633D02*
X723198Y993632D01*
G01X723205Y993633D02*
X723202D01*
G01X723209D02*
X723205D01*
G01X724131Y995583D02*
X724134Y995585D01*
G01X724128Y995581D02*
X724131Y995583D01*
G01X724125Y995581D02*
X724128D01*
G01X724121Y995580D02*
X724125Y995581D01*
G01X724118Y995580D02*
X724121D01*
G01X724114Y995579D02*
X724118Y995580D01*
G01X723192Y996779D02*
X723189Y996778D01*
G01X723195Y996780D02*
X723192Y996779D01*
G01X723198Y996781D02*
X723195Y996780D01*
G01X723202Y996782D02*
X723198Y996781D01*
G01X723205Y996783D02*
X723202Y996782D01*
G01X723209Y996783D02*
X723205D01*
G01X724131Y998732D02*
X724134Y998734D01*
G01X724128Y998731D02*
X724131Y998732D01*
G01X724125Y998730D02*
X724128Y998731D01*
G01X724121Y998730D02*
X724125D01*
G01X724118Y998729D02*
X724121Y998730D01*
G01X724114Y998729D02*
X724118D01*
G01X723192Y999929D02*
X723189Y999927D01*
G01X723195Y999930D02*
X723192Y999929D01*
G01X723198Y999931D02*
X723195Y999930D01*
G01X723202Y999932D02*
X723198Y999931D01*
G01X723205Y999932D02*
X723202D01*
G01X723209D02*
X723205D01*
G01X724131Y1001882D02*
X724134Y1001884D01*
G01X724128Y1001881D02*
X724131Y1001882D01*
G01X724125Y1001880D02*
X724128Y1001881D01*
G01X724121Y1001879D02*
X724125Y1001880D01*
G01X724118Y1001879D02*
X724121D01*
G01X724114Y1001878D02*
X724118Y1001879D01*
G01X723192Y1003078D02*
X723189Y1003077D01*
G01X723195Y1003080D02*
X723192Y1003078D01*
G01X723198Y1003081D02*
X723195Y1003080D01*
G01X723202Y1003081D02*
X723198D01*
G01X723205Y1003082D02*
X723202Y1003081D01*
G01X723209Y1003082D02*
X723205D01*
G01X723192Y1006228D02*
X723189Y1006226D01*
G01X723195Y1006229D02*
X723192Y1006228D01*
G01X723198Y1006230D02*
X723195Y1006229D01*
G01X723202Y1006231D02*
X723198Y1006230D01*
G01X723205Y1006231D02*
X723202D01*
G01X723209D02*
X723205D01*
G01X724131Y1008181D02*
X724134Y1008183D01*
G01X724128Y1008180D02*
X724131Y1008181D01*
G01X724125Y1008179D02*
X724128Y1008180D01*
G01X724121Y1008178D02*
X724125Y1008179D01*
G01X724118Y1008178D02*
X724121D01*
G01X724114D02*
X724118D01*
G01X723192Y1009378D02*
X723189Y1009376D01*
G01X723195Y1009379D02*
X723192Y1009378D01*
G01X723198Y1009380D02*
X723195Y1009379D01*
G01X723202Y1009381D02*
X723198Y1009380D01*
G01X723205Y1009381D02*
X723202D01*
G01X723209D02*
X723205D01*
G01X722422Y992480D02*
X721988D01*
G01X722796D02*
X722422D01*
G01Y998780D02*
X721988D01*
G01X722796D02*
X722422D01*
G01Y1001929D02*
X721988D01*
G01X722796D02*
X722422D01*
G01X724144Y990471D02*
X724148Y990465D01*
G01X724139Y990475D02*
X724144Y990471D01*
G01X724133Y990479D02*
X724139Y990475D01*
G01X724128Y990481D02*
X724133Y990479D01*
G01X724121Y990483D02*
X724128Y990481D01*
G01X724114Y990483D02*
X724121D01*
G01X724144Y993620D02*
X724148Y993615D01*
G01X724139Y993625D02*
X724144Y993620D01*
G01X724133Y993628D02*
X724139Y993625D01*
G01X724128Y993631D02*
X724133Y993628D01*
G01X724121Y993633D02*
X724128Y993631D01*
G01X724114Y993633D02*
X724121D01*
G01X724144Y996770D02*
X724148Y996765D01*
G01X724139Y996774D02*
X724144Y996770D01*
G01X724133Y996778D02*
X724139Y996774D01*
G01X724128Y996781D02*
X724133Y996778D01*
G01X724121Y996782D02*
X724128Y996781D01*
G01X724114Y996783D02*
X724121Y996782D01*
G01X724144Y999920D02*
X724148Y999914D01*
G01X724139Y999924D02*
X724144Y999920D01*
G01X724133Y999928D02*
X724139Y999924D01*
G01X724128Y999930D02*
X724133Y999928D01*
G01X724121Y999932D02*
X724128Y999930D01*
G01X724114Y999932D02*
X724121D01*
G01X724144Y1003069D02*
X724148Y1003064D01*
G01X724139Y1003074D02*
X724144Y1003069D01*
G01X724133Y1003077D02*
X724139Y1003074D01*
G01X724128Y1003080D02*
X724133Y1003077D01*
G01X724121Y1003081D02*
X724128Y1003080D01*
G01X724114Y1003082D02*
X724121Y1003081D01*
G01X724144Y1006219D02*
X724148Y1006213D01*
G01X724139Y1006223D02*
X724144Y1006219D01*
G01X724133Y1006227D02*
X724139Y1006223D01*
G01X724128Y1006230D02*
X724133Y1006227D01*
G01X724121Y1006231D02*
X724128Y1006230D01*
G01X724114Y1006231D02*
X724121D01*
G01X724144Y1009369D02*
X724148Y1009363D01*
G01X724139Y1009373D02*
X724144Y1009369D01*
G01X724133Y1009376D02*
X724139Y1009373D01*
G01X724128Y1009379D02*
X724133Y1009376D01*
G01X724121Y1009381D02*
X724128Y1009379D01*
G01X724114Y1009381D02*
X724121D01*
G01X723170Y989310D02*
X723169Y989317D01*
G01X723172Y989303D02*
X723170Y989310D01*
G01X723176Y989296D02*
X723172Y989303D01*
G01X723181Y989291D02*
X723176Y989296D01*
G01X723187Y989286D02*
X723181Y989291D01*
G01X723194Y989283D02*
X723187Y989286D01*
G01X723201Y989281D02*
X723194Y989283D01*
G01X723209Y989280D02*
X723201Y989281D01*
G01X723170Y992459D02*
X723169Y992467D01*
G01X723172Y992452D02*
X723170Y992459D01*
G01X723176Y992446D02*
X723172Y992452D01*
G01X723181Y992441D02*
X723176Y992446D01*
G01X723187Y992436D02*
X723181Y992441D01*
G01X723194Y992432D02*
X723187Y992436D01*
G01X723201Y992430D02*
X723194Y992432D01*
G01X723209Y992430D02*
X723201D01*
G01X723170Y995609D02*
X723169Y995616D01*
G01X723172Y995602D02*
X723170Y995609D01*
G01X723176Y995596D02*
X723172Y995602D01*
G01X723181Y995590D02*
X723176Y995596D01*
G01X723187Y995585D02*
X723181Y995590D01*
G01X723194Y995582D02*
X723187Y995585D01*
G01X723201Y995580D02*
X723194Y995582D01*
G01X723209Y995579D02*
X723201Y995580D01*
G01X723170Y998759D02*
X723169Y998766D01*
G01X723172Y998752D02*
X723170Y998759D01*
G01X723176Y998745D02*
X723172Y998752D01*
G01X723181Y998740D02*
X723176Y998745D01*
G01X723187Y998735D02*
X723181Y998740D01*
G01X723194Y998731D02*
X723187Y998735D01*
G01X723201Y998730D02*
X723194Y998731D01*
G01X723209Y998729D02*
X723201Y998730D01*
G01X723170Y1001908D02*
X723169Y1001915D01*
G01X723172Y1001901D02*
X723170Y1001908D01*
G01X723176Y1001895D02*
X723172Y1001901D01*
G01X723181Y1001889D02*
X723176Y1001895D01*
G01X723187Y1001885D02*
X723181Y1001889D01*
G01X723194Y1001881D02*
X723187Y1001885D01*
G01X723201Y1001879D02*
X723194Y1001881D01*
G01X723209Y1001878D02*
X723201Y1001879D01*
G01X723170Y1005058D02*
X723169Y1005065D01*
G01X723172Y1005051D02*
X723170Y1005058D01*
G01X723176Y1005044D02*
X723172Y1005051D01*
G01X723181Y1005039D02*
X723176Y1005044D01*
G01X723187Y1005034D02*
X723181Y1005039D01*
G01X723194Y1005031D02*
X723187Y1005034D01*
G01X723201Y1005029D02*
X723194Y1005031D01*
G01X723209Y1005028D02*
X723201Y1005029D01*
G01X723170Y1008207D02*
X723169Y1008215D01*
G01X723172Y1008200D02*
X723170Y1008207D01*
G01X723176Y1008194D02*
X723172Y1008200D01*
G01X723181Y1008189D02*
X723176Y1008194D01*
G01X723187Y1008184D02*
X723181Y1008189D01*
G01X723194Y1008180D02*
X723187Y1008184D01*
G01X723201Y1008178D02*
X723194Y1008180D01*
G01X723209Y1008178D02*
X723201D01*
G01X724123Y990471D02*
X724133Y990467D01*
G01X724113Y990472D02*
X724123Y990471D01*
G01Y993620D02*
X724133Y993617D01*
G01X724113Y993622D02*
X724123Y993620D01*
G01Y996770D02*
X724133Y996766D01*
G01X724113Y996772D02*
X724123Y996770D01*
G01Y999920D02*
X724133Y999916D01*
G01X724113Y999921D02*
X724123Y999920D01*
G01Y1003069D02*
X724133Y1003065D01*
G01X724113Y1003071D02*
X724123Y1003069D01*
G01Y1006219D02*
X724133Y1006215D01*
G01X724113Y1006220D02*
X724123Y1006219D01*
G01Y1009369D02*
X724133Y1009365D01*
G01X724113Y1009370D02*
X724123Y1009369D01*
G01X737566Y1032511D02*
X737577Y1032496D01*
G01X737542Y1032520D02*
X737566Y1032511D01*
G01Y1037511D02*
X737577Y1037496D01*
G01X737542Y1037520D02*
X737566Y1037511D01*
G01Y1042511D02*
X737577Y1042496D01*
G01X737542Y1042520D02*
X737566Y1042511D01*
G01Y1047511D02*
X737577Y1047496D01*
G01X737542Y1047520D02*
X737566Y1047511D01*
G01X723172Y990453D02*
X723167Y990433D01*
G01X723187Y990467D02*
X723172Y990453D01*
G01X723206Y990472D02*
X723187Y990467D01*
G01X723172Y993602D02*
X723167Y993583D01*
G01X723187Y993617D02*
X723172Y993602D01*
G01X723206Y993622D02*
X723187Y993617D01*
G01X723172Y996752D02*
X723167Y996732D01*
G01X723187Y996766D02*
X723172Y996752D01*
G01X723206Y996772D02*
X723187Y996766D01*
G01X723172Y999902D02*
X723167Y999882D01*
G01X723187Y999916D02*
X723172Y999902D01*
G01X723206Y999921D02*
X723187Y999916D01*
G01X723172Y1003051D02*
X723167Y1003031D01*
G01X723187Y1003065D02*
X723172Y1003051D01*
G01X723206Y1003071D02*
X723187Y1003065D01*
G01X723172Y1006201D02*
X723167Y1006181D01*
G01X723187Y1006215D02*
X723172Y1006201D01*
G01X723206Y1006220D02*
X723187Y1006215D01*
G01X723172Y1009350D02*
X723167Y1009331D01*
G01X723187Y1009365D02*
X723172Y1009350D01*
G01X723206Y1009370D02*
X723187Y1009365D01*
G01X724147Y989311D02*
X724152Y989331D01*
G01X724132Y989296D02*
X724147Y989311D01*
G01X724113Y989291D02*
X724132Y989296D01*
G01X724147Y992461D02*
X724152Y992480D01*
G01X724132Y992446D02*
X724147Y992461D01*
G01X724113Y992441D02*
X724132Y992446D01*
G01X724147Y995610D02*
X724152Y995630D01*
G01X724132Y995596D02*
X724147Y995610D01*
G01X724113Y995591D02*
X724132Y995596D01*
G01X724147Y998760D02*
X724152Y998780D01*
G01X724132Y998745D02*
X724147Y998760D01*
G01X724113Y998740D02*
X724132Y998745D01*
G01X724147Y1001909D02*
X724152Y1001929D01*
G01X724132Y1001895D02*
X724147Y1001909D01*
G01X724113Y1001890D02*
X724132Y1001895D01*
G01X724147Y1005059D02*
X724152Y1005079D01*
G01X724132Y1005044D02*
X724147Y1005059D01*
G01X724113Y1005039D02*
X724132Y1005044D01*
G01X724147Y1008209D02*
X724152Y1008228D01*
G01X724132Y1008194D02*
X724147Y1008209D01*
G01X724113Y1008189D02*
X724132Y1008194D01*
G01X724153Y1005058D02*
X724154Y1005065D01*
G01X724150Y1005051D02*
X724153Y1005058D01*
G01X724147Y1005044D02*
X724150Y1005051D01*
G01X724142Y1005039D02*
X724147Y1005044D01*
G01X724136Y1005034D02*
X724142Y1005039D01*
G01X724129Y1005031D02*
X724136Y1005034D01*
G01X724122Y1005029D02*
X724129Y1005031D01*
G01X724114Y1005028D02*
X724122Y1005029D01*
G01X741929Y1046142D02*
X736596D01*
G01X736594Y1045650D02*
X737579D01*
G01Y1043012D02*
X736594D01*
G01X736596Y1042520D02*
X741929D01*
G01Y1042480D02*
X737581D01*
G01X741929Y1041142D02*
X736596D01*
G01X736594Y1040650D02*
X737579D01*
G01Y1038012D02*
X736594D01*
G01X736596Y1037520D02*
X741929D01*
G01Y1037480D02*
X737581D01*
G01X741929Y1036142D02*
X736596D01*
G01X736594Y1035650D02*
X737579D01*
G01Y1033012D02*
X736594D01*
G01X736596Y1032520D02*
X741929D01*
G01Y1032480D02*
X737581D01*
G01X741929Y1031142D02*
X736596D01*
G01X736594Y1030650D02*
X737579D01*
G01Y1028012D02*
X736594D01*
G01X736596Y1027520D02*
X741929D01*
G01Y1027480D02*
X737581D01*
G01X741929Y1026142D02*
X736596D01*
G01X736594Y1025650D02*
X737579D01*
G01Y1023012D02*
X736594D01*
G01X736596Y1022520D02*
X741929D01*
G01Y1022480D02*
X737581D01*
G01X741929Y1021142D02*
X736596D01*
G01X737579Y1045946D02*
X736594Y1045945D01*
G01Y1042715D02*
X737550Y1042717D01*
G01X737579Y1040946D02*
X736594Y1040945D01*
G01Y1037715D02*
X737550Y1037717D01*
G01X737579Y1035946D02*
X736594Y1035945D01*
G01Y1032715D02*
X737550Y1032717D01*
G01X737579Y1030946D02*
X736594Y1030945D01*
G01Y1027715D02*
X737550Y1027717D01*
G01X737579Y1025946D02*
X736594Y1025945D01*
G01Y1022715D02*
X737550Y1022717D01*
G01X737579Y1020946D02*
X736594Y1020945D01*
G01X723056Y1008228D02*
X723168Y1008220D01*
G01X723167Y998775D02*
X723056Y998780D01*
G01X723167Y992477D02*
X723056Y992480D01*
G01X723167Y1001926D02*
X723056Y1001929D01*
G01X736594Y1020650D02*
X737579D01*
G01Y1018012D02*
X736594D01*
G01X736596Y1017520D02*
X741929D01*
G01Y1017480D02*
X737581D01*
G01X741929Y1016142D02*
X736596D01*
G01X736594Y1015650D02*
X737579D01*
G01Y1013012D02*
X736594D01*
G01X736596Y1012520D02*
X741929D01*
G01Y1012480D02*
X737581D01*
G01X724606Y1011535D02*
X721260D01*
G01X741929Y1011142D02*
X736596D01*
G01X736594Y1010650D02*
X737579D01*
G01X734252Y1010374D02*
X738189D01*
G01X724114Y1009567D02*
X723209D01*
G01X724154Y1009528D02*
X723169D01*
G01X724113Y1009370D02*
X718228D01*
G01Y1009331D02*
X724152D01*
G01X733071Y1009193D02*
X737008D01*
G01X724152Y1008228D02*
X718228D01*
G01X724113Y1008189D02*
X718228D01*
G01X723169Y1008031D02*
X724154D01*
G01X723209Y1007992D02*
X724114D01*
G01Y1006417D02*
X723209D01*
G01X724154Y1006378D02*
X723169D01*
G01X724113Y1006220D02*
X718228D01*
G01Y1006181D02*
X724152D01*
G01Y1005079D02*
X718228D01*
G01X724113Y1005039D02*
X718228D01*
G01X723169Y1004882D02*
X724154D01*
G01X723209Y1004843D02*
X724114D01*
G01Y1003268D02*
X723209D01*
G01X724154Y1003228D02*
X723169D01*
G01X724113Y1003071D02*
X718228D01*
G01Y1003031D02*
X724152D01*
G01Y1001929D02*
X718228D01*
G01X724113Y1001890D02*
X718228D01*
G01X723169Y1001732D02*
X724154D01*
G01X723209Y1001693D02*
X724114D01*
G01Y1000118D02*
X723209D01*
G01X724154Y1000079D02*
X723169D01*
G01X724113Y999921D02*
X718228D01*
G01Y999882D02*
X724152D01*
G01Y998780D02*
X718228D01*
G01X724113Y998740D02*
X718228D01*
G01X723169Y998583D02*
X724154D01*
G01X723209Y998543D02*
X724114D01*
G01Y996969D02*
X723209D01*
G01X724154Y996929D02*
X723169D01*
G01X724113Y996772D02*
X718228D01*
G01Y996732D02*
X724152D01*
G01Y995630D02*
X718228D01*
G01X724113Y995591D02*
X718228D01*
G01X723169Y995433D02*
X724154D01*
G01X723209Y995394D02*
X724114D01*
G01Y993819D02*
X723209D01*
G01X724154Y993780D02*
X723169D01*
G01X724113Y993622D02*
X718228D01*
G01Y993583D02*
X724152D01*
G01Y992480D02*
X718228D01*
G01X724113Y992441D02*
X718228D01*
G01X723169Y992283D02*
X724154D01*
G01X723209Y992244D02*
X724114D01*
G01Y990669D02*
X723209D01*
G01X724154Y990630D02*
X723169D01*
G01X724113Y990472D02*
X718228D01*
G01Y990433D02*
X724152D01*
G01X737008Y989469D02*
X733071D01*
G01X724152Y989331D02*
X718228D01*
G01X724113Y989291D02*
X718228D01*
G01X723169Y989134D02*
X724154D01*
G01X723209Y989094D02*
X724114D01*
G01X738189Y988287D02*
X734252D01*
G01X737579Y988012D02*
X736594D01*
G01X736596Y987520D02*
X741929D01*
G01Y987480D02*
X737581D01*
G01X724606Y987126D02*
X721260D01*
G01X741929Y986142D02*
X736596D01*
G01X736594Y985650D02*
X737579D01*
G01Y983012D02*
X736594D01*
G01X736596Y982520D02*
X741929D01*
G01Y982480D02*
X737581D01*
G01X741929Y981142D02*
X736596D01*
G01X736594Y980650D02*
X737579D01*
G01Y978012D02*
X736594D01*
G01X736596Y977520D02*
X741929D01*
G01Y977480D02*
X737581D01*
G01X741929Y976142D02*
X736596D01*
G01X736594Y975650D02*
X737579D01*
G01Y973012D02*
X736594D01*
G01X736596Y972520D02*
X741929D01*
G01Y972480D02*
X737581D01*
G01X741929Y971142D02*
X736596D01*
G01X736594Y970650D02*
X737579D01*
G01Y968012D02*
X736594D01*
G01X736596Y967520D02*
X741929D01*
G01Y967480D02*
X737581D01*
G01X741929Y966142D02*
X736596D01*
G01X736594Y965650D02*
X737579D01*
G01Y963012D02*
X736594D01*
G01X736596Y962520D02*
X741929D01*
G01Y962480D02*
X737581D01*
G01X741929Y961142D02*
X736596D01*
G01X736594Y960650D02*
X737579D01*
G01Y958012D02*
X736594D01*
G01X736596Y957520D02*
X741929D01*
G01Y957480D02*
X737581D01*
G01X741929Y956142D02*
X736596D01*
G01X736594Y955650D02*
X737579D01*
G01X733071Y953012D02*
X727559D01*
G01X736594Y1017715D02*
X737550Y1017717D01*
G01X737579Y1015946D02*
X736594Y1015945D01*
G01Y1012715D02*
X737550Y1012717D01*
G01X737579Y1010946D02*
X736594Y1010945D01*
G01Y987715D02*
X737550Y987717D01*
G01X737579Y985946D02*
X736594Y985945D01*
G01Y982715D02*
X737550Y982717D01*
G01X737579Y980946D02*
X736594Y980945D01*
G01Y977715D02*
X737550Y977717D01*
G01X737579Y975946D02*
X736594Y975945D01*
G01Y972715D02*
X737550Y972717D01*
G01X737579Y970946D02*
X736594Y970945D01*
G01Y967715D02*
X737550Y967717D01*
G01X737579Y965946D02*
X736594Y965945D01*
G01Y962715D02*
X737550Y962717D01*
G01X737579Y960946D02*
X736594Y960945D01*
G01Y957715D02*
X737550Y957717D01*
G01X737579Y955946D02*
X736594Y955945D01*
G01X737008Y989469D02*
X738189Y988287D01*
G01X733071Y989469D02*
X734252Y988287D01*
G01X724113Y1005039D02*
X724116Y1005028D01*
G01X737579Y957494D02*
Y957502D01*
G01Y962494D02*
Y962502D01*
G01Y967494D02*
Y967502D01*
G01Y972494D02*
Y972502D01*
G01Y977494D02*
Y977502D01*
G01Y982494D02*
Y982502D01*
G01Y987494D02*
Y987502D01*
G01X741929Y1046142D02*
Y1047520D01*
G01Y1041142D02*
Y1042520D01*
G01Y1036142D02*
Y1037520D01*
G01Y1031142D02*
Y1032520D01*
G01Y1026142D02*
Y1027520D01*
G01Y1021142D02*
Y1022520D01*
G01Y1016142D02*
Y1017520D01*
G01Y1011142D02*
Y1012520D01*
G01Y986142D02*
Y987520D01*
G01Y981142D02*
Y982520D01*
G01Y976142D02*
Y977520D01*
G01Y971142D02*
Y972520D01*
G01Y966142D02*
Y967520D01*
G01Y961142D02*
Y962520D01*
G01Y956142D02*
Y957520D01*
G01X738760D02*
Y956142D01*
G01Y962520D02*
Y961142D01*
G01Y967520D02*
Y966142D01*
G01Y972520D02*
Y971142D01*
G01Y977520D02*
Y976142D01*
G01Y982520D02*
Y981142D01*
G01Y987520D02*
Y986142D01*
G01Y1012520D02*
Y1011142D01*
G01Y1017520D02*
Y1016142D01*
G01Y1022520D02*
Y1021142D01*
G01Y1027520D02*
Y1026142D01*
G01Y1032520D02*
Y1031142D01*
G01Y1037520D02*
Y1036142D01*
G01Y1042520D02*
Y1041142D01*
G01Y1047520D02*
Y1046142D01*
G01X738189Y1010374D02*
Y988287D01*
G01X737579Y1045650D02*
Y1048012D01*
G01Y1040650D02*
Y1043012D01*
G01Y1035650D02*
Y1038012D01*
G01Y1030650D02*
Y1033012D01*
G01Y1025650D02*
Y1028012D01*
G01Y1020650D02*
Y1023012D01*
G01Y1015650D02*
Y1018012D01*
G01Y1010650D02*
Y1013012D01*
G01Y985650D02*
Y988012D01*
G01Y980650D02*
Y983012D01*
G01Y975650D02*
Y978012D01*
G01Y970650D02*
Y973012D01*
G01Y965650D02*
Y968012D01*
G01Y960650D02*
Y963012D01*
G01Y955650D02*
Y958012D01*
G01Y962494D02*
Y962637D01*
G01Y967494D02*
Y967637D01*
G01Y972494D02*
Y972637D01*
G01Y977494D02*
Y977637D01*
G01Y982494D02*
Y982637D01*
G01Y987494D02*
Y987637D01*
G01Y1012494D02*
Y1012637D01*
G01Y1017494D02*
Y1017637D01*
G01Y1022494D02*
Y1022637D01*
G01Y1027494D02*
Y1027637D01*
G01Y1032494D02*
Y1032637D01*
G01Y1037494D02*
Y1037637D01*
G01Y1042494D02*
Y1042637D01*
G01X737008Y1009193D02*
Y989469D01*
G01X736594Y958012D02*
Y955650D01*
G01Y963012D02*
Y960650D01*
G01Y968012D02*
Y965650D01*
G01Y973012D02*
Y970650D01*
G01Y978012D02*
Y975650D01*
G01Y983012D02*
Y980650D01*
G01Y988012D02*
Y985650D01*
G01Y1013012D02*
Y1010650D01*
G01Y1018012D02*
Y1015650D01*
G01Y1023012D02*
Y1020650D01*
G01Y1028012D02*
Y1025650D01*
G01Y1033012D02*
Y1030650D01*
G01Y1038012D02*
Y1035650D01*
G01Y1043012D02*
Y1040650D01*
G01Y1048012D02*
Y1045650D01*
G01X734252Y1086831D02*
Y1010374D01*
G01X733071Y989469D02*
Y953012D01*
G01Y1085650D02*
Y1009193D01*
G01X724153Y990435D02*
X724154Y990446D01*
G01X724153Y993585D02*
X724154Y993596D01*
G01X724153Y996734D02*
X724154Y996746D01*
G01X724153Y999884D02*
X724154Y999895D01*
G01X724153Y1003033D02*
X724154Y1003045D01*
G01X724153Y1006183D02*
X724154Y1006194D01*
G01X724153Y1009333D02*
X724154Y1009344D01*
G01X737579Y1012494D02*
Y1012502D01*
G01Y1017494D02*
Y1017502D01*
G01Y1022494D02*
Y1022502D01*
G01Y1027494D02*
Y1027502D01*
G01Y1032494D02*
Y1032502D01*
G01Y1037494D02*
Y1037502D01*
G01Y1042494D02*
Y1042502D01*
G01X727559Y953012D02*
Y1085650D01*
G01X724606Y1090571D02*
Y1011535D01*
G01X724154Y1008031D02*
Y1009528D01*
G01Y1004881D02*
Y1006378D01*
G01Y1001732D02*
Y1003228D01*
G01Y998582D02*
Y1000079D01*
G01Y995433D02*
Y996929D01*
G01Y992283D02*
Y993780D01*
G01Y989133D02*
Y990630D01*
G01X724114Y989280D02*
Y989133D01*
G01Y990630D02*
Y990483D01*
G01Y995579D02*
Y995432D01*
G01Y992430D02*
Y992283D01*
G01Y993780D02*
Y993633D01*
G01Y998729D02*
Y998582D01*
G01Y1000079D02*
Y999932D01*
G01Y996930D02*
Y996783D01*
G01Y1001878D02*
Y1001731D01*
G01Y1003229D02*
Y1003082D01*
G01Y1008178D02*
Y1008031D01*
G01Y1009528D02*
Y1009381D01*
G01Y1005028D02*
Y1004881D01*
G01Y1006378D02*
Y1006231D01*
G01X723209Y1008031D02*
Y1008178D01*
G01Y1009381D02*
Y1009528D01*
G01Y1004881D02*
Y1005028D01*
G01Y1006231D02*
Y1006378D01*
G01Y1001731D02*
Y1001878D01*
G01Y1003082D02*
Y1003229D01*
G01Y998582D02*
Y998729D01*
G01Y999932D02*
Y1000079D01*
G01Y996783D02*
Y996930D01*
G01Y995432D02*
Y995579D01*
G01Y992283D02*
Y992430D01*
G01Y993633D02*
Y993780D01*
G01Y989133D02*
Y989280D01*
G01Y990483D02*
Y990630D01*
G01X723169D02*
Y989134D01*
G01Y993780D02*
Y992283D01*
G01Y1000079D02*
Y998583D01*
G01Y996929D02*
Y995433D01*
G01Y1003228D02*
Y1001732D01*
G01Y1009528D02*
Y1008031D01*
G01Y1006378D02*
Y1004882D01*
G01X721988Y990472D02*
Y989291D01*
G01Y996772D02*
Y995591D01*
G01Y993622D02*
Y992441D01*
G01Y999921D02*
Y998740D01*
G01Y1003071D02*
Y1001890D01*
G01Y1009370D02*
Y1008189D01*
G01Y1006220D02*
Y1005039D01*
G01X721654Y1011535D02*
Y987126D01*
G01X721260D02*
Y1011535D01*
G01X718228Y1008189D02*
Y1009370D01*
G01Y1005039D02*
Y1006220D01*
G01Y1001890D02*
Y1003071D01*
G01Y998740D02*
Y999921D01*
G01Y995591D02*
Y996772D01*
G01Y992441D02*
Y993622D01*
G01Y989291D02*
Y990472D01*
G01X724154Y1008215D02*
X724153Y1008226D01*
G01X724154Y1005065D02*
X724153Y1005076D01*
G01X724154Y1001916D02*
X724153Y1001926D01*
G01X724154Y998766D02*
X724153Y998777D01*
G01X724154Y995617D02*
X724153Y995627D01*
G01X724154Y992467D02*
X724153Y992478D01*
G01X724154Y989317D02*
X724153Y989328D01*
G01X737008Y1009193D02*
X738189Y1010374D01*
G01X733071Y1009193D02*
X734252Y1010374D01*
G01X737579Y1081134D02*
Y1081125D01*
G01X737580Y1081140D02*
X737579Y1081134D01*
G01X737581Y1081142D02*
X737580Y1081140D01*
G01X737579Y1076134D02*
Y1076125D01*
G01X737580Y1076140D02*
X737579Y1076134D01*
G01X737581Y1076142D02*
X737580Y1076140D01*
G01X737579Y1071134D02*
Y1071125D01*
G01X737580Y1071140D02*
X737579Y1071134D01*
G01X737581Y1071142D02*
X737580Y1071140D01*
G01X737579Y1066134D02*
Y1066125D01*
G01X737580Y1066140D02*
X737579Y1066134D01*
G01X737581Y1066142D02*
X737580Y1066140D01*
G01X737579Y1061134D02*
Y1061125D01*
G01X737580Y1061140D02*
X737579Y1061134D01*
G01X737581Y1061142D02*
X737580Y1061140D01*
G01X737579Y1056134D02*
Y1056125D01*
G01X737580Y1056140D02*
X737579Y1056134D01*
G01X737581Y1056142D02*
X737580Y1056140D01*
G01X737579Y1051134D02*
Y1051125D01*
G01X737580Y1051140D02*
X737579Y1051134D01*
G01X737581Y1051142D02*
X737580Y1051140D01*
G01X736595Y1081140D02*
X736596Y1081142D01*
G01X736594Y1081134D02*
X736595Y1081140D01*
G01X736594Y1081126D02*
Y1081134D01*
G01X736595Y1076140D02*
X736596Y1076142D01*
G01X736594Y1076134D02*
X736595Y1076140D01*
G01X736594Y1076126D02*
Y1076134D01*
G01X736595Y1071140D02*
X736596Y1071142D01*
G01X736594Y1071134D02*
X736595Y1071140D01*
G01X736594Y1071126D02*
Y1071134D01*
G01X736595Y1066140D02*
X736596Y1066142D01*
G01X736594Y1066134D02*
X736595Y1066140D01*
G01X736594Y1066126D02*
Y1066134D01*
G01X736595Y1061140D02*
X736596Y1061142D01*
G01X736594Y1061134D02*
X736595Y1061140D01*
G01X736594Y1061126D02*
Y1061134D01*
G01X736595Y1056140D02*
X736596Y1056142D01*
G01X736594Y1056134D02*
X736595Y1056140D01*
G01X736594Y1056126D02*
Y1056134D01*
G01X736595Y1051140D02*
X736596Y1051142D01*
G01X736594Y1051134D02*
X736595Y1051140D01*
G01X736594Y1051126D02*
Y1051134D01*
G01X737546Y1047618D02*
X737550Y1047717D01*
G01X737540Y1047546D02*
X737546Y1047618D01*
G01X737542Y1047520D02*
X737540Y1047546D01*
G01X737546Y1052618D02*
X737550Y1052717D01*
G01X737540Y1052546D02*
X737546Y1052618D01*
G01X737542Y1052520D02*
X737540Y1052546D01*
G01X737546Y1057618D02*
X737550Y1057717D01*
G01X737540Y1057546D02*
X737546Y1057618D01*
G01X737542Y1057520D02*
X737540Y1057546D01*
G01X737546Y1062618D02*
X737550Y1062717D01*
G01X737540Y1062546D02*
X737546Y1062618D01*
G01X737542Y1062520D02*
X737540Y1062546D01*
G01X737546Y1067618D02*
X737550Y1067717D01*
G01X737540Y1067546D02*
X737546Y1067618D01*
G01X737542Y1067520D02*
X737540Y1067546D01*
G01X737546Y1072618D02*
X737550Y1072717D01*
G01X737540Y1072546D02*
X737546Y1072618D01*
G01X737542Y1072520D02*
X737540Y1072546D01*
G01X737546Y1077618D02*
X737550Y1077717D01*
G01X737540Y1077546D02*
X737546Y1077618D01*
G01X737542Y1077520D02*
X737540Y1077546D01*
G01X737546Y1082618D02*
X737550Y1082717D01*
G01X737540Y1082546D02*
X737546Y1082618D01*
G01X737542Y1082520D02*
X737540Y1082546D01*
G01X736594Y1047527D02*
Y1047536D01*
G01X736595Y1047521D02*
X736594Y1047527D01*
G01Y1052527D02*
Y1052536D01*
G01X736595Y1052521D02*
X736594Y1052527D01*
G01X736596Y1052520D02*
X736595Y1052521D01*
G01X736594Y1057527D02*
Y1057536D01*
G01X736595Y1057521D02*
X736594Y1057527D01*
G01X736596Y1057520D02*
X736595Y1057521D01*
G01X736594Y1062527D02*
Y1062536D01*
G01X736595Y1062521D02*
X736594Y1062527D01*
G01X736596Y1062520D02*
X736595Y1062521D01*
G01X736594Y1067527D02*
Y1067536D01*
G01X736595Y1067521D02*
X736594Y1067527D01*
G01X736596Y1067520D02*
X736595Y1067521D01*
G01X736594Y1072527D02*
Y1072536D01*
G01X736595Y1072521D02*
X736594Y1072527D01*
G01X736596Y1072520D02*
X736595Y1072521D01*
G01X736594Y1077527D02*
Y1077536D01*
G01X736595Y1077521D02*
X736594Y1077527D01*
G01X736596Y1077520D02*
X736595Y1077521D01*
G01X736594Y1082527D02*
Y1082536D01*
G01X736595Y1082521D02*
X736594Y1082527D01*
G01X736596Y1082520D02*
X736595Y1082521D01*
G01X737571Y1047663D02*
X737579Y1047637D01*
G01X737561Y1047690D02*
X737571Y1047663D01*
G01X737550Y1047717D02*
X737561Y1047690D01*
G01X737571Y1052663D02*
X737579Y1052637D01*
G01X737561Y1052690D02*
X737571Y1052663D01*
G01X737550Y1052717D02*
X737561Y1052690D01*
G01X737571Y1057663D02*
X737579Y1057637D01*
G01X737561Y1057690D02*
X737571Y1057663D01*
G01X737550Y1057717D02*
X737561Y1057690D01*
G01X737571Y1062663D02*
X737579Y1062637D01*
G01X737561Y1062690D02*
X737571Y1062663D01*
G01X737550Y1062717D02*
X737561Y1062690D01*
G01X737571Y1067663D02*
X737579Y1067637D01*
G01X737561Y1067690D02*
X737571Y1067663D01*
G01X737550Y1067717D02*
X737561Y1067690D01*
G01X737571Y1072663D02*
X737579Y1072637D01*
G01X737561Y1072690D02*
X737571Y1072663D01*
G01X737550Y1072717D02*
X737561Y1072690D01*
G01X737571Y1077663D02*
X737579Y1077637D01*
G01X737561Y1077690D02*
X737571Y1077663D01*
G01X737550Y1077717D02*
X737561Y1077690D01*
G01X737571Y1082663D02*
X737579Y1082637D01*
G01X737561Y1082690D02*
X737571Y1082663D01*
G01X737550Y1082717D02*
X737561Y1082690D01*
G01Y1052515D02*
X737542Y1052520D01*
G01X737576Y1052500D02*
X737561Y1052515D01*
G01X737581Y1052480D02*
X737576Y1052500D01*
G01X737561Y1057515D02*
X737542Y1057520D01*
G01X737576Y1057500D02*
X737561Y1057515D01*
G01X737581Y1057480D02*
X737576Y1057500D01*
G01X737561Y1062515D02*
X737542Y1062520D01*
G01X737576Y1062500D02*
X737561Y1062515D01*
G01X737581Y1062480D02*
X737576Y1062500D01*
G01X737561Y1067515D02*
X737542Y1067520D01*
G01X737576Y1067500D02*
X737561Y1067515D01*
G01X737581Y1067480D02*
X737576Y1067500D01*
G01X737561Y1072515D02*
X737542Y1072520D01*
G01X737576Y1072500D02*
X737561Y1072515D01*
G01X737581Y1072480D02*
X737576Y1072500D01*
G01X737561Y1077515D02*
X737542Y1077520D01*
G01X737576Y1077500D02*
X737561Y1077515D01*
G01X737581Y1077480D02*
X737576Y1077500D01*
G01X737561Y1082515D02*
X737542Y1082520D01*
G01X737576Y1082500D02*
X737561Y1082515D01*
G01X737581Y1082480D02*
X737576Y1082500D01*
G01X737579Y1047487D02*
Y1047494D01*
G01Y1052487D02*
Y1052494D01*
G01X737580Y1052482D02*
X737579Y1052487D01*
G01X737581Y1052480D02*
X737580Y1052482D01*
G01X737579Y1057487D02*
Y1057494D01*
G01X737580Y1057482D02*
X737579Y1057487D01*
G01X737581Y1057480D02*
X737580Y1057482D01*
G01X737579Y1062487D02*
Y1062494D01*
G01X737580Y1062482D02*
X737579Y1062487D01*
G01X737581Y1062480D02*
X737580Y1062482D01*
G01X737579Y1067487D02*
Y1067494D01*
G01X737580Y1067482D02*
X737579Y1067487D01*
G01X737581Y1067480D02*
X737580Y1067482D01*
G01X737579Y1072487D02*
Y1072494D01*
G01X737580Y1072482D02*
X737579Y1072487D01*
G01X737581Y1072480D02*
X737580Y1072482D01*
G01X737579Y1077487D02*
Y1077494D01*
G01X737580Y1077482D02*
X737579Y1077487D01*
G01X737581Y1077480D02*
X737580Y1077482D01*
G01X737579Y1082487D02*
Y1082494D01*
G01X737580Y1082482D02*
X737579Y1082487D01*
G01X737581Y1082480D02*
X737580Y1082482D01*
G01X737566Y1052511D02*
X737577Y1052496D01*
G01X737542Y1052520D02*
X737566Y1052511D01*
G01Y1057511D02*
X737577Y1057496D01*
G01X737542Y1057520D02*
X737566Y1057511D01*
G01Y1062511D02*
X737577Y1062496D01*
G01X737542Y1062520D02*
X737566Y1062511D01*
G01Y1067511D02*
X737577Y1067496D01*
G01X737542Y1067520D02*
X737566Y1067511D01*
G01Y1072511D02*
X737577Y1072496D01*
G01X737542Y1072520D02*
X737566Y1072511D01*
G01Y1077511D02*
X737577Y1077496D01*
G01X737542Y1077520D02*
X737566Y1077511D01*
G01Y1082511D02*
X737577Y1082496D01*
G01X737542Y1082520D02*
X737566Y1082511D01*
G01X736024Y1108012D02*
G03X735433Y1108602I-591J-1D01*
G01X728740D02*
G03X728150Y1108012I0J-590D01*
G01X730906Y1106831D02*
G03Y1104862I0J-985D01*
G01X733268D02*
G03Y1106831I0J984D01*
G01X729528Y1098917D02*
G03X728346Y1097736I-1J-1181D01*
G01X735827D02*
G03X734646Y1098917I-1181J0D01*
G01X733976Y1093642D02*
G03I-1889J0D01*
G01X742913Y1107421D02*
G03X740945Y1109390I-1968J1D01*
G01X723228D02*
G03X721260Y1107421I1J-1969D01*
G01X734449Y1093642D02*
G03I-2362J0D01*
G01X740945Y1109390D02*
X723228D01*
G01X735433Y1108602D02*
X728740D01*
G01X733268Y1106831D02*
X730906D01*
G01Y1104862D02*
X733268D01*
G01X736024Y1103484D02*
X728150D01*
G01Y1101909D02*
X736024D01*
G01X742913Y1098957D02*
X721260D01*
G01X729528Y1098917D02*
X734646D01*
G01X730906Y1094232D02*
X733268D01*
G01X730906Y1092539D02*
X733268D01*
G01X724606Y1090571D02*
X738976D01*
G01X724606Y1089193D02*
X728346D01*
G01X738976D02*
X735827D01*
G01X724606Y1088327D02*
X739567D01*
G01X726378Y1086831D02*
X734252D01*
G01X727559Y1085650D02*
X733071D01*
G01X737579Y1083012D02*
X736594D01*
G01X736596Y1082520D02*
X741929D01*
G01Y1082480D02*
X737581D01*
G01X741929Y1081142D02*
X736596D01*
G01X736594Y1080650D02*
X737579D01*
G01Y1078012D02*
X736594D01*
G01X736596Y1077520D02*
X741929D01*
G01Y1077480D02*
X737581D01*
G01X741929Y1076142D02*
X736596D01*
G01X736594Y1075650D02*
X737579D01*
G01Y1073012D02*
X736594D01*
G01X736596Y1072520D02*
X741929D01*
G01Y1072480D02*
X737581D01*
G01X741929Y1071142D02*
X736596D01*
G01X736594Y1070650D02*
X737579D01*
G01Y1068012D02*
X736594D01*
G01X736596Y1067520D02*
X741929D01*
G01Y1067480D02*
X737581D01*
G01X741929Y1066142D02*
X736596D01*
G01X736594Y1065650D02*
X737579D01*
G01Y1063012D02*
X736594D01*
G01X736596Y1062520D02*
X741929D01*
G01Y1062480D02*
X737581D01*
G01X741929Y1061142D02*
X736596D01*
G01X736594Y1060650D02*
X737579D01*
G01Y1058012D02*
X736594D01*
G01X736596Y1057520D02*
X741929D01*
G01Y1057480D02*
X737581D01*
G01X741929Y1056142D02*
X736596D01*
G01X736594Y1055650D02*
X737579D01*
G01Y1053012D02*
X736594D01*
G01X736596Y1052520D02*
X741929D01*
G01Y1052480D02*
X737581D01*
G01X741929Y1051142D02*
X736596D01*
G01X736594Y1050650D02*
X737579D01*
G01Y1048012D02*
X736594D01*
G01X736596Y1047520D02*
X741929D01*
G01Y1047480D02*
X737581D01*
G01X736594Y1082715D02*
X737550Y1082717D01*
G01X737579Y1080946D02*
X736594Y1080945D01*
G01Y1077715D02*
X737550Y1077717D01*
G01X737579Y1075946D02*
X736594Y1075945D01*
G01Y1072715D02*
X737550Y1072717D01*
G01X737579Y1070946D02*
X736594Y1070945D01*
G01Y1067715D02*
X737550Y1067717D01*
G01X737579Y1065946D02*
X736594Y1065945D01*
G01Y1062715D02*
X737550Y1062717D01*
G01X737579Y1060946D02*
X736594Y1060945D01*
G01Y1057715D02*
X737550Y1057717D01*
G01X737579Y1055946D02*
X736594Y1055945D01*
G01Y1052715D02*
X737550Y1052717D01*
G01X737579Y1050946D02*
X736594Y1050945D01*
G01Y1047715D02*
X737550Y1047717D01*
G01X726378Y1086831D02*
X727559Y1085650D01*
G01X721260Y1091673D02*
X724606Y1088327D01*
G01X730906Y1094232D02*
X728595Y1098461D01*
G01X733268Y1092539D02*
X734571Y1090571D01*
G01X742913Y1091673D02*
Y1107421D01*
G01X741929Y1081142D02*
Y1082520D01*
G01Y1076142D02*
Y1077520D01*
G01Y1071142D02*
Y1072520D01*
G01Y1066142D02*
Y1067520D01*
G01Y1061142D02*
Y1062520D01*
G01Y1056142D02*
Y1057520D01*
G01Y1051142D02*
Y1052520D01*
G01X738760D02*
Y1051142D01*
G01Y1057520D02*
Y1056142D01*
G01Y1062520D02*
Y1061142D01*
G01Y1067520D02*
Y1066142D01*
G01Y1072520D02*
Y1071142D01*
G01Y1077520D02*
Y1076142D01*
G01Y1082520D02*
Y1081142D01*
G01X737579Y1080650D02*
Y1083012D01*
G01Y1075650D02*
Y1078012D01*
G01Y1070650D02*
Y1073012D01*
G01Y1065650D02*
Y1068012D01*
G01Y1060650D02*
Y1063012D01*
G01Y1055650D02*
Y1058012D01*
G01Y1050650D02*
Y1053012D01*
G01Y1047494D02*
Y1047637D01*
G01Y1052494D02*
Y1052637D01*
G01Y1057494D02*
Y1057637D01*
G01Y1062494D02*
Y1062637D01*
G01Y1067494D02*
Y1067637D01*
G01Y1072494D02*
Y1072637D01*
G01Y1077494D02*
Y1077637D01*
G01Y1082494D02*
Y1082637D01*
G01X736594Y1053012D02*
Y1050650D01*
G01Y1058012D02*
Y1055650D01*
G01Y1063012D02*
Y1060650D01*
G01Y1068012D02*
Y1065650D01*
G01Y1073012D02*
Y1070650D01*
G01Y1078012D02*
Y1075650D01*
G01Y1083012D02*
Y1080650D01*
G01X736024Y1101909D02*
Y1108012D01*
G01X735827Y1097736D02*
Y1089193D01*
G01X733268Y1094232D02*
Y1092539D01*
G01X737579Y1047494D02*
Y1047502D01*
G01Y1052494D02*
Y1052502D01*
G01Y1057494D02*
Y1057502D01*
G01Y1062494D02*
Y1062502D01*
G01Y1067494D02*
Y1067502D01*
G01Y1072494D02*
Y1072502D01*
G01Y1077494D02*
Y1077502D01*
G01Y1082494D02*
Y1082502D01*
G01X730906Y1092539D02*
Y1094232D01*
G01X728346Y1089193D02*
Y1097736D01*
G01X728150Y1101909D02*
Y1108012D01*
G01X721260Y1107421D02*
Y1091673D01*
G01X742913D02*
X739567Y1088327D01*
G01X733071Y1085650D02*
X734252Y1086831D01*
G01X729602Y1090571D02*
X730906Y1092539D01*
G01X735578Y1098461D02*
X733268Y1094232D01*
G01X684449Y1515748D02*
G03X680512Y1519685I-3937J0D01*
G01X684449Y1509055D02*
Y1515748D01*
G01Y1509055D02*
G03X688386Y1505118I3937J0D01*
G01X713976D02*
X688386D01*
G01X713976D02*
G03X717913Y1509055I0J3937D01*
G01Y1515748D02*
Y1509055D01*
G01X721850Y1519685D02*
G03X717913Y1515748I0J-3937D01*
G01X775591Y1519685D02*
X721850D01*
G01X713976Y1505118D02*
G03X717913Y1509055I0J3937D01*
G01X684449D02*
G03X688386Y1505118I3937J0D01*
G01X684449Y1515748D02*
G03X680512Y1519685I-3937J0D01*
G01X721850D02*
G03X717913Y1515748I0J-3937D01*
G01X775591Y1519685D02*
X721850D01*
G01X688386Y1505118D02*
X713976D01*
G01X717913Y1515748D02*
Y1509055D01*
G01X684449Y1515748D02*
Y1509055D01*
G01X697936Y1808346D02*
Y1789409D01*
G01X816639Y17406D02*
G03I-4292J0D01*
G01D02*
G03I-4292J0D01*
G01X791339Y23622D02*
G03X783465I-3937J0D01*
G01Y54331D02*
G03X791339I3937J0D01*
G01Y3937D02*
G03X795276Y0I3937J0D01*
G01D02*
X892317D01*
G01X791339Y54331D02*
Y181890D01*
G01Y3937D02*
Y23622D01*
G01Y54331D02*
Y181890D01*
G01Y23622D02*
G03X783465I-3937J0D01*
G01Y54331D02*
G03X791339I3937J0D01*
G01Y3937D02*
G03X795276Y0I3937J0D01*
G01X783465Y3937D02*
Y185827D01*
G01X779528Y0D02*
G03X783465Y3937I0J3937D01*
G01X791339D02*
Y23622D01*
G01X795276Y0D02*
X892317D01*
G01X779528D02*
G03X783465Y3937I0J3937D01*
G01D02*
Y185827D01*
G01X811024Y181890D02*
G03X822835Y193701I0J11811D01*
G01X791339Y181890D02*
X811024D01*
G01X787402Y189764D02*
G03X783465Y185827I0J-3937D01*
G01X811024Y181890D02*
G03X822835Y193701I0J11811D01*
G01X791339Y181890D02*
X811024D01*
G01X787402Y189764D02*
G03X783465Y185827I0J-3937D01*
G01X830823Y209300D02*
X830559Y209811D01*
G01X831201Y208869D02*
X830823Y209300D01*
G01X831671Y208542D02*
X831201Y208869D01*
G01X832206Y208337D02*
X831671Y208542D01*
G01X832775Y208268D02*
X832206Y208337D01*
G01X844996Y209300D02*
X844733Y209811D01*
G01X845374Y208869D02*
X844996Y209300D01*
G01X845844Y208542D02*
X845374Y208869D01*
G01X846379Y208337D02*
X845844Y208542D01*
G01X846948Y208268D02*
X846379Y208337D01*
G01X830303Y210336D02*
X830349Y210178D01*
G01X830263Y210462D02*
X830303Y210336D01*
G01X830212Y210546D02*
X830263Y210462D01*
G01X830119Y210602D02*
X830212Y210546D01*
G01X829977Y210630D02*
X830119Y210602D01*
G01X844476Y210336D02*
X844522Y210178D01*
G01X844436Y210462D02*
X844476Y210336D01*
G01X844385Y210546D02*
X844436Y210462D01*
G01X844292Y210602D02*
X844385Y210546D01*
G01X844150Y210630D02*
X844292Y210602D01*
G01X832278Y208481D02*
X832307Y208473D01*
G01X832185Y208505D02*
X832278Y208481D01*
G01X832035Y208539D02*
X832185Y208505D01*
G01X831847Y208583D02*
X832035Y208539D01*
G01X846451Y208481D02*
X846480Y208473D01*
G01X846359Y208505D02*
X846451Y208481D01*
G01X846209Y208539D02*
X846359Y208505D01*
G01X846020Y208583D02*
X846209Y208539D01*
G01X860624Y208481D02*
X860654Y208473D01*
G01X860532Y208505D02*
X860624Y208481D01*
G01X860382Y208539D02*
X860532Y208505D01*
G01X860193Y208583D02*
X860382Y208539D01*
G01X853553Y208538D02*
X853743Y208583D01*
G01X853404Y208505D02*
X853553Y208538D01*
G01X853313Y208482D02*
X853404Y208505D01*
G01X853283Y208473D02*
X853313Y208482D01*
G01X839380Y208538D02*
X839570Y208583D01*
G01X839231Y208505D02*
X839380Y208538D01*
G01X839140Y208482D02*
X839231Y208505D01*
G01X839109Y208473D02*
X839140Y208482D01*
G01X825206Y208538D02*
X825396Y208583D01*
G01X825058Y208505D02*
X825206Y208538D01*
G01X824967Y208482D02*
X825058Y208505D01*
G01X824936Y208473D02*
X824967Y208482D01*
G01X854637Y240691D02*
X854606Y240533D01*
G01X854727Y240824D02*
X854637Y240691D01*
G01X854860Y240913D02*
X854727Y240824D01*
G01X855018Y240945D02*
X854860Y240913D01*
G01X840464Y240691D02*
X840433Y240533D01*
G01X840554Y240824D02*
X840464Y240691D01*
G01X840687Y240913D02*
X840554Y240824D01*
G01X840844Y240945D02*
X840687Y240913D01*
G01X826291Y240691D02*
X826259Y240533D01*
G01X826380Y240824D02*
X826291Y240691D01*
G01X826514Y240913D02*
X826380Y240824D01*
G01X826671Y240945D02*
X826514Y240913D01*
G01X855202Y210177D02*
X854930Y209400D01*
G01X855248Y210336D02*
X855202Y210177D01*
G01X855289Y210462D02*
X855248Y210336D01*
G01X855340Y210546D02*
X855289Y210462D01*
G01X855433Y210602D02*
X855340Y210546D01*
G01X855574Y210630D02*
X855433Y210602D01*
G01X841029Y210177D02*
X840757Y209400D01*
G01X841074Y210336D02*
X841029Y210177D01*
G01X841116Y210462D02*
X841074Y210336D01*
G01X841167Y210546D02*
X841116Y210462D01*
G01X841259Y210602D02*
X841167Y210546D01*
G01X841400Y210630D02*
X841259Y210602D01*
G01X826856Y210177D02*
X826782Y209967D01*
G01X826901Y210336D02*
X826856Y210177D01*
G01X826943Y210462D02*
X826901Y210336D01*
G01X826993Y210546D02*
X826943Y210462D01*
G01X827086Y210602D02*
X826993Y210546D01*
G01X827227Y210630D02*
X827086Y210602D01*
G01X854626Y208922D02*
X854930Y209400D01*
G01X854242Y208565D02*
X854626Y208922D01*
G01X853807Y208344D02*
X854242Y208565D01*
G01X853335Y208268D02*
X853807Y208344D01*
G01X840453Y208922D02*
X840757Y209400D01*
G01X840069Y208565D02*
X840453Y208922D01*
G01X839634Y208344D02*
X840069Y208565D01*
G01X839162Y208268D02*
X839634Y208344D01*
G01X853797Y208480D02*
X854193Y208721D01*
G01X853366Y208324D02*
X853797Y208480D01*
G01X852909Y208268D02*
X853366Y208324D01*
G01X839624Y208480D02*
X840019Y208721D01*
G01X839193Y208324D02*
X839624Y208480D01*
G01X838735Y208268D02*
X839193Y208324D01*
G01X826530Y240532D02*
X826666Y240539D01*
G01X826399Y240533D02*
X826530Y240532D01*
G01X840703D02*
X840839Y240539D01*
G01X840572Y240533D02*
X840703Y240532D01*
G01X854876D02*
X855012Y240539D01*
G01X854745Y240533D02*
X854876Y240532D01*
G01X830844Y240533D02*
X831378D01*
G01X830713Y240532D02*
X830844Y240533D01*
G01X830578Y240539D02*
X830713Y240532D01*
G01X859170Y209300D02*
X858906Y209811D01*
G01X859547Y208869D02*
X859170Y209300D01*
G01X860017Y208542D02*
X859547Y208869D01*
G01X860552Y208337D02*
X860017Y208542D01*
G01X861121Y208268D02*
X860552Y208337D01*
G01X858650Y210336D02*
X858695Y210178D01*
G01X858609Y210462D02*
X858650Y210336D01*
G01X858559Y210546D02*
X858609Y210462D01*
G01X858465Y210602D02*
X858559Y210546D01*
G01X858324Y210630D02*
X858465Y210602D01*
G01X832478Y208293D02*
X832602Y208268D01*
G01X832374Y208366D02*
X832478Y208293D01*
G01X832307Y208473D02*
X832374Y208366D01*
G01X846652Y208293D02*
X846776Y208268D01*
G01X846547Y208366D02*
X846652Y208293D01*
G01X846480Y208473D02*
X846547Y208366D01*
G01X860825Y208293D02*
X860949Y208268D01*
G01X860720Y208366D02*
X860825Y208293D01*
G01X860654Y208473D02*
X860720Y208366D01*
G01X831731Y208349D02*
X832219Y208268D01*
G01X831285Y208583D02*
X831731Y208349D01*
G01X830906Y208946D02*
X831285Y208583D01*
G01X830616Y209410D02*
X830906Y208946D01*
G01X830349Y210178D02*
X830616Y209410D01*
G01X845905Y208349D02*
X846392Y208268D01*
G01X845458Y208583D02*
X845905Y208349D01*
G01X845080Y208946D02*
X845458Y208583D01*
G01X844789Y209410D02*
X845080Y208946D01*
G01X844522Y210178D02*
X844789Y209410D01*
G01X860078Y208349D02*
X860565Y208268D01*
G01X859631Y208583D02*
X860078Y208349D01*
G01X859253Y208946D02*
X859631Y208583D01*
G01X858963Y209410D02*
X859253Y208946D01*
G01X858695Y210178D02*
X858963Y209410D01*
G01X830730Y240913D02*
X830572Y240945D01*
G01X830863Y240824D02*
X830730Y240913D01*
G01X830952Y240691D02*
X830863Y240824D01*
G01X830984Y240533D02*
X830952Y240691D01*
G01X844903Y240913D02*
X844745Y240945D01*
G01X845037Y240824D02*
X844903Y240913D01*
G01X845126Y240691D02*
X845037Y240824D01*
G01X845157Y240533D02*
X845126Y240691D01*
G01X859076Y240913D02*
X858919Y240945D01*
G01X859210Y240824D02*
X859076Y240913D01*
G01X859299Y240690D02*
X859210Y240824D01*
G01X859330Y240533D02*
X859299Y240690D01*
G01X830572Y240674D02*
X830578Y240539D01*
G01X830572Y240805D02*
Y240674D01*
G01X844745D02*
X844751Y240539D01*
G01X844745Y240805D02*
Y240674D01*
G01X858918Y240619D02*
X858924Y240539D01*
G01X858919Y240702D02*
X858918Y240619D01*
G01Y240785D02*
X858919Y240702D01*
G01Y240862D02*
X858918Y240785D01*
G01X855018Y240806D02*
Y241339D01*
G01Y240674D02*
Y240806D01*
G01X855012Y240539D02*
X855018Y240674D01*
G01X826671Y240914D02*
Y241339D01*
G01Y240839D02*
Y240914D01*
G01Y240741D02*
Y240839D01*
G01Y240637D02*
Y240741D01*
G01X826666Y240539D02*
X826671Y240637D01*
G01X840844Y240914D02*
Y241339D01*
G01Y240839D02*
Y240914D01*
G01Y240741D02*
Y240839D01*
G01Y240637D02*
Y240741D01*
G01X840839Y240539D02*
X840844Y240637D01*
G01X825475Y208349D02*
X824989Y208268D01*
G01X825922Y208583D02*
X825475Y208349D01*
G01X826301Y208948D02*
X825922Y208583D01*
G01X826590Y209413D02*
X826301Y208948D01*
G01X826782Y209967D02*
X826590Y209413D01*
G01X826179Y209043D02*
X825846Y208740D01*
G01X826448Y209404D02*
X826179Y209043D01*
G01X826644Y209811D02*
X826448Y209404D01*
G01X840352Y209043D02*
X840019Y208740D01*
G01X840621Y209404D02*
X840352Y209043D01*
G01X840818Y209811D02*
X840621Y209404D01*
G01X854525Y209043D02*
X854193Y208740D01*
G01X854794Y209404D02*
X854525Y209043D01*
G01X854991Y209811D02*
X854794Y209404D01*
G01X824765Y208293D02*
X824641Y208268D01*
G01X824869Y208366D02*
X824765Y208293D01*
G01X824936Y208473D02*
X824869Y208366D01*
G01X838939Y208293D02*
X838815Y208268D01*
G01X839043Y208366D02*
X838939Y208293D01*
G01X839109Y208473D02*
X839043Y208366D01*
G01X853112Y208293D02*
X852988Y208268D01*
G01X853216Y208366D02*
X853112Y208293D01*
G01X853283Y208473D02*
X853216Y208366D01*
G01X825044Y208330D02*
X824562Y208268D01*
G01X825474Y208492D02*
X825044Y208330D01*
G01X825846Y208721D02*
X825474Y208492D01*
G01X822835Y193701D02*
Y240157D01*
G01X928098D02*
X822835D01*
G01X928098D02*
X822835D01*
G01X818898Y248031D02*
X1055118D01*
G01X818898D02*
G03X814961Y244094I0J-3937D01*
G01Y193701D02*
Y244094D01*
G01X811024Y189764D02*
G03X814961Y193701I0J3937D01*
G01X787402Y189764D02*
X811024D01*
G01X822835Y193701D02*
Y240157D01*
G01X850673Y279882D02*
G03X849689Y280866I-984J0D01*
G01X854019D02*
G03X853035Y279882I0J-984D01*
G01X857759D02*
G03X856775Y280866I-984J0D01*
G01X861106D02*
G03X860122Y279882I0J-984D01*
G01X825673Y280866D02*
G03X824689Y279882I0J-984D01*
G01X829413D02*
G03X828429Y280866I-984J0D01*
G01X832759D02*
G03X831775Y279882I0J-984D01*
G01X836500D02*
G03X835515Y280866I-984J0D01*
G01X839846D02*
G03X838862Y279882I0J-984D01*
G01X843586D02*
G03X842602Y280866I-984J0D01*
G01X846933D02*
G03X845948Y279882I-1J-984D01*
G01X824059Y279508D02*
G03X825633Y277933I1575J0D01*
G01X827480Y262992D02*
G03I-708J0D01*
G01X828626Y276358D02*
G03X827051Y277933I-1575J0D01*
G01X835712Y276358D02*
G03X832563I-1575J0D01*
G01X842799D02*
G03X839649I-1575J0D01*
G01X849885D02*
G03X846736I-1575J0D01*
G01X856972D02*
G03X853822I-1575J0D01*
G01X864059D02*
G03X860909I-1575J0D01*
G01X818898Y248031D02*
G03X814961Y244094I0J-3937D01*
G01X855574Y240944D02*
G03X855180Y240551I0J-394D01*
G01X858717D02*
G03X858323Y240944I-394J-1D01*
G01X844544Y240551D02*
G03X844150Y240944I-394J-1D01*
G01X855018Y240945D02*
G03X854606Y240533I0J-412D01*
G01X859330D02*
G03X858919Y240945I-412J0D01*
G01X845157Y240533D02*
G03X844745Y240945I-412J0D01*
G01X844937Y240551D02*
G03X844150Y241338I-787J0D01*
G01X855574D02*
G03X854787Y240551I0J-787D01*
G01X859111D02*
G03X858323Y241338I-787J0D01*
G01X859724Y240533D02*
G03X858919Y241339I-806J0D01*
G01X855018D02*
G03X854212Y240533I0J-806D01*
G01X845551D02*
G03X844745Y241339I-806J0D01*
G01X859111Y210674D02*
G03X859208Y210128I1575J-2D01*
G01X859724Y212406D02*
G03X859822Y211860I1575J1D01*
G01X858717Y210674D02*
G03X858839Y209992I1968J0D01*
G01X859330Y212406D02*
G03X859452Y211723I1969J-1D01*
G01X858906Y209811D02*
G03X861122Y208268I2216J819D01*
G01X858323Y210674D02*
G03X858324Y210630I2362J32D01*
G01X858937Y212406D02*
G03X859083Y211587I2362J-1D01*
G01X860654Y208473D02*
G03X860949Y208268I295J110D01*
G01X844937Y210674D02*
G03X845035Y210128I1575J1D01*
G01X854689Y210130D02*
G03X854787Y210675I-1477J547D01*
G01X854115Y211860D02*
G03X854212Y212406I-1478J544D01*
G01X845551D02*
G03X845648Y211860I1575J-2D01*
G01X855058Y209993D02*
G03X855180Y210675I-1846J682D01*
G01X844544Y210674D02*
G03X844666Y209992I1968J0D01*
G01X854484Y211723D02*
G03X854606Y212406I-1847J682D01*
G01X845157D02*
G03X845279Y211723I1969J-1D01*
G01X855574Y210630D02*
G03Y210675I-2362J22D01*
G01X854193Y208740D02*
G03X854991Y209811I-1418J1889D01*
G01X844733D02*
G03X846948Y208268I2215J819D01*
G01X844150Y210674D02*
G03Y210630I2362J-22D01*
G01X854853Y211587D02*
G03X855000Y212406I-2215J820D01*
G01X844763D02*
G03X844910Y211587I2362J1D01*
G01X852987Y208268D02*
G03X853283Y208473I1J315D01*
G01X846480D02*
G03X846776Y208268I295J110D01*
G01X841401Y240944D02*
G03X841007Y240551I0J-394D01*
G01X827228Y240944D02*
G03X826834Y240551I0J-394D01*
G01X830370D02*
G03X829977Y240944I-393J0D01*
G01X826671Y240945D02*
G03X826259Y240533I0J-412D01*
G01X830984D02*
G03X830572Y240945I-412J0D01*
G01X840844D02*
G03X840433Y240533I1J-412D01*
G01X841401Y241338D02*
G03X840613Y240551I-1J-787D01*
G01X827228Y241338D02*
G03X826440Y240551I-1J-787D01*
G01X830764D02*
G03X829977Y241338I-787J0D01*
G01X831378Y240533D02*
G03X830572Y241339I-806J0D01*
G01X826671D02*
G03X825866Y240533I1J-806D01*
G01X840844Y241339D02*
G03X840039Y240533I1J-806D01*
G01X840516Y210130D02*
G03X840613Y210675I-1478J544D01*
G01X830764Y210674D02*
G03X830862Y210128I1575J1D01*
G01X831378Y212406D02*
G03X831475Y211860I1575J-2D01*
G01X839941D02*
G03X840039Y212406I-1477J547D01*
G01X830984D02*
G03X831106Y211723I1968J-1D01*
G01X840885Y209993D02*
G03X841007Y210675I-1846J682D01*
G01X830370Y210674D02*
G03X830493Y209992I1969J3D01*
G01X840311Y211723D02*
G03X840433Y212406I-1847J682D01*
G01X841400Y210630D02*
G03X841401Y210675I-2361J75D01*
G01X840019Y208740D02*
G03X840818Y209811I-1417J1890D01*
G01X830559D02*
G03X832775Y208268I2216J819D01*
G01X829977Y210674D02*
G03Y210630I2362J-22D01*
G01X830590Y212406D02*
G03X830737Y211587I2362J1D01*
G01X840680D02*
G03X840826Y212406I-2216J818D01*
G01X838814Y208268D02*
G03X839109Y208473I0J315D01*
G01X832307D02*
G03X832602Y208268I295J110D01*
G01X826343Y210130D02*
G03X826440Y210675I-1478J544D01*
G01X825768Y211860D02*
G03X825866Y212406I-1477J547D01*
G01X826137Y211723D02*
G03X826259Y212406I-1846J682D01*
G01X826712Y209993D02*
G03X826834Y210675I-1847J682D01*
G01X825846Y208740D02*
G03X826644Y209811I-1418J1889D01*
G01X827227Y210630D02*
G03X827228Y210675I-2361J75D01*
G01X826507Y211587D02*
G03X826653Y212406I-2216J818D01*
G01X824641Y208268D02*
G03X824936Y208473I0J315D01*
G01X811024Y189764D02*
G03X814961Y193701I0J3937D01*
G01X860654Y208473D02*
X861033Y208583D01*
G01X846480Y208473D02*
X846860Y208583D01*
G01X832307Y208473D02*
X832687Y208583D01*
G01X858769Y209966D02*
X859208Y210128D01*
G01X859083Y211587D02*
X859822Y211860D01*
G01X844596Y209966D02*
X845035Y210128D01*
G01X844910Y211587D02*
X845648Y211860D01*
G01X830422Y209966D02*
X830862Y210128D01*
G01X830737Y211587D02*
X831475Y211860D01*
G01X855129Y209967D02*
X854991Y209811D01*
G01X840956Y209967D02*
X840818Y209811D01*
G01X826782Y209967D02*
X826644Y209811D01*
G01X853216Y208366D02*
X853283Y208473D01*
G01X839043Y208366D02*
X839109Y208473D01*
G01X824869Y208366D02*
X824936Y208473D01*
G01X860909Y259847D02*
X859531Y257461D01*
G01X853822Y259847D02*
X852444Y257461D01*
G01X861736Y275186D02*
X860948Y273822D01*
G01X846736Y259847D02*
X845358Y257461D01*
G01X854649Y274765D02*
X853862Y273401D01*
G01X839649Y259847D02*
X838271Y257461D01*
G01X847563Y275186D02*
X846775Y273822D01*
G01X832563Y259847D02*
X831185Y257461D01*
G01X840476Y274765D02*
X839689Y273401D01*
G01X833389Y275186D02*
X832602Y273822D01*
G01X826303Y274765D02*
X825515Y273401D01*
G01X855058Y209993D02*
X854991Y209811D01*
G01X854689Y210130D02*
X854193Y208786D01*
G01X854853Y211587D02*
X853743Y208583D01*
G01X854484Y211723D02*
X853283Y208473D01*
G01X852904Y208583D02*
X854115Y211860D01*
G01X840818Y209811D02*
X840885Y209993D01*
G01X840516Y210130D02*
X840019Y208786D01*
G01X840680Y211587D02*
X839570Y208583D01*
G01X840311Y211723D02*
X839109Y208473D01*
G01X838730Y208583D02*
X839941Y211860D01*
G01X826712Y209993D02*
X826644Y209811D01*
G01X826343Y210130D02*
X825846Y208786D01*
G01X826507Y211587D02*
X825396Y208583D01*
G01X826137Y211723D02*
X824936Y208473D01*
G01X824557Y208583D02*
X825768Y211860D01*
G01X844745Y241339D02*
Y240805D01*
G01X830572Y241339D02*
Y240805D01*
G01X858919Y241339D02*
Y240862D01*
G01X855000Y212406D02*
X855007Y240543D01*
G01X840826Y212406D02*
X840834Y240543D01*
G01X826653Y212406D02*
X826661Y240543D01*
G01X861116Y216142D02*
Y208268D01*
G01X861033Y208583D02*
Y208268D01*
G01X860948Y256457D02*
Y273822D01*
G01X860909Y276358D02*
Y259847D01*
G01X860193Y208583D02*
Y208268D01*
G01X860122Y279882D02*
Y256457D01*
G01X859724Y212406D02*
Y240533D01*
G01X859330D02*
Y212406D01*
G01X859111Y240551D02*
Y210674D01*
G01X858937Y212406D02*
Y240533D01*
G01X858717Y240551D02*
Y210674D01*
G01X858324Y208268D02*
Y210630D01*
G01X858323Y210674D02*
Y241338D01*
G01X857759Y256457D02*
Y279882D01*
G01X856972Y259847D02*
Y276358D01*
G01X856933Y273401D02*
Y256457D01*
G01X855574Y210675D02*
Y241338D01*
G01Y208268D02*
Y210630D01*
G01X855180Y240551D02*
Y210675D01*
G01X854787D02*
Y240551D01*
G01X854606Y240533D02*
Y212406D01*
G01X854212Y240533D02*
Y212406D01*
G01X854193Y208721D02*
Y216142D01*
G01X853862Y256457D02*
Y273401D01*
G01X853822Y276358D02*
Y259847D01*
G01X853743Y208583D02*
Y208268D01*
G01X853035Y279882D02*
Y256457D01*
G01X852904Y208583D02*
Y208268D01*
G01X851830Y216142D02*
Y208268D01*
G01X851470Y216142D02*
Y208268D01*
G01X850673Y256457D02*
Y279882D01*
G01X849885Y259847D02*
Y276358D01*
G01X849846Y273822D02*
Y256457D01*
G01X846943Y208268D02*
Y216142D01*
G01X846860Y208583D02*
Y208268D01*
G01X846775Y256457D02*
Y273822D01*
G01X846736Y276358D02*
Y259847D01*
G01X846020Y208583D02*
Y208268D01*
G01X845948Y279882D02*
Y256457D01*
G01X845551Y212406D02*
Y240533D01*
G01X845157D02*
Y212406D01*
G01X844937Y240551D02*
Y210674D01*
G01X844763Y240533D02*
Y212406D01*
G01X844544Y240551D02*
Y210674D01*
G01X844150Y208268D02*
Y210630D01*
G01Y210674D02*
Y241338D01*
G01X843586Y256457D02*
Y279882D01*
G01X842799Y259847D02*
Y276358D01*
G01X842759Y273401D02*
Y256457D01*
G01X841401Y210675D02*
Y241338D01*
G01X841400Y208268D02*
Y210630D01*
G01X841007Y240551D02*
Y210675D01*
G01X840613D02*
Y240551D01*
G01X840433Y240533D02*
Y212406D01*
G01X840039Y240533D02*
Y212406D01*
G01X840019Y208721D02*
Y216142D01*
G01X839689Y256457D02*
Y273401D01*
G01X839649Y276358D02*
Y259847D01*
G01X839570Y208583D02*
Y208268D01*
G01X838862Y279882D02*
Y256457D01*
G01X838730Y208583D02*
Y208268D01*
G01X837657Y216142D02*
Y208268D01*
G01X837297Y216142D02*
Y208268D01*
G01X836500Y256457D02*
Y279882D01*
G01X835712Y259847D02*
Y276358D01*
G01X835673Y273822D02*
Y256457D01*
G01X832769Y208268D02*
Y216142D01*
G01X832687Y208583D02*
Y208268D01*
G01X832602Y256457D02*
Y273822D01*
G01X832563Y276358D02*
Y259847D01*
G01X831847Y208583D02*
Y208268D01*
G01X831775Y279882D02*
Y256457D01*
G01X831378Y212406D02*
Y240533D01*
G01X830984D02*
Y212406D01*
G01X830764Y240551D02*
Y210674D01*
G01X830370Y240551D02*
Y210674D01*
G01X829977Y208268D02*
Y210630D01*
G01Y210674D02*
Y241338D01*
G01X829413Y256457D02*
Y279882D01*
G01X828626Y259847D02*
Y276358D01*
G01X828586Y273401D02*
Y256457D01*
G01X827228Y241338D02*
Y210675D01*
G01X827227Y210630D02*
Y208268D01*
G01X826834Y240551D02*
Y210675D01*
G01X826440D02*
Y240551D01*
G01X826259Y240533D02*
Y212406D01*
G01X825866Y240533D02*
Y212406D01*
G01X825846Y208721D02*
Y216142D01*
G01X825515Y256457D02*
Y273401D01*
G01X825396Y208583D02*
Y208268D01*
G01X824689Y279882D02*
Y256457D01*
G01X824557Y208583D02*
Y208268D01*
G01X824403Y246850D02*
Y208268D01*
G01X824076Y323917D02*
Y235204D01*
G01X824059Y279508D02*
Y321358D01*
G01X814961Y193701D02*
Y244094D01*
G01X830583Y240543D02*
X830590Y212406D01*
G01X859822Y211860D02*
X861033Y208583D01*
G01X859452Y211723D02*
X860654Y208473D01*
G01X860193Y208583D02*
X859083Y211587D01*
G01X859728Y208722D02*
X859208Y210128D01*
G01X858839Y209992D02*
X858906Y209811D01*
G01X845648Y211860D02*
X846860Y208583D01*
G01X845279Y211723D02*
X846480Y208473D01*
G01X846020Y208583D02*
X844910Y211587D01*
G01X845555Y208722D02*
X845035Y210128D01*
G01X844666Y209992D02*
X844733Y209811D01*
G01X831475Y211860D02*
X832687Y208583D01*
G01X831106Y211723D02*
X832307Y208473D01*
G01X831847Y208583D02*
X830737Y211587D01*
G01X831381Y208722D02*
X830862Y210128D01*
G01X830493Y209992D02*
X830559Y209811D01*
G01X856145Y274765D02*
X856933Y273401D01*
G01X849059Y275186D02*
X849846Y273822D01*
G01X858350Y257461D02*
X856972Y259847D01*
G01X841972Y274765D02*
X842759Y273401D01*
G01X851263Y257461D02*
X849885Y259847D01*
G01X834885Y275186D02*
X835673Y273822D01*
G01X844177Y257461D02*
X842799Y259847D01*
G01X827799Y274765D02*
X828586Y273401D01*
G01X837090Y257461D02*
X835712Y259847D01*
G01X830004Y257461D02*
X828626Y259847D01*
G01X860720Y208366D02*
X860654Y208473D01*
G01X846547Y208366D02*
X846480Y208473D01*
G01X832374Y208366D02*
X832307Y208473D01*
G01X858769Y209966D02*
X858906Y209811D01*
G01X844596Y209966D02*
X844733Y209811D01*
G01X830422Y209966D02*
X830559Y209811D01*
G01X854115Y211860D02*
X854853Y211587D01*
G01X855129Y209967D02*
X854689Y210130D01*
G01X839941Y211860D02*
X840680Y211587D01*
G01X840516Y210130D02*
X840956Y209967D01*
G01X854212Y240533D02*
X854745D01*
G01X840039D02*
X840572D01*
G01X825866D02*
X826399D01*
G01X828429Y280866D02*
X825673D01*
G01X835515D02*
X832759D01*
G01X842602D02*
X839846D01*
G01X849689D02*
X846933D01*
G01X856775D02*
X854019D01*
G01X863862D02*
X861106D01*
G01X829413Y278343D02*
X824689D01*
G01X836500D02*
X831775D01*
G01X843586D02*
X838862D01*
G01X850673D02*
X845948D01*
G01X857759D02*
X853035D01*
G01X864846D02*
X860122D01*
G01X827051Y277933D02*
X825633D01*
G01X834885Y275186D02*
X833389D01*
G01X849059D02*
X847563D01*
G01X863232D02*
X861736D01*
G01X827799Y274765D02*
X826303D01*
G01X841972D02*
X840476D01*
G01X856145D02*
X854649D01*
G01X831185Y257461D02*
X830004D01*
G01X838271D02*
X837090D01*
G01X845358D02*
X844177D01*
G01X852444D02*
X851263D01*
G01X859531D02*
X858350D01*
G01X856933Y256457D02*
X860948D01*
G01X849846D02*
X853862D01*
G01X842759D02*
X846775D01*
G01X835673D02*
X839689D01*
G01X828586D02*
X832602D01*
G01X824076D02*
X825515D01*
G01X880213Y253274D02*
X824076D01*
G01X880213Y248944D02*
X824076D01*
G01X1055118Y248031D02*
X818898D01*
G01X824076Y246850D02*
X880702D01*
G01X824403Y246260D02*
X880702D01*
G01X824403Y243638D02*
X880702D01*
G01X824403Y243441D02*
X880702D01*
G01X830572Y241339D02*
X826671D01*
G01X844745D02*
X840844D01*
G01X858919D02*
X855018D01*
G01X830572Y240945D02*
X826671D01*
G01X844745D02*
X840844D01*
G01X858919D02*
X855018D01*
G01X854787Y240551D02*
X859111D01*
G01X840613D02*
X844937D01*
G01X826440D02*
X830764D01*
G01X855007Y240543D02*
X858937D01*
G01X840834D02*
X844756D01*
G01X826661D02*
X830583D01*
G01X858937Y240533D02*
X859724D01*
G01X844763D02*
X845551D01*
G01X824403Y235204D02*
X824076D01*
G01X851830Y216142D02*
X854193D01*
G01X846943D02*
X851470D01*
G01X837657D02*
X840019D01*
G01X832769D02*
X837297D01*
G01X824403D02*
X825846D01*
G01X865643D02*
X861116D01*
G01X858937Y212406D02*
X859724D01*
G01X844763D02*
X845551D01*
G01X840039D02*
X840826D01*
G01X830590D02*
X831378D01*
G01X826653D02*
X825866D01*
G01X855000D02*
X854212D01*
G01X854787Y210675D02*
X855574D01*
G01X840613D02*
X841401D01*
G01X827228D02*
X826440D01*
G01X858323Y210674D02*
X859111D01*
G01X844150D02*
X844937D01*
G01X829977D02*
X830764D01*
G01X829977Y210630D02*
X827227D01*
G01X844150D02*
X841400D01*
G01X858324D02*
X855574D01*
G01X861116Y208756D02*
X865643D01*
G01X846943D02*
X851470D01*
G01X832769D02*
X837297D01*
G01X851830D02*
X854193D01*
G01X837657D02*
X840019D01*
G01X825846D02*
X824403D01*
G01X853743Y208583D02*
X867077D01*
G01X825396D02*
X838730D01*
G01X839570D02*
X852904D01*
G01X824403D02*
X824557D01*
G01X880702Y208268D02*
X824403D01*
G01X825768Y211860D02*
X826507Y211587D01*
G01X826343Y210130D02*
X826782Y209967D01*
G01X853283Y208473D02*
X852904Y208583D01*
G01X838730D02*
X839109Y208473D01*
G01X824557Y208583D02*
X824936Y208473D01*
G01X787402Y189764D02*
X811024D01*
G01X826136Y314417D02*
X826323Y314272D01*
G01X825959Y314603D02*
X826136Y314417D01*
G01X825801Y314827D02*
X825959Y314603D01*
G01X825669Y315085D02*
X825801Y314827D01*
G01X825569Y315370D02*
X825669Y315085D01*
G01X825507Y315674D02*
X825569Y315370D01*
G01X825486Y315986D02*
X825507Y315674D01*
G01X833222Y314417D02*
X833410Y314272D01*
G01X833046Y314603D02*
X833222Y314417D01*
G01X832887Y314827D02*
X833046Y314603D01*
G01X832755Y315085D02*
X832887Y314827D01*
G01X832656Y315370D02*
X832755Y315085D01*
G01X832594Y315674D02*
X832656Y315370D01*
G01X832572Y315986D02*
X832594Y315674D01*
G01X840309Y314417D02*
X840496Y314272D01*
G01X840132Y314603D02*
X840309Y314417D01*
G01X839974Y314827D02*
X840132Y314603D01*
G01X839842Y315085D02*
X839974Y314827D01*
G01X839743Y315370D02*
X839842Y315085D01*
G01X839680Y315674D02*
X839743Y315370D01*
G01X839659Y315986D02*
X839680Y315674D01*
G01X825957Y314493D02*
X826323Y314272D01*
G01X825695Y314774D02*
X825957Y314493D01*
G01X825539Y315088D02*
X825695Y314774D01*
G01X825486Y315415D02*
X825539Y315088D01*
G01X833044Y314493D02*
X833410Y314272D01*
G01X832782Y314774D02*
X833044Y314493D01*
G01X832625Y315088D02*
X832782Y314774D01*
G01X832572Y315415D02*
X832625Y315088D01*
G01X840131Y314493D02*
X840496Y314272D01*
G01X839869Y314774D02*
X840131Y314493D01*
G01X839712Y315088D02*
X839869Y314774D01*
G01X839659Y315415D02*
X839712Y315088D01*
G01X847217Y314493D02*
X847583Y314272D01*
G01X846955Y314774D02*
X847217Y314493D01*
G01X846798Y315088D02*
X846955Y314774D01*
G01X846746Y315415D02*
X846798Y315088D01*
G01X854304Y314493D02*
X854670Y314272D01*
G01X854042Y314774D02*
X854304Y314493D01*
G01X853885Y315088D02*
X854042Y314774D01*
G01X853832Y315415D02*
X853885Y315088D01*
G01X861391Y314493D02*
X861756Y314272D01*
G01X861128Y314774D02*
X861391Y314493D01*
G01X860972Y315088D02*
X861128Y314774D01*
G01X860919Y315415D02*
X860972Y315088D01*
G01X847396Y314417D02*
X847583Y314272D01*
G01X847219Y314603D02*
X847396Y314417D01*
G01X847061Y314827D02*
X847219Y314603D01*
G01X846928Y315085D02*
X847061Y314827D01*
G01X846829Y315370D02*
X846928Y315085D01*
G01X846767Y315674D02*
X846829Y315370D01*
G01X846746Y315986D02*
X846767Y315674D01*
G01X854482Y314417D02*
X854670Y314272D01*
G01X854306Y314603D02*
X854482Y314417D01*
G01X854147Y314827D02*
X854306Y314603D01*
G01X854015Y315085D02*
X854147Y314827D01*
G01X853916Y315370D02*
X854015Y315085D01*
G01X853854Y315674D02*
X853916Y315370D01*
G01X853832Y315986D02*
X853854Y315674D01*
G01X861569Y314417D02*
X861756Y314272D01*
G01X861392Y314603D02*
X861569Y314417D01*
G01X861234Y314827D02*
X861392Y314603D01*
G01X861102Y315085D02*
X861234Y314827D01*
G01X861002Y315370D02*
X861102Y315085D01*
G01X860940Y315674D02*
X861002Y315370D01*
G01X860919Y315986D02*
X860940Y315674D01*
G01X828151Y314499D02*
X827778Y314272D01*
G01X828410Y314779D02*
X828151Y314499D01*
G01X828563Y315088D02*
X828410Y314779D01*
G01X828616Y315415D02*
X828563Y315088D01*
G01X835237Y314499D02*
X834865Y314272D01*
G01X835497Y314779D02*
X835237Y314499D01*
G01X835650Y315088D02*
X835497Y314779D01*
G01X835702Y315415D02*
X835650Y315088D01*
G01X842324Y314499D02*
X841952Y314272D01*
G01X842583Y314779D02*
X842324Y314499D01*
G01X842736Y315088D02*
X842583Y314779D01*
G01X842789Y315415D02*
X842736Y315088D01*
G01X849411Y314499D02*
X849038Y314272D01*
G01X849670Y314779D02*
X849411Y314499D01*
G01X849823Y315088D02*
X849670Y314779D01*
G01X849876Y315415D02*
X849823Y315088D01*
G01X856497Y314499D02*
X856125Y314272D01*
G01X856757Y314779D02*
X856497Y314499D01*
G01X856909Y315088D02*
X856757Y314779D01*
G01X856962Y315415D02*
X856909Y315088D01*
G01X828594Y315674D02*
X828616Y315986D01*
G01X828532Y315370D02*
X828594Y315674D01*
G01X828433Y315085D02*
X828532Y315370D01*
G01X828301Y314827D02*
X828433Y315085D01*
G01X828143Y314603D02*
X828301Y314827D01*
G01X827966Y314417D02*
X828143Y314603D01*
G01X827778Y314272D02*
X827966Y314417D01*
G01X835681Y315674D02*
X835702Y315986D01*
G01X835619Y315370D02*
X835681Y315674D01*
G01X835520Y315085D02*
X835619Y315370D01*
G01X835388Y314827D02*
X835520Y315085D01*
G01X835230Y314603D02*
X835388Y314827D01*
G01X835053Y314417D02*
X835230Y314603D01*
G01X834865Y314272D02*
X835053Y314417D01*
G01X842768Y315674D02*
X842789Y315986D01*
G01X842706Y315370D02*
X842768Y315674D01*
G01X842606Y315085D02*
X842706Y315370D01*
G01X842474Y314827D02*
X842606Y315085D01*
G01X842316Y314603D02*
X842474Y314827D01*
G01X842139Y314417D02*
X842316Y314603D01*
G01X841952Y314272D02*
X842139Y314417D01*
G01X849854Y315674D02*
X849876Y315986D01*
G01X849792Y315370D02*
X849854Y315674D01*
G01X849693Y315085D02*
X849792Y315370D01*
G01X849561Y314827D02*
X849693Y315085D01*
G01X849403Y314603D02*
X849561Y314827D01*
G01X849226Y314417D02*
X849403Y314603D01*
G01X849038Y314272D02*
X849226Y314417D01*
G01X856941Y315674D02*
X856962Y315986D01*
G01X856879Y315370D02*
X856941Y315674D01*
G01X856780Y315085D02*
X856879Y315370D01*
G01X856648Y314827D02*
X856780Y315085D01*
G01X856489Y314603D02*
X856648Y314827D01*
G01X856313Y314417D02*
X856489Y314603D01*
G01X856125Y314272D02*
X856313Y314417D01*
G01X827480Y315354D02*
G03I-708J0D01*
G01X861756Y314272D02*
G03X863211I727J1385D01*
G01X854670D02*
G03X856125I727J1385D01*
G01X847583D02*
G03X849038I727J1385D01*
G01X840496D02*
G03X841952I728J1385D01*
G01X833410D02*
G03X834865I727J1385D01*
G01X826323D02*
G03X827778I727J1385D01*
G01X864452Y296043D02*
G03I-1968J0D01*
G01X857366D02*
G03I-1969J0D01*
G01X850279D02*
G03I-1968J0D01*
G01X843193D02*
G03I-1969J0D01*
G01X836106D02*
G03I-1969J0D01*
G01X829019D02*
G03I-1968J0D01*
G01X862130Y322933D02*
X860948Y321752D01*
G01X855043Y322933D02*
X853862Y321752D01*
G01X847956Y322933D02*
X846775Y321752D01*
G01X840870Y322933D02*
X839689Y321752D01*
G01X833783Y322933D02*
X832602Y321752D01*
G01X826696Y322933D02*
X825515Y321752D01*
G01X860948D02*
Y318996D01*
G01X860919Y321358D02*
Y315415D01*
G01X856962Y321358D02*
Y315415D01*
G01X856933Y321752D02*
Y318996D01*
G01X853862Y321752D02*
Y318996D01*
G01X853832Y321358D02*
Y315415D01*
G01X849876Y321358D02*
Y315415D01*
G01X849846Y321752D02*
Y318996D01*
G01X846775Y321752D02*
Y318996D01*
G01X846746Y321358D02*
Y315415D01*
G01X842789Y321358D02*
Y315415D01*
G01X842759Y321752D02*
Y318996D01*
G01X839689Y321752D02*
Y318996D01*
G01X839659Y321358D02*
Y315415D01*
G01X835702Y321358D02*
Y315415D01*
G01X835673Y321752D02*
Y318996D01*
G01X832602Y321752D02*
Y318996D01*
G01X832572Y321358D02*
Y315415D01*
G01X828616Y321358D02*
Y315415D01*
G01X828586Y321752D02*
Y318996D01*
G01X825515Y321752D02*
Y318996D01*
G01X825486Y321358D02*
Y315415D01*
G01X862838Y322933D02*
X864019Y321752D01*
G01X856933D02*
X855752Y322933D01*
G01X848665D02*
X849846Y321752D01*
G01X842759D02*
X841578Y322933D01*
G01X834492D02*
X835673Y321752D01*
G01X827405Y322933D02*
X828586Y321752D01*
G01X880213Y323917D02*
X824076D01*
G01X827405Y322933D02*
X826696D01*
G01X834492D02*
X833783D01*
G01X841578D02*
X840870D01*
G01X848665D02*
X847956D01*
G01X855752D02*
X855043D01*
G01X862838D02*
X862130D01*
G01X828586Y321752D02*
X825515D01*
G01X835673D02*
X832602D01*
G01X842759D02*
X839689D01*
G01X849846D02*
X846775D01*
G01X856933D02*
X853862D01*
G01X864019D02*
X860948D01*
G01X915633Y321358D02*
X824059D01*
G01X880213Y320571D02*
X824076D01*
G01X824059Y318996D02*
X915646D01*
G01X826323Y314272D02*
X824059D01*
G01X833410D02*
X827778D01*
G01X840496D02*
X834865D01*
G01X847583D02*
X841952D01*
G01X854670D02*
X849038D01*
G01X861756D02*
X856125D01*
G01X824076Y310472D02*
X880213D01*
G01X791339Y1519685D02*
G03X787402Y1515748I0J-3937D01*
G01X817323Y1503937D02*
G03Y1496063I0J-3937D01*
G01X799213D02*
G03Y1503937I0J3937D01*
G01X791339Y1519685D02*
X980315D01*
G01X799213Y1503937D02*
X787402D01*
G01X954331D02*
X817323D01*
G01X787402Y1515748D02*
Y1503937D01*
G01X954331D02*
X817323D01*
G01X799213D02*
X787402D01*
G01X791339Y1519685D02*
G03X787402Y1515748I0J-3937D01*
G01X817323Y1503937D02*
G03Y1496063I0J-3937D01*
G01X799213D02*
G03Y1503937I0J3937D01*
G01X779528Y1515748D02*
G03X775591Y1519685I-3937J0D01*
G01X779528Y1500000D02*
Y1515748D01*
G01Y1500000D02*
G03X783465Y1496063I3937J0D01*
G01X988189D02*
X783465D01*
G01X787402Y1515748D02*
Y1503937D01*
G01X791339Y1519685D02*
X980315D01*
G01X779528Y1500000D02*
G03X783465Y1496063I3937J0D01*
G01X779528Y1515748D02*
G03X775591Y1519685I-3937J0D01*
G01X988189Y1496063D02*
X783465D01*
G01X779528Y1515748D02*
Y1500000D01*
G01X917605Y-369410D02*
Y-388347D01*
G01X900191Y0D02*
G03X892317I-3937J0D01*
G01X900191D02*
X1212598D01*
G01X900191D02*
X1212598D01*
G01X896254D02*
Y-394D01*
G01Y0D02*
Y394D01*
G01X895762Y0D02*
X896746D01*
G01X927749Y-1400D02*
Y1400D01*
G01X900191Y0D02*
G03X892317I-3937J0D01*
G01X903159Y208538D02*
X903349Y208583D01*
G01X903011Y208505D02*
X903159Y208538D01*
G01X902920Y208482D02*
X903011Y208505D01*
G01X902889Y208473D02*
X902920Y208482D01*
G01X888986Y208538D02*
X889176Y208583D01*
G01X888837Y208505D02*
X888986Y208538D01*
G01X888746Y208482D02*
X888837Y208505D01*
G01X888716Y208473D02*
X888746Y208482D01*
G01X867726Y208538D02*
X867916Y208583D01*
G01X867578Y208505D02*
X867726Y208538D01*
G01X867487Y208482D02*
X867578Y208505D01*
G01X867456Y208473D02*
X867487Y208482D01*
G01X904244Y240691D02*
X904212Y240533D01*
G01X904333Y240824D02*
X904244Y240691D01*
G01X904467Y240913D02*
X904333Y240824D01*
G01X904624Y240945D02*
X904467Y240913D01*
G01X890070Y240691D02*
X890039Y240533D01*
G01X890160Y240824D02*
X890070Y240691D01*
G01X890293Y240913D02*
X890160Y240824D01*
G01X890451Y240945D02*
X890293Y240913D01*
G01X868811Y240691D02*
X868779Y240533D01*
G01X868900Y240824D02*
X868811Y240691D01*
G01X869033Y240913D02*
X868900Y240824D01*
G01X869191Y240945D02*
X869033Y240913D01*
G01X869375Y210177D02*
X869104Y209400D01*
G01X869421Y210336D02*
X869375Y210177D01*
G01X869463Y210462D02*
X869421Y210336D01*
G01X869513Y210546D02*
X869463Y210462D01*
G01X869606Y210602D02*
X869513Y210546D01*
G01X869747Y210630D02*
X869606Y210602D01*
G01X904809Y210178D02*
X904735Y209967D01*
G01X904855Y210337D02*
X904809Y210178D01*
G01X904896Y210463D02*
X904855Y210337D01*
G01X904946Y210546D02*
X904896Y210463D01*
G01X905040Y210602D02*
X904946Y210546D01*
G01X905180Y210630D02*
X905040Y210602D01*
G01X890636Y210178D02*
X890562Y209967D01*
G01X890681Y210337D02*
X890636Y210178D01*
G01X890723Y210463D02*
X890681Y210337D01*
G01X890773Y210546D02*
X890723Y210463D01*
G01X890867Y210602D02*
X890773Y210546D01*
G01X891007Y210630D02*
X890867Y210602D01*
G01X904537Y209400D02*
X904735Y209967D01*
G01X904232Y208922D02*
X904537Y209400D01*
G01X903848Y208565D02*
X904232Y208922D01*
G01X903413Y208344D02*
X903848Y208565D01*
G01X902941Y208268D02*
X903413Y208344D01*
G01X868799Y208922D02*
X869104Y209400D01*
G01X868415Y208565D02*
X868799Y208922D01*
G01X867980Y208344D02*
X868415Y208565D01*
G01X867508Y208268D02*
X867980Y208344D01*
G01X903403Y208480D02*
X903799Y208721D01*
G01X902972Y208324D02*
X903403Y208480D01*
G01X902515Y208268D02*
X902972Y208324D01*
G01X867970Y208480D02*
X868366Y208721D01*
G01X867539Y208324D02*
X867970Y208480D01*
G01X867082Y208268D02*
X867539Y208324D01*
G01X890297Y240533D02*
X890446Y240537D01*
G01X890166Y240533D02*
X890297D01*
G01X869050Y240532D02*
X869185Y240539D01*
G01X868919Y240533D02*
X869050Y240532D01*
G01X894637Y240533D02*
X895157D01*
G01X894505D02*
X894637D01*
G01X894356Y240537D02*
X894505Y240533D01*
G01X873343Y209300D02*
X873079Y209811D01*
G01X873720Y208869D02*
X873343Y209300D01*
G01X874191Y208542D02*
X873720Y208869D01*
G01X874726Y208337D02*
X874191Y208542D01*
G01X875294Y208268D02*
X874726Y208337D01*
G01X894603Y209300D02*
X894339Y209811D01*
G01X894980Y208869D02*
X894603Y209300D01*
G01X895450Y208542D02*
X894980Y208869D01*
G01X895985Y208337D02*
X895450Y208542D01*
G01X896554Y208268D02*
X895985Y208337D01*
G01X908776Y209300D02*
X908512Y209811D01*
G01X909154Y208869D02*
X908776Y209300D01*
G01X909624Y208542D02*
X909154Y208869D01*
G01X910159Y208337D02*
X909624Y208542D01*
G01X910728Y208268D02*
X910159Y208337D01*
G01X894082Y210337D02*
X894128Y210179D01*
G01X894042Y210463D02*
X894082Y210337D01*
G01X893991Y210547D02*
X894042Y210463D01*
G01X893898Y210603D02*
X893991Y210547D01*
G01X893757Y210630D02*
X893898Y210603D01*
G01X908256Y210337D02*
X908301Y210179D01*
G01X908215Y210463D02*
X908256Y210337D01*
G01X908165Y210547D02*
X908215Y210463D01*
G01X908071Y210603D02*
X908165Y210547D01*
G01X907930Y210630D02*
X908071Y210603D01*
G01X872823Y210336D02*
X872869Y210178D01*
G01X872782Y210462D02*
X872823Y210336D01*
G01X872732Y210546D02*
X872782Y210462D01*
G01X872638Y210602D02*
X872732Y210546D01*
G01X872497Y210630D02*
X872638Y210602D01*
G01X874797Y208481D02*
X874827Y208473D01*
G01X874705Y208505D02*
X874797Y208481D01*
G01X874555Y208539D02*
X874705Y208505D01*
G01X874367Y208583D02*
X874555Y208539D01*
G01X896057Y208481D02*
X896087Y208473D01*
G01X895965Y208505D02*
X896057Y208481D01*
G01X895815Y208539D02*
X895965Y208505D01*
G01X895626Y208583D02*
X895815Y208539D01*
G01X910230Y208481D02*
X910260Y208473D01*
G01X910138Y208505D02*
X910230Y208481D01*
G01X909988Y208539D02*
X910138Y208505D01*
G01X909800Y208583D02*
X909988Y208539D01*
G01X874998Y208293D02*
X875122Y208268D01*
G01X874894Y208366D02*
X874998Y208293D01*
G01X874827Y208473D02*
X874894Y208366D01*
G01X896258Y208293D02*
X896382Y208268D01*
G01X896154Y208366D02*
X896258Y208293D01*
G01X896087Y208473D02*
X896154Y208366D01*
G01X910431Y208293D02*
X910555Y208268D01*
G01X910327Y208366D02*
X910431Y208293D01*
G01X910260Y208473D02*
X910327Y208366D01*
G01X874251Y208349D02*
X874738Y208268D01*
G01X873805Y208583D02*
X874251Y208349D01*
G01X873426Y208946D02*
X873805Y208583D01*
G01X873136Y209410D02*
X873426Y208946D01*
G01X872869Y210178D02*
X873136Y209410D01*
G01X895511Y208349D02*
X895998Y208268D01*
G01X895065Y208583D02*
X895511Y208349D01*
G01X894686Y208946D02*
X895065Y208583D01*
G01X894396Y209410D02*
X894686Y208946D01*
G01X894128Y210179D02*
X894396Y209410D01*
G01X909684Y208349D02*
X910171Y208268D01*
G01X909238Y208583D02*
X909684Y208349D01*
G01X908859Y208946D02*
X909238Y208583D01*
G01X908569Y209410D02*
X908859Y208946D01*
G01X908301Y210179D02*
X908569Y209410D01*
G01X894509Y240913D02*
X894352Y240945D01*
G01X894643Y240824D02*
X894509Y240913D01*
G01X894732Y240691D02*
X894643Y240824D01*
G01X894763Y240533D02*
X894732Y240691D01*
G01X908683Y240913D02*
X908525Y240945D01*
G01X908816Y240824D02*
X908683Y240913D01*
G01X908905Y240691D02*
X908816Y240824D01*
G01X908937Y240533D02*
X908905Y240691D01*
G01X873249Y240913D02*
X873092Y240945D01*
G01X873383Y240824D02*
X873249Y240913D01*
G01X873472Y240690D02*
X873383Y240824D01*
G01X873504Y240533D02*
X873472Y240690D01*
G01X873091Y240619D02*
X873098Y240539D01*
G01X873092Y240702D02*
X873091Y240619D01*
G01Y240785D02*
X873092Y240702D01*
G01Y240862D02*
X873091Y240785D01*
G01X869191Y240806D02*
Y241339D01*
G01Y240674D02*
Y240806D01*
G01X869185Y240539D02*
X869191Y240674D01*
G01X894351Y240687D02*
X894356Y240537D01*
G01X894352Y240818D02*
X894351Y240687D01*
G01X904624Y240818D02*
Y241339D01*
G01Y240687D02*
Y240818D01*
G01X904620Y240537D02*
X904624Y240687D01*
G01X889255Y208349D02*
X888768Y208268D01*
G01X889702Y208583D02*
X889255Y208349D01*
G01X890080Y208948D02*
X889702Y208583D01*
G01X890370Y209413D02*
X890080Y208948D01*
G01X890562Y209967D02*
X890370Y209413D01*
G01X868698Y209043D02*
X868366Y208740D01*
G01X868967Y209404D02*
X868698Y209043D01*
G01X869164Y209811D02*
X868967Y209404D01*
G01X889958Y209043D02*
X889626Y208740D01*
G01X890227Y209404D02*
X889958Y209043D01*
G01X890424Y209811D02*
X890227Y209404D01*
G01X904131Y209043D02*
X903799Y208740D01*
G01X904400Y209404D02*
X904131Y209043D01*
G01X904597Y209811D02*
X904400Y209404D01*
G01X867285Y208293D02*
X867161Y208268D01*
G01X867389Y208366D02*
X867285Y208293D01*
G01X867456Y208473D02*
X867389Y208366D01*
G01X888545Y208293D02*
X888421Y208268D01*
G01X888649Y208366D02*
X888545Y208293D01*
G01X888716Y208473D02*
X888649Y208366D01*
G01X902718Y208293D02*
X902594Y208268D01*
G01X902822Y208366D02*
X902718Y208293D01*
G01X902889Y208473D02*
X902822Y208366D01*
G01X888823Y208330D02*
X888342Y208268D01*
G01X889254Y208492D02*
X888823Y208330D01*
G01X889626Y208721D02*
X889254Y208492D01*
G01X953294Y248031D02*
G03Y240157I1J-3937D01*
G01X928098D02*
G03Y248031I0J3937D01*
G01X1051181Y240157D02*
X953294D01*
G01Y248031D02*
G03Y240157I1J-3937D01*
G01X928098D02*
G03Y248031I0J3937D01*
G01X1051181Y240157D02*
X953294D01*
G01X896539Y280866D02*
G03X895555Y279882I0J-984D01*
G01X900279D02*
G03X899295Y280866I-984J0D01*
G01X907366Y279882D02*
G03X906381Y280866I-984J0D01*
G01X903626D02*
G03X902641Y279882I-1J-984D01*
G01X910712Y280866D02*
G03X909728Y279882I0J-984D01*
G01X914452D02*
G03X913468Y280866I-984J0D01*
G01X914059Y277933D02*
G03X915633Y279508I-1J1575D01*
G01X889452Y280866D02*
G03X888468Y279882I0J-984D01*
G01X893193D02*
G03X892208Y280866I-984J0D01*
G01X871933Y279882D02*
G03X870948Y280866I-984J0D01*
G01X875279D02*
G03X874295Y279882I0J-984D01*
G01X879019D02*
G03X878035Y280866I-984J0D01*
G01X864846Y279882D02*
G03X863862Y280866I-984J0D01*
G01X868193D02*
G03X867208Y279882I-1J-984D01*
G01X891260Y262992D02*
G03I-709J0D01*
G01X912520Y253937D02*
G03I-709J0D01*
G01X877087D02*
G03I-709J0D01*
G01X871145Y276358D02*
G03X867996I-1575J0D01*
G01X878232D02*
G03X875082I-1575J0D01*
G01X885319D02*
G03X882169I-1575J0D01*
G01X892405D02*
G03X889256I-1574J0D01*
G01X899492D02*
G03X896342I-1575J0D01*
G01X906578D02*
G03X903429I-1575J0D01*
G01X912090Y277933D02*
G03X910515Y276358I0J-1575D01*
G01X905180Y240944D02*
G03X904787Y240551I0J-393D01*
G01X908323D02*
G03X907930Y240944I-393J0D01*
G01X891007D02*
G03X890613Y240551I0J-394D01*
G01X894150D02*
G03X893756Y240944I-394J-1D01*
G01X890451Y240945D02*
G03X890039Y240533I0J-412D01*
G01X894763D02*
G03X894352Y240945I-412J0D01*
G01X904624D02*
G03X904212Y240533I0J-412D01*
G01X908937D02*
G03X908525Y240945I-412J0D01*
G01X905180Y241338D02*
G03X904393Y240551I0J-787D01*
G01X908717D02*
G03X907930Y241338I-787J0D01*
G01X891007D02*
G03X890220Y240551I0J-787D01*
G01X894544D02*
G03X893756Y241338I-787J0D01*
G01X895157Y240533D02*
G03X894352Y241339I-806J0D01*
G01X890451D02*
G03X889645Y240533I0J-806D01*
G01X909330D02*
G03X908525Y241339I-806J0D01*
G01X904624D02*
G03X903819Y240533I1J-806D01*
G01X908717Y210674D02*
G03X908815Y210128I1575J1D01*
G01X909330Y212406D02*
G03X909428Y211860I1575J1D01*
G01X908323Y210674D02*
G03X908445Y209992I1969J0D01*
G01X908937Y212406D02*
G03X909059Y211723I1968J-1D01*
G01X908512Y209811D02*
G03X910728Y208268I2216J819D01*
G01X907930Y210674D02*
G03Y210630I2362J-22D01*
G01X908543Y212406D02*
G03X908689Y211587I2362J-1D01*
G01X910260Y208473D02*
G03X910555Y208268I295J110D01*
G01X904295Y210130D02*
G03X904393Y210675I-1477J547D01*
G01X894544Y210674D02*
G03X894641Y210128I1575J-2D01*
G01X895157Y212406D02*
G03X895255Y211860I1575J1D01*
G01X903721D02*
G03X903819Y212406I-1477J547D01*
G01X894763D02*
G03X894885Y211723I1969J-1D01*
G01X904665Y209993D02*
G03X904787Y210675I-1847J682D01*
G01X894150Y210674D02*
G03X894272Y209992I1969J0D01*
G01X904090Y211723D02*
G03X904212Y212406I-1846J682D01*
G01X905180Y210630D02*
G03Y210675I-2362J22D01*
G01X903799Y208740D02*
G03X904597Y209811I-1418J1889D01*
G01X894339D02*
G03X896555Y208268I2216J819D01*
G01X893756Y210674D02*
G03X893757Y210630I2362J32D01*
G01X894370Y212406D02*
G03X894516Y211587I2362J-1D01*
G01X904459D02*
G03X904606Y212406I-2215J820D01*
G01X902594Y208268D02*
G03X902889Y208473I0J315D01*
G01X896087D02*
G03X896382Y208268I295J110D01*
G01X869747Y240944D02*
G03X869354Y240551I0J-393D01*
G01X872890D02*
G03X872496Y240944I-393J0D01*
G01X869191Y240945D02*
G03X868779Y240533I0J-412D01*
G01X873504D02*
G03X873092Y240945I-412J0D01*
G01X869747Y241338D02*
G03X868960Y240551I0J-787D01*
G01X873284D02*
G03X872496Y241338I-787J0D01*
G01X873897Y240533D02*
G03X873092Y241339I-806J0D01*
G01X869191D02*
G03X868385Y240533I0J-806D01*
G01X890122Y210130D02*
G03X890220Y210675I-1477J547D01*
G01X889548Y211860D02*
G03X889645Y212406I-1478J544D01*
G01X889917Y211723D02*
G03X890039Y212406I-1847J682D01*
G01X890491Y209993D02*
G03X890613Y210675I-1846J682D01*
G01X889626Y208740D02*
G03X890424Y209811I-1418J1889D01*
G01X891007Y210630D02*
G03Y210675I-2362J22D01*
G01X890286Y211587D02*
G03X890433Y212406I-2215J820D01*
G01X888420Y208268D02*
G03X888716Y208473I1J315D01*
G01X868862Y210130D02*
G03X868960Y210675I-1477J547D01*
G01X873284Y210674D02*
G03X873381Y210128I1575J-2D01*
G01X873897Y212406D02*
G03X873995Y211860I1575J1D01*
G01X868288D02*
G03X868385Y212406I-1478J544D01*
G01X872890Y210674D02*
G03X873012Y209992I1969J0D01*
G01X869231Y209993D02*
G03X869354Y210675I-1845J685D01*
G01X868657Y211723D02*
G03X868779Y212406I-1846J682D01*
G01X873504D02*
G03X873626Y211723I1968J-1D01*
G01X872496Y210674D02*
G03X872497Y210630I2362J32D01*
G01X873079Y209811D02*
G03X875295Y208268I2216J819D01*
G01X869747Y210630D02*
G03Y210675I-2362J22D01*
G01X868366Y208740D02*
G03X869164Y209811I-1418J1889D01*
G01X869026Y211587D02*
G03X869173Y212406I-2215J820D01*
G01X873110D02*
G03X873256Y211587I2362J-1D01*
G01X874827Y208473D02*
G03X875122Y208268I295J110D01*
G01X867161D02*
G03X867456Y208473I0J315D01*
G01X910260D02*
X910639Y208583D01*
G01X896087Y208473D02*
X896466Y208583D01*
G01X874827Y208473D02*
X875206Y208583D01*
G01X908375Y209966D02*
X908815Y210128D01*
G01X908689Y211587D02*
X909428Y211860D01*
G01X894202Y209966D02*
X894641Y210128D01*
G01X894516Y211587D02*
X895255Y211860D01*
G01X872942Y209966D02*
X873381Y210128D01*
G01X873256Y211587D02*
X873995Y211860D01*
G01X904735Y209967D02*
X904597Y209811D01*
G01X890562Y209967D02*
X890424Y209811D01*
G01X869302Y209967D02*
X869164Y209811D01*
G01X902822Y208366D02*
X902889Y208473D01*
G01X888649Y208366D02*
X888716Y208473D01*
G01X867389Y208366D02*
X867456Y208473D01*
G01X910515Y259847D02*
X909137Y257461D01*
G01X903429Y259847D02*
X902051Y257461D01*
G01X911342Y275186D02*
X910555Y273822D01*
G01X896342Y259847D02*
X894964Y257461D01*
G01X904256Y274765D02*
X903468Y273401D01*
G01X889256Y259847D02*
X887878Y257461D01*
G01X897169Y275186D02*
X896381Y273822D01*
G01X882169Y259847D02*
X880791Y257461D01*
G01X890082Y274765D02*
X889295Y273401D01*
G01X875082Y259847D02*
X873704Y257461D01*
G01X867996Y259847D02*
X866618Y257461D01*
G01X875909Y275186D02*
X875122Y273822D01*
G01X868822Y274765D02*
X868035Y273401D01*
G01X904597Y209811D02*
X904665Y209993D01*
G01X904295Y210130D02*
X903799Y208786D01*
G01X904459Y211587D02*
X903349Y208583D01*
G01X904090Y211723D02*
X902889Y208473D01*
G01X902510Y208583D02*
X903721Y211860D01*
G01X890491Y209993D02*
X890424Y209811D01*
G01X890122Y210130D02*
X889626Y208786D01*
G01X890286Y211587D02*
X889176Y208583D01*
G01X889917Y211723D02*
X888716Y208473D01*
G01X888337Y208583D02*
X889548Y211860D01*
G01X869231Y209993D02*
X869164Y209811D01*
G01X868862Y210130D02*
X868366Y208786D01*
G01X869026Y211587D02*
X867916Y208583D01*
G01X868657Y211723D02*
X867456Y208473D01*
G01X867077Y208583D02*
X868288Y211860D01*
G01X916135Y246850D02*
Y208268D01*
G01X915646Y323917D02*
Y235204D01*
G01X915633Y279508D02*
Y321358D01*
G01X915250Y216142D02*
Y208268D01*
G01X914452Y279882D02*
Y256457D01*
G01X913626Y273822D02*
Y256457D01*
G01X910722Y216142D02*
Y208268D01*
G01X910639Y208583D02*
Y208268D01*
G01X910555Y273822D02*
Y256457D01*
G01X910515Y276358D02*
Y259847D01*
G01X909800Y208583D02*
Y208268D01*
G01X909728Y279882D02*
Y256457D01*
G01X909330Y212406D02*
Y240533D01*
G01X908937D02*
Y212406D01*
G01X908717Y240551D02*
Y210674D01*
G01X908543Y212406D02*
Y240533D01*
G01X908525Y240551D02*
Y241339D01*
G01X908323Y240551D02*
Y210674D01*
G01X907930Y208268D02*
Y210630D01*
G01Y210674D02*
Y241338D01*
G01X907366Y279882D02*
Y256457D01*
G01X906578Y259847D02*
Y276358D01*
G01X906539Y273401D02*
Y256457D01*
G01X905180Y210675D02*
Y241338D01*
G01Y208268D02*
Y210630D01*
G01X904787Y240551D02*
Y210675D01*
G01X904606Y212406D02*
Y240533D01*
G01X904393Y210675D02*
Y240551D01*
G01X904212Y240533D02*
Y212406D01*
G01X903819Y240533D02*
Y212406D01*
G01X903799Y208721D02*
Y216142D01*
G01X903468Y273401D02*
Y256457D01*
G01X903429Y276358D02*
Y259847D01*
G01X903349Y208583D02*
Y208268D01*
G01X902641Y279882D02*
Y256457D01*
G01X902510Y208583D02*
Y208268D01*
G01X901437Y216142D02*
Y208268D01*
G01X901076Y216142D02*
Y208268D01*
G01X900279Y256457D02*
Y279882D01*
G01X899492Y259847D02*
Y276358D01*
G01X899452Y273822D02*
Y256457D01*
G01X896549Y208268D02*
Y216142D01*
G01X896466Y208583D02*
Y208268D01*
G01X896381Y256457D02*
Y273822D01*
G01X896342Y276358D02*
Y259847D01*
G01X915640Y279508D02*
X915646Y256457D01*
G01X894352Y241339D02*
Y240818D01*
G01X873092Y241339D02*
Y240862D01*
G01X869173Y212406D02*
X869180Y240543D01*
G01X895626Y208583D02*
Y208268D01*
G01X895555Y279882D02*
Y256457D01*
G01X895157Y212406D02*
Y240533D01*
G01X894763D02*
Y212406D01*
G01X894544Y240551D02*
Y210674D01*
G01X894370Y240533D02*
Y212406D01*
G01X894150Y240551D02*
Y210674D01*
G01X893757Y208268D02*
Y210630D01*
G01X893756Y210674D02*
Y241338D01*
G01X893193Y256457D02*
Y279882D01*
G01X892405Y259847D02*
Y276358D01*
G01X892366Y273401D02*
Y256457D01*
G01X891007Y241338D02*
Y210675D01*
G01Y210630D02*
Y208268D01*
G01X890613Y240551D02*
Y210675D01*
G01X890451Y240551D02*
Y241339D01*
G01X890433Y212406D02*
Y240533D01*
G01X890220Y210675D02*
Y240551D01*
G01X890039Y240533D02*
Y212406D01*
G01X889645Y240533D02*
Y212406D01*
G01X889626Y208721D02*
Y216142D01*
G01X889295Y256457D02*
Y273401D01*
G01X889256Y276358D02*
Y259847D01*
G01X889176Y208583D02*
Y208268D01*
G01X888468Y279882D02*
Y256457D01*
G01X888337Y208583D02*
Y208268D01*
G01X888183Y246850D02*
Y208268D01*
G01X887855Y323917D02*
Y235204D01*
G01X885319Y259847D02*
Y276358D01*
G01X882169D02*
Y259847D01*
G01X880702Y246850D02*
Y208268D01*
G01X880213Y323917D02*
Y235204D01*
G01X879817Y216142D02*
Y208268D01*
G01X879019Y279882D02*
Y256457D01*
G01X878232Y259847D02*
Y276358D01*
G01X878193Y273822D02*
Y256457D01*
G01X875289Y216142D02*
Y208268D01*
G01X875206Y208583D02*
Y208268D01*
G01X875122Y273822D02*
Y256457D01*
G01X875082Y276358D02*
Y259847D01*
G01X874367Y208583D02*
Y208268D01*
G01X874295Y279882D02*
Y256457D01*
G01X873897Y212406D02*
Y240533D01*
G01X873504D02*
Y212406D01*
G01X873284Y240551D02*
Y210674D01*
G01X873110Y212406D02*
Y240533D01*
G01X872890Y240551D02*
Y210674D01*
G01X872497Y208268D02*
Y210630D01*
G01X872496Y210674D02*
Y241338D01*
G01X871933Y279882D02*
Y256457D01*
G01X871145Y259847D02*
Y276358D01*
G01X871106Y273401D02*
Y256457D01*
G01X869747Y210675D02*
Y241338D01*
G01Y208268D02*
Y210630D01*
G01X869354Y240551D02*
Y210675D01*
G01X868960D02*
Y240551D01*
G01X868779Y240533D02*
Y212406D01*
G01X868385Y240533D02*
Y212406D01*
G01X868366Y208721D02*
Y216142D01*
G01X868035Y273401D02*
Y256457D01*
G01X867996Y276358D02*
Y259847D01*
G01X867916Y208583D02*
Y208268D01*
G01X867208Y279882D02*
Y256457D01*
G01X867077Y208583D02*
Y208268D01*
G01X866004Y216142D02*
Y208268D01*
G01X865643Y216142D02*
Y208268D01*
G01X864846Y256457D02*
Y279882D01*
G01X864059Y259847D02*
Y276358D01*
G01X864019Y273822D02*
Y256457D01*
G01X909428Y211860D02*
X910639Y208583D01*
G01X909059Y211723D02*
X910260Y208473D01*
G01X909800Y208583D02*
X908689Y211587D01*
G01X909334Y208722D02*
X908815Y210128D01*
G01X908445Y209992D02*
X908512Y209811D01*
G01X895255Y211860D02*
X896466Y208583D01*
G01X894885Y211723D02*
X896087Y208473D01*
G01X895626Y208583D02*
X894516Y211587D01*
G01X895161Y208722D02*
X894641Y210128D01*
G01X894272Y209992D02*
X894339Y209811D01*
G01X873995Y211860D02*
X875206Y208583D01*
G01X873626Y211723D02*
X874827Y208473D01*
G01X874367Y208583D02*
X873256Y211587D01*
G01X873901Y208722D02*
X873381Y210128D01*
G01X873012Y209992D02*
X873079Y209811D01*
G01X912838Y275186D02*
X913626Y273822D01*
G01X905752Y274765D02*
X906539Y273401D01*
G01X898665Y275186D02*
X899452Y273822D01*
G01X907956Y257461D02*
X906578Y259847D01*
G01X891578Y274765D02*
X892366Y273401D01*
G01X900870Y257461D02*
X899492Y259847D01*
G01X893783Y257461D02*
X892405Y259847D01*
G01X877405Y275186D02*
X878193Y273822D01*
G01X885319Y259847D02*
X886696Y257461D01*
G01X870319Y274765D02*
X871106Y273401D01*
G01X879610Y257461D02*
X878232Y259847D01*
G01X863232Y275186D02*
X864019Y273822D01*
G01X872523Y257461D02*
X871145Y259847D01*
G01X865437Y257461D02*
X864059Y259847D01*
G01X910327Y208366D02*
X910260Y208473D01*
G01X896154Y208366D02*
X896087Y208473D01*
G01X874894Y208366D02*
X874827Y208473D01*
G01X908375Y209966D02*
X908512Y209811D01*
G01X894202Y209966D02*
X894339Y209811D01*
G01X872942Y209966D02*
X873079Y209811D01*
G01X903721Y211860D02*
X904459Y211587D01*
G01X904295Y210130D02*
X904735Y209967D01*
G01X889548Y211860D02*
X890286Y211587D01*
G01X890122Y210130D02*
X890562Y209967D01*
G01X868288Y211860D02*
X869026Y211587D01*
G01X869302Y209967D02*
X868862Y210130D01*
G01X902510Y208583D02*
X902889Y208473D01*
G01X888337Y208583D02*
X888716Y208473D01*
G01X867077Y208583D02*
X867456Y208473D01*
G01X868385Y240533D02*
X868919D01*
G01X889645D02*
X890166D01*
G01X870948Y280866D02*
X868193D01*
G01X878035D02*
X875279D01*
G01X892208D02*
X889452D01*
G01X899295D02*
X896539D01*
G01X906381D02*
X903626D01*
G01X913468D02*
X910712D01*
G01X902641Y278343D02*
X907366D01*
G01X867208D02*
X871933D01*
G01X879019D02*
X874295D01*
G01X893193D02*
X888468D01*
G01X900279D02*
X895555D01*
G01X914452D02*
X909728D01*
G01X914059Y277933D02*
X912090D01*
G01X877405Y275186D02*
X875909D01*
G01X898665D02*
X897169D01*
G01X912838D02*
X911342D01*
G01X870319Y274765D02*
X868822D01*
G01X891578D02*
X890082D01*
G01X905752D02*
X904256D01*
G01X866618Y257461D02*
X865437D01*
G01X873704D02*
X872523D01*
G01X880791D02*
X879610D01*
G01X887878D02*
X886696D01*
G01X894964D02*
X893783D01*
G01X902051D02*
X900870D01*
G01X909137D02*
X907956D01*
G01X899452Y256457D02*
X903468D01*
G01X892366D02*
X896381D01*
G01X887855D02*
X889295D01*
G01X864019D02*
X868035D01*
G01X875122D02*
X871106D01*
G01X880213D02*
X878193D01*
G01X910555D02*
X906539D01*
G01X915646D02*
X913626D01*
G01X915646Y253274D02*
X887855D01*
G01X915646Y248944D02*
X887855D01*
G01Y246850D02*
X916135D01*
G01X888183Y246260D02*
X916135D01*
G01X888183Y243638D02*
X916135D01*
G01X888183Y243441D02*
X916135D01*
G01X873092Y241339D02*
X869191D01*
G01X894352D02*
X890451D01*
G01X908525D02*
X904624D01*
G01X873092Y240945D02*
X869191D01*
G01X894352D02*
X890451D01*
G01X908525D02*
X904624D01*
G01X904393Y240551D02*
X908717D01*
G01X890220D02*
X894544D01*
G01X868960D02*
X873284D01*
G01X869180Y240543D02*
X873110D01*
G01X908543Y240533D02*
X909330D01*
G01X903819D02*
X904606D01*
G01X873110D02*
X873897D01*
G01X915646Y235204D02*
X916135D01*
G01X880213D02*
X880702D01*
G01X888183D02*
X887855D01*
G01X901437Y216142D02*
X903799D01*
G01X896549D02*
X901076D01*
G01X888183D02*
X889626D01*
G01X866004D02*
X868366D01*
G01X879817D02*
X875289D01*
G01X915250D02*
X910722D01*
G01X908543Y212406D02*
X909330D01*
G01X894370D02*
X895157D01*
G01X873110D02*
X873897D01*
G01X869173D02*
X868385D01*
G01X890433D02*
X889645D01*
G01X904606D02*
X903819D01*
G01X904393Y210675D02*
X905180D01*
G01X868960D02*
X869747D01*
G01X891007D02*
X890220D01*
G01X907930Y210674D02*
X908717D01*
G01X893756D02*
X894544D01*
G01X872496D02*
X873284D01*
G01X872497Y210630D02*
X869747D01*
G01X893757D02*
X891007D01*
G01X907930D02*
X905180D01*
G01X910722Y208756D02*
X915250D01*
G01X896549D02*
X901076D01*
G01X875289D02*
X879817D01*
G01X901437D02*
X903799D01*
G01X866004D02*
X868366D01*
G01X889626D02*
X888183D01*
G01X889176Y208583D02*
X902510D01*
G01X867916D02*
X880702D01*
G01X903349D02*
X916135D01*
G01X888183D02*
X888337D01*
G01X916135Y208268D02*
X888183D01*
G01X868477Y314493D02*
X868843Y314272D01*
G01X868215Y314774D02*
X868477Y314493D01*
G01X868058Y315088D02*
X868215Y314774D01*
G01X868006Y315415D02*
X868058Y315088D01*
G01X875564Y314493D02*
X875930Y314272D01*
G01X875302Y314774D02*
X875564Y314493D01*
G01X875145Y315088D02*
X875302Y314774D01*
G01X875092Y315415D02*
X875145Y315088D01*
G01X882650Y314493D02*
X883016Y314272D01*
G01X882388Y314774D02*
X882650Y314493D01*
G01X882231Y315088D02*
X882388Y314774D01*
G01X882179Y315415D02*
X882231Y315088D01*
G01X868656Y314417D02*
X868843Y314272D01*
G01X868479Y314603D02*
X868656Y314417D01*
G01X868320Y314827D02*
X868479Y314603D01*
G01X868188Y315085D02*
X868320Y314827D01*
G01X868089Y315370D02*
X868188Y315085D01*
G01X868027Y315674D02*
X868089Y315370D01*
G01X868006Y315986D02*
X868027Y315674D01*
G01X875742Y314417D02*
X875930Y314272D01*
G01X875565Y314603D02*
X875742Y314417D01*
G01X875407Y314827D02*
X875565Y314603D01*
G01X875275Y315085D02*
X875407Y314827D01*
G01X875176Y315370D02*
X875275Y315085D01*
G01X875113Y315674D02*
X875176Y315370D01*
G01X875092Y315986D02*
X875113Y315674D01*
G01X882829Y314417D02*
X883016Y314272D01*
G01X882652Y314603D02*
X882829Y314417D01*
G01X882494Y314827D02*
X882652Y314603D01*
G01X882361Y315085D02*
X882494Y314827D01*
G01X882262Y315370D02*
X882361Y315085D01*
G01X882200Y315674D02*
X882262Y315370D01*
G01X882179Y315986D02*
X882200Y315674D01*
G01X889915Y314417D02*
X890103Y314272D01*
G01X889739Y314603D02*
X889915Y314417D01*
G01X889580Y314827D02*
X889739Y314603D01*
G01X889448Y315085D02*
X889580Y314827D01*
G01X889349Y315370D02*
X889448Y315085D01*
G01X889287Y315674D02*
X889349Y315370D01*
G01X889265Y315986D02*
X889287Y315674D01*
G01X897002Y314417D02*
X897189Y314272D01*
G01X896825Y314603D02*
X897002Y314417D01*
G01X896667Y314827D02*
X896825Y314603D01*
G01X896535Y315085D02*
X896667Y314827D01*
G01X896435Y315370D02*
X896535Y315085D01*
G01X896373Y315674D02*
X896435Y315370D01*
G01X896352Y315986D02*
X896373Y315674D01*
G01X904089Y314417D02*
X904276Y314272D01*
G01X903912Y314603D02*
X904089Y314417D01*
G01X903754Y314827D02*
X903912Y314603D01*
G01X903621Y315085D02*
X903754Y314827D01*
G01X903522Y315370D02*
X903621Y315085D01*
G01X903460Y315674D02*
X903522Y315370D01*
G01X903439Y315986D02*
X903460Y315674D01*
G01X911175Y314417D02*
X911363Y314272D01*
G01X910998Y314603D02*
X911175Y314417D01*
G01X910840Y314827D02*
X910998Y314603D01*
G01X910708Y315085D02*
X910840Y314827D01*
G01X910609Y315370D02*
X910708Y315085D01*
G01X910546Y315674D02*
X910609Y315370D01*
G01X910525Y315986D02*
X910546Y315674D01*
G01X889737Y314493D02*
X890103Y314272D01*
G01X889475Y314774D02*
X889737Y314493D01*
G01X889318Y315088D02*
X889475Y314774D01*
G01X889265Y315415D02*
X889318Y315088D01*
G01X896824Y314493D02*
X897189Y314272D01*
G01X896561Y314774D02*
X896824Y314493D01*
G01X896405Y315088D02*
X896561Y314774D01*
G01X896352Y315415D02*
X896405Y315088D01*
G01X903910Y314493D02*
X904276Y314272D01*
G01X903648Y314774D02*
X903910Y314493D01*
G01X903491Y315088D02*
X903648Y314774D01*
G01X903439Y315415D02*
X903491Y315088D01*
G01X910997Y314493D02*
X911363Y314272D01*
G01X910735Y314774D02*
X910997Y314493D01*
G01X910578Y315088D02*
X910735Y314774D01*
G01X910525Y315415D02*
X910578Y315088D01*
G01X863584Y314499D02*
X863211Y314272D01*
G01X863843Y314779D02*
X863584Y314499D01*
G01X863996Y315088D02*
X863843Y314779D01*
G01X864049Y315415D02*
X863996Y315088D01*
G01X870670Y314499D02*
X870298Y314272D01*
G01X870930Y314779D02*
X870670Y314499D01*
G01X871083Y315088D02*
X870930Y314779D01*
G01X871135Y315415D02*
X871083Y315088D01*
G01X877757Y314499D02*
X877385Y314272D01*
G01X878017Y314779D02*
X877757Y314499D01*
G01X878169Y315088D02*
X878017Y314779D01*
G01X878222Y315415D02*
X878169Y315088D01*
G01X884844Y314499D02*
X884471Y314272D01*
G01X885103Y314779D02*
X884844Y314499D01*
G01X885256Y315088D02*
X885103Y314779D01*
G01X885309Y315415D02*
X885256Y315088D01*
G01X891930Y314499D02*
X891558Y314272D01*
G01X892190Y314779D02*
X891930Y314499D01*
G01X892343Y315088D02*
X892190Y314779D01*
G01X892395Y315415D02*
X892343Y315088D01*
G01X899017Y314499D02*
X898644Y314272D01*
G01X899276Y314779D02*
X899017Y314499D01*
G01X899429Y315088D02*
X899276Y314779D01*
G01X899482Y315415D02*
X899429Y315088D01*
G01X906104Y314499D02*
X905731Y314272D01*
G01X906363Y314779D02*
X906104Y314499D01*
G01X906516Y315088D02*
X906363Y314779D01*
G01X906569Y315415D02*
X906516Y315088D01*
G01X913190Y314499D02*
X912818Y314272D01*
G01X913450Y314779D02*
X913190Y314499D01*
G01X913602Y315088D02*
X913450Y314779D01*
G01X913655Y315415D02*
X913602Y315088D01*
G01X864028Y315674D02*
X864049Y315986D01*
G01X863965Y315370D02*
X864028Y315674D01*
G01X863866Y315085D02*
X863965Y315370D01*
G01X863734Y314827D02*
X863866Y315085D01*
G01X863576Y314603D02*
X863734Y314827D01*
G01X863399Y314417D02*
X863576Y314603D01*
G01X863211Y314272D02*
X863399Y314417D01*
G01X871114Y315674D02*
X871135Y315986D01*
G01X871052Y315370D02*
X871114Y315674D01*
G01X870953Y315085D02*
X871052Y315370D01*
G01X870821Y314827D02*
X870953Y315085D01*
G01X870663Y314603D02*
X870821Y314827D01*
G01X870486Y314417D02*
X870663Y314603D01*
G01X870298Y314272D02*
X870486Y314417D01*
G01X878201Y315674D02*
X878222Y315986D01*
G01X878139Y315370D02*
X878201Y315674D01*
G01X878039Y315085D02*
X878139Y315370D01*
G01X877907Y314827D02*
X878039Y315085D01*
G01X877749Y314603D02*
X877907Y314827D01*
G01X877572Y314417D02*
X877749Y314603D01*
G01X877385Y314272D02*
X877572Y314417D01*
G01X885287Y315674D02*
X885309Y315986D01*
G01X885225Y315370D02*
X885287Y315674D01*
G01X885126Y315085D02*
X885225Y315370D01*
G01X884994Y314827D02*
X885126Y315085D01*
G01X884836Y314603D02*
X884994Y314827D01*
G01X884659Y314417D02*
X884836Y314603D01*
G01X884471Y314272D02*
X884659Y314417D01*
G01X892374Y315674D02*
X892395Y315986D01*
G01X892312Y315370D02*
X892374Y315674D01*
G01X892213Y315085D02*
X892312Y315370D01*
G01X892081Y314827D02*
X892213Y315085D01*
G01X891922Y314603D02*
X892081Y314827D01*
G01X891746Y314417D02*
X891922Y314603D01*
G01X891558Y314272D02*
X891746Y314417D01*
G01X899461Y315674D02*
X899482Y315986D01*
G01X899398Y315370D02*
X899461Y315674D01*
G01X899299Y315085D02*
X899398Y315370D01*
G01X899167Y314827D02*
X899299Y315085D01*
G01X899009Y314603D02*
X899167Y314827D01*
G01X898832Y314417D02*
X899009Y314603D01*
G01X898644Y314272D02*
X898832Y314417D01*
G01X906547Y315674D02*
X906569Y315986D01*
G01X906485Y315370D02*
X906547Y315674D01*
G01X906386Y315085D02*
X906485Y315370D01*
G01X906254Y314827D02*
X906386Y315085D01*
G01X906096Y314603D02*
X906254Y314827D01*
G01X905919Y314417D02*
X906096Y314603D01*
G01X905731Y314272D02*
X905919Y314417D01*
G01X913634Y315674D02*
X913655Y315986D01*
G01X913572Y315370D02*
X913634Y315674D01*
G01X913472Y315085D02*
X913572Y315370D01*
G01X913341Y314827D02*
X913472Y315085D01*
G01X913182Y314603D02*
X913341Y314827D01*
G01X913006Y314417D02*
X913182Y314603D01*
G01X912818Y314272D02*
X913006Y314417D01*
G01X891260Y315354D02*
G03I-709J0D01*
G01X912520Y310630D02*
G03I-709J0D01*
G01X877087D02*
G03I-709J0D01*
G01X911363Y314272D02*
G03X912818I728J1385D01*
G01X904276D02*
G03X905731I727J1385D01*
G01X897189D02*
G03X898644I728J1385D01*
G01X890103D02*
G03X891558I727J1385D01*
G01X883016D02*
G03X884471I727J1385D01*
G01X875930D02*
G03X877385I728J1385D01*
G01X914059Y296043D02*
G03I-1969J0D01*
G01X906972D02*
G03I-1968J0D01*
G01X899885D02*
G03I-1968J0D01*
G01X885712D02*
G03I-1968J0D01*
G01X892799D02*
G03I-1969J0D01*
G01X878626D02*
G03I-1969J0D01*
G01X868843Y314272D02*
G03X870298I727J1385D01*
G01X871539Y296043D02*
G03I-1968J0D01*
G01X911736Y322933D02*
X910555Y321752D01*
G01X904649Y322933D02*
X903468Y321752D01*
G01X897563Y322933D02*
X896381Y321752D01*
G01X890476Y322933D02*
X889295Y321752D01*
G01X876303Y322933D02*
X875122Y321752D01*
G01X869216Y322933D02*
X868035Y321752D01*
G01X913655Y321358D02*
Y315415D01*
G01X913626Y321752D02*
Y318996D01*
G01X910555Y321752D02*
Y318996D01*
G01X910525Y321358D02*
Y315415D01*
G01X906569Y321358D02*
Y315415D01*
G01X906539Y321752D02*
Y318996D01*
G01X903468Y321752D02*
Y318996D01*
G01X903439Y321358D02*
Y315415D01*
G01X899482Y321358D02*
Y315415D01*
G01X899452Y321752D02*
Y318996D01*
G01X896381Y321752D02*
Y318996D01*
G01X896352Y321358D02*
Y315415D01*
G01X892395Y321358D02*
Y315415D01*
G01X892366Y321752D02*
Y318996D01*
G01X889295Y321752D02*
Y318996D01*
G01X889265Y321358D02*
Y315415D01*
G01X885309Y321358D02*
Y315415D01*
G01X882179Y321358D02*
Y315415D01*
G01X878222Y321358D02*
Y315415D01*
G01X878193Y321752D02*
Y318996D01*
G01X875122Y321752D02*
Y318996D01*
G01X875092Y321358D02*
Y315415D01*
G01X871135Y321358D02*
Y315415D01*
G01X871106Y321752D02*
Y318996D01*
G01X868035Y321752D02*
Y318996D01*
G01X868006Y321358D02*
Y315415D01*
G01X864049Y321358D02*
Y315415D01*
G01X864019Y321752D02*
Y318996D01*
G01X912444Y322933D02*
X913626Y321752D01*
G01X906539D02*
X905358Y322933D01*
G01X898271D02*
X899452Y321752D01*
G01X891185Y322933D02*
X892366Y321752D01*
G01X877011Y322933D02*
X878193Y321752D01*
G01X871106D02*
X869925Y322933D01*
G01X915646Y323917D02*
X887855D01*
G01X869925Y322933D02*
X869216D01*
G01X877011D02*
X876303D01*
G01X891185D02*
X890476D01*
G01X898271D02*
X897563D01*
G01X905358D02*
X904649D01*
G01X912444D02*
X911736D01*
G01X871106Y321752D02*
X868035D01*
G01X878193D02*
X875122D01*
G01X892366D02*
X889295D01*
G01X899452D02*
X896381D01*
G01X906539D02*
X903468D01*
G01X913626D02*
X910555D01*
G01X915646Y320571D02*
X887855D01*
G01X868843Y314272D02*
X863211D01*
G01X875930D02*
X870298D01*
G01X883016D02*
X877385D01*
G01X890103D02*
X884471D01*
G01X897189D02*
X891558D01*
G01X904276D02*
X898644D01*
G01X911363D02*
X905731D01*
G01X915633D02*
X912818D01*
G01X887855Y310472D02*
X915646D01*
G01X944512Y705657D02*
G03X978323I16905J-13531D01*
G01X971398Y718788D02*
G03X951437I-9980J-3040D01*
G01X944512Y705657D02*
G03X951437Y718788I-30737J24602D01*
G01X971398D02*
G03X951437I-9980J-3040D01*
G01X944512Y705657D02*
G03X978323I16905J-13531D01*
G01X944512D02*
G03X951437Y718788I-30737J24602D01*
G01X944512Y974161D02*
G03X978323I16905J-13531D01*
G01X944512D02*
G03X978323I16905J-13531D01*
G01X971398Y987292D02*
G03X951437I-9980J-3040D01*
G01X944512Y974161D02*
G03X951437Y987292I-30737J24602D01*
G01X971398D02*
G03X951437I-9980J-3040D01*
G01X944512Y974161D02*
G03X951437Y987292I-30737J24602D01*
G01X889930Y1511515D02*
G03I-4291J0D01*
G01D02*
G03I-4291J0D01*
G01X954331Y1496063D02*
G03Y1503937I0J3937D01*
G01Y1496063D02*
G03Y1503937I0J3937D01*
G01X917605Y1808346D02*
Y1789409D01*
G01X1022235Y-1400D02*
Y1400D01*
G01X990739Y-1400D02*
Y1400D01*
G01X959244Y-1400D02*
Y1400D01*
G01X1051181Y193701D02*
G03X1062992Y181890I11811J0D01*
G01X1051181Y193701D02*
G03X1062992Y181890I11811J0D01*
G01X991233Y282141D02*
X991257Y282034D01*
G01X991218Y282226D02*
X991233Y282141D01*
G01X991215Y282302D02*
X991218Y282226D01*
G01X991229Y282328D02*
X991215Y282302D01*
G01X991257Y282313D02*
X991229Y282328D01*
G01X969397Y252648D02*
X969373Y252756D01*
G01X969412Y252564D02*
X969397Y252648D01*
G01X969415Y252487D02*
X969412Y252564D01*
G01X969401Y252463D02*
X969415Y252487D01*
G01X969373Y252478D02*
X969401Y252463D01*
G01X997744Y252648D02*
X997719Y252756D01*
G01X997758Y252564D02*
X997744Y252648D01*
G01X997761Y252487D02*
X997758Y252564D01*
G01X997748Y252463D02*
X997761Y252487D01*
G01X997719Y252478D02*
X997748Y252463D01*
G01X1026090Y252648D02*
X1026066Y252756D01*
G01X1026105Y252564D02*
X1026090Y252648D01*
G01X1026107Y252487D02*
X1026105Y252564D01*
G01X1026094Y252463D02*
X1026107Y252487D01*
G01X1026066Y252478D02*
X1026094Y252463D01*
G01X1019579Y282141D02*
X1019604Y282034D01*
G01X1019565Y282226D02*
X1019579Y282141D01*
G01X1019562Y282302D02*
X1019565Y282226D01*
G01X1019576Y282328D02*
X1019562Y282302D01*
G01X1019604Y282313D02*
X1019576Y282328D01*
G01X1047926Y282141D02*
X1047950Y282034D01*
G01X1047911Y282226D02*
X1047926Y282141D01*
G01X1047908Y282302D02*
X1047911Y282226D01*
G01X1047922Y282328D02*
X1047908Y282302D01*
G01X1047950Y282313D02*
X1047922Y282328D01*
G01X968085Y253817D02*
X968084Y253841D01*
G01X968089Y253795D02*
X968085Y253817D01*
G01X968095Y253774D02*
X968089Y253795D01*
G01X968104Y253756D02*
X968095Y253774D01*
G01X968114Y253738D02*
X968104Y253756D01*
G01X968127Y253723D02*
X968114Y253738D01*
G01X992544Y280974D02*
X992546Y280949D01*
G01X992541Y280996D02*
X992544Y280974D01*
G01X992535Y281017D02*
X992541Y280996D01*
G01X992526Y281035D02*
X992535Y281017D01*
G01X992515Y281052D02*
X992526Y281035D01*
G01X992503Y281067D02*
X992515Y281052D01*
G01X1020891Y280974D02*
X1020893Y280949D01*
G01X1020887Y280996D02*
X1020891Y280974D01*
G01X1020881Y281017D02*
X1020887Y280996D01*
G01X1020872Y281035D02*
X1020881Y281017D01*
G01X1020862Y281052D02*
X1020872Y281035D01*
G01X1020849Y281067D02*
X1020862Y281052D01*
G01X1049237Y280974D02*
X1049239Y280949D01*
G01X1049234Y280996D02*
X1049237Y280974D01*
G01X1049228Y281017D02*
X1049234Y280996D01*
G01X1049219Y281035D02*
X1049228Y281017D01*
G01X1049208Y281052D02*
X1049219Y281035D01*
G01X1049196Y281067D02*
X1049208Y281052D01*
G01X996432Y253817D02*
X996431Y253841D01*
G01X996435Y253795D02*
X996432Y253817D01*
G01X996441Y253774D02*
X996435Y253795D01*
G01X996450Y253756D02*
X996441Y253774D01*
G01X996461Y253738D02*
X996450Y253756D01*
G01X996474Y253723D02*
X996461Y253738D01*
G01X1024778Y253817D02*
X1024777Y253841D01*
G01X1024782Y253795D02*
X1024778Y253817D01*
G01X1024788Y253774D02*
X1024782Y253795D01*
G01X1024796Y253756D02*
X1024788Y253774D01*
G01X1024807Y253738D02*
X1024796Y253756D01*
G01X1024820Y253723D02*
X1024807Y253738D01*
G01X991172Y282440D02*
X991142Y282590D01*
G01X991257Y282313D02*
X991172Y282440D01*
G01X969458Y252350D02*
X969488Y252199D01*
G01X969373Y252478D02*
X969458Y252350D01*
G01X997805D02*
X997835Y252199D01*
G01X997719Y252478D02*
X997805Y252350D01*
G01X968085Y253774D02*
X968127Y253723D01*
G01X968054Y253826D02*
X968085Y253774D01*
G01X996431D02*
X996474Y253723D01*
G01X996400Y253826D02*
X996431Y253774D01*
G01X1019519Y282440D02*
X1019488Y282590D01*
G01X1019604Y282313D02*
X1019519Y282440D01*
G01X1047865D02*
X1047835Y282590D01*
G01X1047950Y282313D02*
X1047865Y282440D01*
G01X1026151Y252350D02*
X1026181Y252199D01*
G01X1026066Y252478D02*
X1026151Y252350D01*
G01X992546Y281016D02*
X992503Y281067D01*
G01X992577Y280965D02*
X992546Y281016D01*
G01X1024778Y253774D02*
X1024820Y253723D01*
G01X1024746Y253826D02*
X1024778Y253774D01*
G01X1020892Y281016D02*
X1020849Y281067D01*
G01X1020923Y280965D02*
X1020892Y281016D01*
G01X1049239D02*
X1049196Y281067D01*
G01X1049270Y280965D02*
X1049239Y281016D01*
G01X992544Y253867D02*
X992546Y253841D01*
G01X992541Y253893D02*
X992544Y253867D01*
G01X992535Y253919D02*
X992541Y253893D01*
G01X992526Y253947D02*
X992535Y253919D01*
G01X992515Y253975D02*
X992526Y253947D01*
G01X992503Y254002D02*
X992515Y253975D01*
G01X1020891Y253867D02*
X1020893Y253841D01*
G01X1020887Y253893D02*
X1020891Y253867D01*
G01X1020881Y253919D02*
X1020887Y253893D01*
G01X1020872Y253947D02*
X1020881Y253919D01*
G01X1020862Y253975D02*
X1020872Y253947D01*
G01X1020849Y254002D02*
X1020862Y253975D01*
G01X968085Y280924D02*
X968084Y280949D01*
G01X968089Y280898D02*
X968085Y280924D01*
G01X968095Y280872D02*
X968089Y280898D01*
G01X968104Y280844D02*
X968095Y280872D01*
G01X968114Y280817D02*
X968104Y280844D01*
G01X968127Y280789D02*
X968114Y280817D01*
G01X996432Y280924D02*
X996431Y280949D01*
G01X996435Y280898D02*
X996432Y280924D01*
G01X996441Y280872D02*
X996435Y280898D01*
G01X996450Y280844D02*
X996441Y280872D01*
G01X996461Y280817D02*
X996450Y280844D01*
G01X996474Y280789D02*
X996461Y280817D01*
G01X1049237Y253867D02*
X1049239Y253841D01*
G01X1049234Y253893D02*
X1049237Y253867D01*
G01X1049228Y253919D02*
X1049234Y253893D01*
G01X1049219Y253947D02*
X1049228Y253919D01*
G01X1049208Y253975D02*
X1049219Y253947D01*
G01X1049196Y254002D02*
X1049208Y253975D01*
G01X1024778Y280924D02*
X1024777Y280949D01*
G01X1024782Y280898D02*
X1024778Y280924D01*
G01X1024788Y280872D02*
X1024782Y280898D01*
G01X1024796Y280844D02*
X1024788Y280872D01*
G01X1024807Y280817D02*
X1024796Y280844D01*
G01X1024820Y280789D02*
X1024807Y280817D01*
G01X968024Y253906D02*
X968054Y253826D01*
G01X968012Y254002D02*
X968024Y253906D01*
G01X992606Y280884D02*
X992577Y280965D01*
G01X992618Y280789D02*
X992606Y280884D01*
G01X996370Y253906D02*
X996400Y253826D01*
G01X996358Y254002D02*
X996370Y253906D01*
G01X1020953Y280884D02*
X1020923Y280965D01*
G01X1020965Y280789D02*
X1020953Y280884D01*
G01X1024717Y253906D02*
X1024746Y253826D01*
G01X1024705Y254002D02*
X1024717Y253906D01*
G01X968114Y253972D02*
X968127Y254002D01*
G01X968103Y253944D02*
X968114Y253972D01*
G01X968095Y253917D02*
X968103Y253944D01*
G01X968089Y253891D02*
X968095Y253917D01*
G01X968085Y253865D02*
X968089Y253891D01*
G01X968084Y253841D02*
X968085Y253865D01*
G01X996460Y253972D02*
X996474Y254002D01*
G01X996450Y253944D02*
X996460Y253972D01*
G01X996441Y253917D02*
X996450Y253944D01*
G01X996435Y253891D02*
X996441Y253917D01*
G01X996431Y253865D02*
X996435Y253891D01*
G01X996431Y253841D02*
Y253865D01*
G01X1024807Y253972D02*
X1024820Y254002D01*
G01X1024796Y253944D02*
X1024807Y253972D01*
G01X1024788Y253917D02*
X1024796Y253944D01*
G01X1024782Y253891D02*
X1024788Y253917D01*
G01X1024778Y253865D02*
X1024782Y253891D01*
G01X1024777Y253841D02*
X1024778Y253865D01*
G01X992516Y280817D02*
X992503Y280789D01*
G01X992526Y280844D02*
X992516Y280817D01*
G01X992535Y280872D02*
X992526Y280844D01*
G01X992541Y280898D02*
X992535Y280872D01*
G01X992544Y280924D02*
X992541Y280898D01*
G01X992546Y280949D02*
X992544Y280924D01*
G01X1020862Y280817D02*
X1020849Y280789D01*
G01X1020873Y280844D02*
X1020862Y280817D01*
G01X1020881Y280872D02*
X1020873Y280844D01*
G01X1020887Y280898D02*
X1020881Y280872D01*
G01X1020891Y280924D02*
X1020887Y280898D01*
G01X1020893Y280949D02*
X1020891Y280924D01*
G01X992516Y253739D02*
X992503Y253723D01*
G01X992527Y253756D02*
X992516Y253739D01*
G01X992535Y253775D02*
X992527Y253756D01*
G01X992541Y253796D02*
X992535Y253775D01*
G01X992545Y253818D02*
X992541Y253796D01*
G01X992546Y253841D02*
X992545Y253818D01*
G01X1020863Y253739D02*
X1020849Y253723D01*
G01X1020873Y253756D02*
X1020863Y253739D01*
G01X1020882Y253775D02*
X1020873Y253756D01*
G01X1020888Y253796D02*
X1020882Y253775D01*
G01X1020891Y253818D02*
X1020888Y253796D01*
G01X1020893Y253841D02*
X1020891Y253818D01*
G01X968114Y281052D02*
X968127Y281067D01*
G01X968104Y281035D02*
X968114Y281052D01*
G01X968095Y281016D02*
X968104Y281035D01*
G01X968089Y280995D02*
X968095Y281016D01*
G01X968085Y280973D02*
X968089Y280995D01*
G01X968084Y280949D02*
X968085Y280973D01*
G01X996461Y281052D02*
X996474Y281067D01*
G01X996450Y281035D02*
X996461Y281052D01*
G01X996441Y281016D02*
X996450Y281035D01*
G01X996435Y280995D02*
X996441Y281016D01*
G01X996432Y280973D02*
X996435Y280995D01*
G01X996431Y280949D02*
X996432Y280973D01*
G01X1024807Y281052D02*
X1024820Y281067D01*
G01X1024796Y281035D02*
X1024807Y281052D01*
G01X1024788Y281016D02*
X1024796Y281035D01*
G01X1024782Y280995D02*
X1024788Y281016D01*
G01X1024778Y280973D02*
X1024782Y280995D01*
G01X1024777Y280949D02*
X1024778Y280973D01*
G01X1049299Y280884D02*
X1049270Y280965D01*
G01X1049311Y280789D02*
X1049299Y280884D01*
G01X1049209Y280817D02*
X1049196Y280789D01*
G01X1049219Y280844D02*
X1049209Y280817D01*
G01X1049228Y280872D02*
X1049219Y280844D01*
G01X1049234Y280898D02*
X1049228Y280872D01*
G01X1049237Y280924D02*
X1049234Y280898D01*
G01X1049239Y280949D02*
X1049237Y280924D01*
G01X1049209Y253739D02*
X1049196Y253723D01*
G01X1049220Y253756D02*
X1049209Y253739D01*
G01X1049228Y253775D02*
X1049220Y253756D01*
G01X1049234Y253796D02*
X1049228Y253775D01*
G01X1049238Y253818D02*
X1049234Y253796D01*
G01X1049239Y253841D02*
X1049238Y253818D01*
G01X969458Y282440D02*
X969373Y282313D01*
G01X969488Y282591D02*
X969458Y282440D01*
G01X991172Y252350D02*
X991257Y252478D01*
G01X991142Y252199D02*
X991172Y252350D01*
G01X997805Y282440D02*
X997719Y282313D01*
G01X997835Y282591D02*
X997805Y282440D01*
G01X1019518Y252350D02*
X1019604Y252478D01*
G01X1019488Y252199D02*
X1019518Y252350D01*
G01X1026151Y282440D02*
X1026066Y282313D01*
G01X1026181Y282591D02*
X1026151Y282440D01*
G01X969397Y282328D02*
X969373Y282313D01*
G01X969412Y282315D02*
X969397Y282328D01*
G01X969415Y282254D02*
X969412Y282315D01*
G01X969401Y282159D02*
X969415Y282254D01*
G01X969373Y282034D02*
X969401Y282159D01*
G01X997744Y282328D02*
X997719Y282313D01*
G01X997758Y282315D02*
X997744Y282328D01*
G01X997761Y282254D02*
X997758Y282315D01*
G01X997748Y282159D02*
X997761Y282254D01*
G01X997719Y282034D02*
X997748Y282159D01*
G01X991233Y252462D02*
X991257Y252478D01*
G01X991218Y252475D02*
X991233Y252462D01*
G01X991215Y252537D02*
X991218Y252475D01*
G01X991229Y252630D02*
X991215Y252537D01*
G01X991257Y252756D02*
X991229Y252630D01*
G01X1026090Y282328D02*
X1026066Y282313D01*
G01X1026105Y282315D02*
X1026090Y282328D01*
G01X1026107Y282254D02*
X1026105Y282315D01*
G01X1026094Y282159D02*
X1026107Y282254D01*
G01X1026066Y282034D02*
X1026094Y282159D01*
G01X1019579Y252462D02*
X1019604Y252478D01*
G01X1019565Y252475D02*
X1019579Y252462D01*
G01X1019562Y252537D02*
X1019565Y252475D01*
G01X1019576Y252630D02*
X1019562Y252537D01*
G01X1019604Y252756D02*
X1019576Y252630D01*
G01X968023Y280882D02*
X968012Y280789D01*
G01X968054Y280965D02*
X968023Y280882D01*
G01X1047865Y252350D02*
X1047950Y252478D01*
G01X1047835Y252199D02*
X1047865Y252350D01*
G01X1047926Y252462D02*
X1047950Y252478D01*
G01X1047911Y252475D02*
X1047926Y252462D01*
G01X1047908Y252537D02*
X1047911Y252475D01*
G01X1047922Y252630D02*
X1047908Y252537D01*
G01X1047950Y252756D02*
X1047922Y252630D01*
G01X996370Y280882D02*
X996358Y280789D01*
G01X996400Y280965D02*
X996370Y280882D01*
G01X992607Y253908D02*
X992618Y254002D01*
G01X992577Y253826D02*
X992607Y253908D01*
G01X1024716Y280882D02*
X1024705Y280789D01*
G01X1024746Y280965D02*
X1024716Y280882D01*
G01X1020953Y253908D02*
X1020965Y254002D01*
G01X1020923Y253826D02*
X1020953Y253908D01*
G01X1049300D02*
X1049311Y254002D01*
G01X1049270Y253826D02*
X1049300Y253908D01*
G01X968083Y281015D02*
X968054Y280965D01*
G01X968127Y281067D02*
X968083Y281015D01*
G01X996430D02*
X996400Y280965D01*
G01X996474Y281067D02*
X996430Y281015D01*
G01X992546Y253775D02*
X992577Y253826D01*
G01X992503Y253723D02*
X992546Y253775D01*
G01X1024776Y281015D02*
X1024746Y280965D01*
G01X1024820Y281067D02*
X1024776Y281015D01*
G01X1020893Y253775D02*
X1020923Y253826D01*
G01X1020849Y253723D02*
X1020893Y253775D01*
G01X1049239D02*
X1049270Y253826D01*
G01X1049196Y253723D02*
X1049239Y253775D01*
G01X1051181Y240157D02*
Y193701D01*
G01Y240157D02*
Y193701D01*
G01X1026066Y282313D02*
G03X1026181Y282591I-279J278D01*
G01X1047835D02*
G03X1047950Y282313I393J0D01*
G01X1019488Y282591D02*
G03X1019604Y282313I394J1D01*
G01X997719D02*
G03X997835Y282591I-278J279D01*
G01X969373Y282313D02*
G03X969488Y282591I-279J278D01*
G01X991142D02*
G03X991257Y282313I394J0D01*
G01X1049311Y280789D02*
G03X1049196Y281067I-394J0D01*
G01X1042339Y276453D02*
G03X1039209I-1565J4D01*
G01X1047861Y278022D02*
G03X1046296Y276454I0J-1565D01*
G01X1049288Y278022D02*
G03X1050853Y279587I0J1565D01*
G01X1042310Y262162D02*
G03Y263942I-1299J890D01*
G01Y269485D02*
G03Y271265I-1299J890D01*
G01X1039239D02*
G03Y269485I1299J-890D01*
G01Y263942D02*
G03Y262162I1299J-890D01*
G01X1047950Y252478D02*
G03X1047835Y252199I279J-278D01*
G01X1049196Y253723D02*
G03X1049311Y254002I-279J278D01*
G01X1044764Y255905D02*
G03I-1457J0D01*
G01X1024820Y281067D02*
G03X1024705Y280789I279J-278D01*
G01X1020965D02*
G03X1020849Y281067I-394J-1D01*
G01X1021080Y276453D02*
G03X1017950I-1565J4D01*
G01X1028166D02*
G03X1025036I-1565J4D01*
G01X1035253D02*
G03X1032123I-1565J4D01*
G01X1032152Y271265D02*
G03Y269485I1300J-890D01*
G01X1035223D02*
G03Y271265I-1299J890D01*
G01Y262162D02*
G03Y263942I-1299J890D01*
G01X1032152D02*
G03Y262162I1299J-890D01*
G01X1024705Y254002D02*
G03X1024820Y253723I394J-1D01*
G01X1026181Y252199D02*
G03X1026066Y252478I-394J1D01*
G01X1019604D02*
G03X1019488Y252199I278J-279D01*
G01X1020849Y253723D02*
G03X1020965Y254002I-278J279D01*
G01X1032165Y255905D02*
G03I-1456J0D01*
G01X1023720Y234986D02*
G03X1023836Y234707I394J0D01*
G01X1025984Y232396D02*
G03X1025869Y232674I-394J0D01*
G01X1048147D02*
G03X1048031Y232396I278J-279D01*
G01X1050180Y234707D02*
G03X1050295Y234986I-279J278D01*
G01X1019800Y232674D02*
G03X1019685Y232396I279J-278D01*
G01X1021833Y234707D02*
G03X1021949Y234986I-278J279D01*
G01X996474Y281067D02*
G03X996358Y280789I278J-279D01*
G01X992618D02*
G03X992503Y281067I-394J0D01*
G01X999820Y276453D02*
G03X996690I-1565J4D01*
G01X1006906D02*
G03X1003776I-1565J4D01*
G01X1013993D02*
G03X1010863I-1565J4D01*
G01X1003806Y271265D02*
G03Y269485I1299J-890D01*
G01X1006877D02*
G03Y271265I-1299J890D01*
G01X1013963Y269485D02*
G03Y271265I-1299J890D01*
G01X1010893D02*
G03Y269485I1299J-890D01*
G01X996358Y254002D02*
G03X996474Y253723I394J0D01*
G01X997835Y252199D02*
G03X997719Y252478I-394J0D01*
G01X991257D02*
G03X991142Y252199I279J-278D01*
G01X992503Y253723D02*
G03X992618Y254002I-279J278D01*
G01X1016417Y255905D02*
G03I-1456J0D01*
G01X1003819D02*
G03I-1457J0D01*
G01X1013963Y262162D02*
G03Y263942I-1299J890D01*
G01X1010893D02*
G03Y262162I1299J-890D01*
G01X1006877D02*
G03Y263942I-1299J890D01*
G01X1003806D02*
G03Y262162I1299J-890D01*
G01X968127Y281067D02*
G03X968012Y280789I279J-278D01*
G01X978560Y276453D02*
G03X975430I-1565J4D01*
G01X985646D02*
G03X982517I-1564J4D01*
G01X992733D02*
G03X989603I-1565J4D01*
G01X969869Y278021D02*
G03X969830Y278022I-60J-1564D01*
G01X971473Y276453D02*
G03X969869Y278021I-1565J4D01*
G01X966375Y279596D02*
G03X967950Y278022I1575J1D01*
G01X975459Y271265D02*
G03Y269485I1300J-890D01*
G01X978530D02*
G03Y271265I-1299J890D01*
G01X985617Y269485D02*
G03Y271265I-1299J890D01*
G01X982546D02*
G03Y269485I1299J-890D01*
G01X968012Y254002D02*
G03X968127Y253723I394J-1D01*
G01X969488Y252199D02*
G03X969373Y252478I-394J1D01*
G01X988071Y255905D02*
G03I-1457J0D01*
G01X975472D02*
G03I-1456J0D01*
G01X985617Y262162D02*
G03Y263942I-1299J890D01*
G01X982546D02*
G03Y262162I1299J-890D01*
G01X978530D02*
G03Y263942I-1299J890D01*
G01X975459D02*
G03Y262162I1300J-890D01*
G01X995374Y234986D02*
G03X995489Y234707I394J-1D01*
G01X997638Y232396D02*
G03X997522Y232674I-394J-1D01*
G01X967028Y234986D02*
G03X967143Y234707I394J-1D01*
G01X969291Y232396D02*
G03X969176Y232674I-393J0D01*
G01X991454D02*
G03X991339Y232396I278J-278D01*
G01X993487Y234707D02*
G03X993602Y234986I-279J278D01*
G01X1048031Y197028D02*
X1046457Y195453D01*
G01X1029724D02*
X1032283Y198012D01*
G01X1019685Y197028D02*
X1018110Y195453D01*
G01X1050180Y234707D02*
X1048147Y232674D01*
G01X1047835Y236359D02*
X1046260Y234784D01*
G01X1001378Y195453D02*
X1003937Y198012D01*
G01X1049196Y253723D02*
X1047950Y252478D01*
G01Y252756D02*
X1049196Y254002D01*
G01X991339Y197028D02*
X989764Y195453D01*
G01X1021833Y234707D02*
X1019800Y232674D01*
G01X1019488Y236359D02*
X1017913Y234784D01*
G01X973031Y195453D02*
X975591Y198012D01*
G01X1020849Y253723D02*
X1019604Y252478D01*
G01Y252756D02*
X1020849Y254002D01*
G01X993487Y234707D02*
X991454Y232674D01*
G01X991142Y236359D02*
X989567Y234784D01*
G01X1026066Y282034D02*
X1024820Y280789D01*
G01Y281067D02*
X1026066Y282313D01*
G01X992503Y253723D02*
X991257Y252478D01*
G01Y252756D02*
X992503Y254002D01*
G01X997719Y282034D02*
X996474Y280789D01*
G01Y281067D02*
X997719Y282313D01*
G01X969373Y282034D02*
X968127Y280789D01*
G01Y281067D02*
X969373Y282313D01*
G01X1044086Y256409D02*
X1043904Y256192D01*
G01Y256440D02*
X1044086Y256657D01*
G01X1039961Y198012D02*
X1038483Y195453D01*
G01X1039205Y259948D02*
X1039003Y259605D01*
G01X1032118Y259948D02*
X1031916Y259605D01*
G01X1025031Y259948D02*
X1024830Y259605D01*
G01X1017945Y259948D02*
X1017743Y259605D01*
G01X1010858Y259948D02*
X1010656Y259605D01*
G01X1003772Y259948D02*
X1003570Y259605D01*
G01X996685Y259948D02*
X996483Y259605D01*
G01X989598Y259948D02*
X989396Y259605D01*
G01X982512Y259948D02*
X982310Y259605D01*
G01X975425Y259948D02*
X975223Y259605D01*
G01X1049508Y246417D02*
X1047929Y243690D01*
G01X1021161Y246417D02*
X1019583Y243690D01*
G01X992815Y246417D02*
X991236Y243690D01*
G01X1011614Y198012D02*
X1010137Y195453D01*
G01X1044908Y257559D02*
X1046296Y259963D01*
G01X1037822Y257559D02*
X1039200Y259946D01*
G01X1030735Y257559D02*
X1032113Y259946D01*
G01X1023648Y257559D02*
X1025026Y259946D01*
G01X983268Y198012D02*
X981790Y195453D01*
G01X1016562Y257559D02*
X1017940Y259946D01*
G01X1009475Y257559D02*
X1010853Y259946D01*
G01X1002389Y257559D02*
X1003767Y259946D01*
G01X995302Y257559D02*
X996680Y259946D01*
G01X988215Y257559D02*
X989593Y259946D01*
G01X981129Y257559D02*
X982507Y259946D01*
G01X974042Y257559D02*
X975420Y259946D01*
G01X1042447Y255200D02*
X1042933Y256657D01*
G01X1042750Y255572D02*
X1042629Y255200D01*
G01X1042781Y255696D02*
X1043054Y256533D01*
G01X1042343Y271215D02*
X1042339Y276457D01*
G01X1035256Y271215D02*
X1035253Y276457D01*
G01X1028176Y259946D02*
X1028166Y276457D01*
G01X1021089Y259948D02*
X1021080Y276457D01*
G01X1013996Y271215D02*
X1013993Y276457D01*
G01X1006909Y271215D02*
X1006906Y276457D01*
G01X999830Y259946D02*
X999820Y276457D01*
G01X992743Y259948D02*
X992733Y276457D01*
G01X985650Y271215D02*
X985646Y276457D01*
G01X978560Y276453D02*
Y276457D01*
G01X1039206Y271215D02*
X1039209Y276453D01*
G01X1039202Y263886D02*
X1039206Y269536D01*
G01X1039200Y259946D02*
X1039201Y262220D01*
G01X1032120Y271215D02*
X1032123Y276453D01*
G01X1032115Y263886D02*
X1032119Y269536D01*
G01X1032113Y259946D02*
X1032115Y262220D01*
G01X1025026Y259946D02*
X1025036Y276453D01*
G01X1017940Y259946D02*
X1017950Y276453D01*
G01X1010860Y271215D02*
X1010863Y276453D01*
G01X1010856Y263886D02*
X1010859Y269536D01*
G01X1010853Y259946D02*
X1010855Y262220D01*
G01X1003773Y271215D02*
X1003776Y276453D01*
G01X1003769Y263886D02*
X1003772Y269536D01*
G01X1003767Y259946D02*
X1003768Y262220D01*
G01X996680Y259946D02*
X996690Y276453D01*
G01X989593Y259946D02*
X989603Y276453D01*
G01X982513Y271215D02*
X982517Y276453D01*
G01X982509Y263886D02*
X982513Y269536D01*
G01X982507Y259946D02*
X982508Y262220D01*
G01X1050853Y321457D02*
Y279587D01*
G01X1050295Y246417D02*
Y234986D01*
G01X1049311Y280952D02*
Y253839D01*
G01X1049196Y254002D02*
Y280789D01*
G01X1048031Y232396D02*
Y197028D01*
G01X1047950Y282034D02*
Y252756D01*
G01X1047929Y242580D02*
Y243690D01*
G01X1047835Y236359D02*
Y303676D01*
G01Y252756D02*
Y252199D01*
G01Y282590D02*
Y282034D01*
G01X1046296Y259953D02*
Y276457D01*
G01X1044268Y256657D02*
Y255200D01*
G01X1044086D02*
Y256409D01*
G01X1043904Y256192D02*
Y256440D01*
G01X1042310Y262162D02*
Y256542D01*
G01Y269485D02*
Y263942D01*
G01Y274863D02*
Y271265D01*
G01X1041732Y206575D02*
Y198012D01*
G01X1039961D02*
Y206575D01*
G01X1039239Y262162D02*
Y256542D01*
G01Y269485D02*
Y263942D01*
G01Y274863D02*
Y271265D01*
G01X1035223Y262162D02*
Y256542D01*
G01Y269485D02*
Y263942D01*
G01Y274863D02*
Y271265D01*
G01X1034055Y206575D02*
Y198012D01*
G01X1032283Y206575D02*
Y198012D01*
G01X1032152Y256542D02*
Y262162D01*
G01Y269485D02*
Y263942D01*
G01Y274863D02*
Y271265D01*
G01X1026181Y252199D02*
Y252756D01*
G01Y303560D02*
Y236359D01*
G01Y282034D02*
Y282591D01*
G01X1026087Y243683D02*
Y242580D01*
G01X1026066Y252756D02*
Y282034D01*
G01X1025984Y232396D02*
Y197028D01*
G01X1024820Y280789D02*
Y254002D01*
G01X1024705Y253839D02*
Y280952D01*
G01X1023720Y246417D02*
Y234986D01*
G01X1021949Y246417D02*
Y234986D01*
G01X1020965Y280952D02*
Y253839D01*
G01X1020849Y254002D02*
Y280789D01*
G01X1019685Y232396D02*
Y197028D01*
G01X1019604Y282034D02*
Y252756D01*
G01X1019583Y242580D02*
Y243690D01*
G01X1019488Y236359D02*
Y303676D01*
G01Y252756D02*
Y252199D01*
G01Y282590D02*
Y282034D01*
G01X1013963Y262162D02*
Y256542D01*
G01Y269485D02*
Y263942D01*
G01Y274863D02*
Y271265D01*
G01X1013386Y206575D02*
Y198012D01*
G01X1011614D02*
Y206575D01*
G01X1010893Y262162D02*
Y256542D01*
G01Y269485D02*
Y263942D01*
G01Y274863D02*
Y271265D01*
G01X1006877Y262162D02*
Y256542D01*
G01Y269485D02*
Y263942D01*
G01Y274863D02*
Y271265D01*
G01X1005709Y206575D02*
Y198012D01*
G01X1003937Y206575D02*
Y198012D01*
G01X1003806Y256542D02*
Y262162D01*
G01Y269485D02*
Y263942D01*
G01Y274863D02*
Y271265D01*
G01X997835Y252199D02*
Y252756D01*
G01Y303560D02*
Y236359D01*
G01Y282034D02*
Y282591D01*
G01X997740Y243683D02*
Y242580D01*
G01X997719Y252756D02*
Y282034D01*
G01X997638Y232396D02*
Y197028D01*
G01X996474Y280789D02*
Y254002D01*
G01X996358Y253839D02*
Y280952D01*
G01X995374Y246417D02*
Y234986D01*
G01X993602Y246417D02*
Y234986D01*
G01X992618Y280952D02*
Y253839D01*
G01X992503Y254002D02*
Y280789D01*
G01X991339Y232396D02*
Y197028D01*
G01X991257Y282034D02*
Y252756D01*
G01X991236Y242580D02*
Y243690D01*
G01X991142Y236359D02*
Y303676D01*
G01Y252756D02*
Y252199D01*
G01Y282590D02*
Y282034D01*
G01X985617Y262162D02*
Y256542D01*
G01Y269485D02*
Y263942D01*
G01Y274863D02*
Y271265D01*
G01X985039Y206575D02*
Y198012D01*
G01X983268D02*
Y206575D01*
G01X982546Y262162D02*
Y256542D01*
G01Y269485D02*
Y263942D01*
G01Y274863D02*
Y271265D01*
G01X978530Y262162D02*
Y256542D01*
G01Y269485D02*
Y263942D01*
G01Y274863D02*
Y271265D01*
G01X1042348Y262220D02*
X1042349Y259946D01*
G01X1042344Y269536D02*
X1042347Y263886D01*
G01X1035261Y262220D02*
X1035263Y259946D01*
G01X1035257Y269536D02*
X1035260Y263886D01*
G01X1014002Y262220D02*
X1014003Y259946D01*
G01X1013997Y269536D02*
X1014000Y263886D01*
G01X1006915Y262220D02*
X1006916Y259946D01*
G01X1006911Y269536D02*
X1006914Y263886D01*
G01X985655Y262220D02*
X985656Y259946D01*
G01X985651Y269536D02*
X985654Y263886D01*
G01X975427Y271215D02*
X975430Y276453D01*
G01X975422Y263886D02*
X975426Y269536D01*
G01X975420Y259946D02*
X975422Y262220D01*
G01X977362Y206575D02*
Y198012D01*
G01X975591Y206575D02*
Y198012D01*
G01X975459Y256542D02*
Y262162D01*
G01Y269485D02*
Y263942D01*
G01Y274863D02*
Y271265D01*
G01X969488Y252199D02*
Y252756D01*
G01Y303560D02*
Y236359D01*
G01Y282034D02*
Y282591D01*
G01X969394Y243683D02*
Y242580D01*
G01X969373Y252756D02*
Y282034D01*
G01X969291Y232396D02*
Y197028D01*
G01X968127Y280789D02*
Y254002D01*
G01X968012Y253839D02*
Y280952D01*
G01X967028Y246417D02*
Y234986D01*
G01X966375Y279596D02*
Y321457D01*
G01X978569Y262220D02*
X978570Y259946D01*
G01X978564Y269536D02*
X978567Y263886D01*
G01X978560Y276453D02*
X978563Y271215D01*
G01X971473Y276453D02*
X971483Y259946D01*
G01X1043054Y256533D02*
X1043327Y255696D01*
G01X1043479Y255200D02*
X1043357Y255572D01*
G01X1043175Y256657D02*
X1043661Y255200D01*
G01X1043727Y257559D02*
X1042348Y259948D01*
G01X1036641Y257559D02*
X1035261Y259948D01*
G01X1029554Y257559D02*
X1028174Y259948D01*
G01X1022467Y257559D02*
X1021088Y259948D01*
G01X1024508Y246417D02*
X1026087Y243683D01*
G01X1015381Y257559D02*
X1014001Y259948D01*
G01X1008294Y257559D02*
X1006915Y259948D01*
G01X1001207Y257559D02*
X999828Y259948D01*
G01X1034055Y198012D02*
X1035533Y195453D01*
G01X994121Y257559D02*
X992741Y259948D01*
G01X996161Y246417D02*
X997740Y243683D01*
G01X1021084Y259948D02*
X1022467Y257559D01*
G01X992738Y259948D02*
X994121Y257559D01*
G01X987034D02*
X985655Y259948D01*
G01X979948Y257559D02*
X978568Y259948D01*
G01X972861Y257559D02*
X971481Y259948D01*
G01X1005709Y198012D02*
X1007186Y195453D01*
G01X967815Y246417D02*
X969394Y243683D01*
G01X977362Y198012D02*
X978840Y195453D01*
G01X1047950Y282313D02*
X1049196Y281067D01*
G01Y280789D02*
X1047950Y282034D01*
G01X1019604Y282313D02*
X1020849Y281067D01*
G01Y280789D02*
X1019604Y282034D01*
G01X1024820Y254002D02*
X1026066Y252756D01*
G01Y252478D02*
X1024820Y253723D01*
G01X991257Y282313D02*
X992503Y281067D01*
G01Y280789D02*
X991257Y282034D01*
G01X1026181Y236359D02*
X1027756Y234784D01*
G01X1023836Y234707D02*
X1025869Y232674D01*
G01X996474Y254002D02*
X997719Y252756D01*
G01Y252478D02*
X996474Y253723D01*
G01X1044291Y195453D02*
X1041732Y198012D01*
G01X997835Y236359D02*
X999409Y234784D01*
G01X995489Y234707D02*
X997522Y232674D01*
G01X1025984Y197028D02*
X1027559Y195453D01*
G01X968127Y254002D02*
X969373Y252756D01*
G01Y252478D02*
X968127Y253723D01*
G01X1015945Y195453D02*
X1013386Y198012D01*
G01X969488Y236359D02*
X971063Y234784D01*
G01X967143Y234707D02*
X969176Y232674D01*
G01X997638Y197028D02*
X999213Y195453D01*
G01X987598D02*
X985039Y198012D01*
G01X969291Y197028D02*
X970866Y195453D01*
G01X1026066Y282034D02*
X1026181D01*
G01X997719D02*
X997835D01*
G01X969373D02*
X969488D01*
G01X991257D02*
X991142D01*
G01X1019604D02*
X1019488D01*
G01X1047950D02*
X1047835D01*
G01X992618Y280952D02*
X968012D01*
G01X1020965D02*
X996358D01*
G01X1049311D02*
X1024705D01*
G01X1049196Y280789D02*
X1049311D01*
G01X1024705D02*
X1024820D01*
G01X1020849D02*
X1020965D01*
G01X996358D02*
X996474D01*
G01X992503D02*
X992618D01*
G01X968012D02*
X968127D01*
G01X1024705Y278428D02*
X1049311D01*
G01X996358D02*
X1020965D01*
G01X968012D02*
X992618D01*
G01X967950Y278022D02*
X969830D01*
G01X1049288D02*
X1047861D01*
G01X978530Y274863D02*
X975459D01*
G01X985617D02*
X982546D01*
G01X1006877D02*
X1003806D01*
G01X1013963D02*
X1010893D01*
G01X1035223D02*
X1032152D01*
G01X1042310D02*
X1039239D01*
G01X1042546Y259605D02*
X1046089D01*
G01X1035459D02*
X1039003D01*
G01X1028373D02*
X1031916D01*
G01X1021286D02*
X1024830D01*
G01X1014200D02*
X1017743D01*
G01X1007113D02*
X1010656D01*
G01X1000026D02*
X1003570D01*
G01X992940D02*
X996483D01*
G01X985853D02*
X989396D01*
G01X978767D02*
X982310D01*
G01X971680D02*
X975223D01*
G01X1043727Y257559D02*
X1044908D01*
G01X1036641D02*
X1037822D01*
G01X1029554D02*
X1030735D01*
G01X1015381D02*
X1016562D01*
G01X1008294D02*
X1009475D01*
G01X1001207D02*
X1002389D01*
G01X987034D02*
X988215D01*
G01X979948D02*
X981129D01*
G01X974042D02*
X972861D01*
G01X995302D02*
X994121D01*
G01X1023648D02*
X1022467D01*
G01X1044086Y256657D02*
X1044268D01*
G01X1042933D02*
X1043175D01*
G01X1024705Y256542D02*
X1032152D01*
G01X996358D02*
X1003806D01*
G01X968012D02*
X975459D01*
G01X982546D02*
X978530D01*
G01X992618D02*
X985617D01*
G01X1010893D02*
X1006877D01*
G01X1020965D02*
X1013963D01*
G01X1039239D02*
X1035223D01*
G01X1049311D02*
X1042310D01*
G01X1043327Y255696D02*
X1042781D01*
G01X1043357Y255572D02*
X1042750D01*
G01X1044268Y255200D02*
X1044086D01*
G01X1043661D02*
X1043479D01*
G01X1042629D02*
X1042447D01*
G01X968127Y254002D02*
X968012D01*
G01X992618D02*
X992503D01*
G01X996474D02*
X996358D01*
G01X1020965D02*
X1020849D01*
G01X1024820D02*
X1024705D01*
G01X1049311D02*
X1049196D01*
G01X992618Y253839D02*
X968012D01*
G01X1020965D02*
X996358D01*
G01X1049311D02*
X1024705D01*
G01X1026066Y252756D02*
X1026181D01*
G01X997719D02*
X997835D01*
G01X969373D02*
X969488D01*
G01X991257D02*
X991142D01*
G01X1019604D02*
X1019488D01*
G01X1047950D02*
X1047835D01*
G01X991142Y247539D02*
X969488D01*
G01X1019488D02*
X997835D01*
G01X1047835D02*
X1026181D01*
G01X967815Y246417D02*
X967028D01*
G01X991142D02*
X969488D01*
G01X993602D02*
X992815D01*
G01X996161D02*
X995374D01*
G01X1019488D02*
X997835D01*
G01X1021949D02*
X1021161D01*
G01X1024508D02*
X1023720D01*
G01X1047835D02*
X1026181D01*
G01X1050295D02*
X1049508D01*
G01X991142Y244824D02*
X969488D01*
G01X1019488D02*
X997835D01*
G01X1047835D02*
X1026181D01*
G01X969394Y243661D02*
X967028D01*
G01X993602D02*
X991236D01*
G01X997740D02*
X995374D01*
G01X1021949D02*
X1019583D01*
G01X1026087D02*
X1023720D01*
G01X1050295D02*
X1047929D01*
G01X969488Y242580D02*
X969394D01*
G01X991236D02*
X991142D01*
G01X997835D02*
X997740D01*
G01X1019583D02*
X1019488D01*
G01X1026181D02*
X1026087D01*
G01X1047929D02*
X1047835D01*
G01X1027756Y234784D02*
X1046260D01*
G01X999409D02*
X1017913D01*
G01X971063D02*
X989567D01*
G01X977362Y206575D02*
X975591D01*
G01X985039D02*
X983268D01*
G01X1005709D02*
X1003937D01*
G01X1013386D02*
X1011614D01*
G01X1034055D02*
X1032283D01*
G01X1041732D02*
X1039961D01*
G01X977362Y198012D02*
X975591D01*
G01X1005709D02*
X1003937D01*
G01X1034055D02*
X1032283D01*
G01X985039D02*
X983268D01*
G01X1011614D02*
X1013386D01*
G01X1041732D02*
X1039961D01*
G01X991339Y197028D02*
X969291D01*
G01X1019685D02*
X997638D01*
G01X1048031D02*
X1025984D01*
G01X989764Y195453D02*
X970866D01*
G01X1018110D02*
X999213D01*
G01X1046457D02*
X1027559D01*
G01X975544Y314802D02*
X975459Y315051D01*
G01X975681Y314572D02*
X975544Y314802D01*
G01X975865Y314370D02*
X975681Y314572D01*
G01X982631Y314802D02*
X982546Y315051D01*
G01X982768Y314572D02*
X982631Y314802D01*
G01X982951Y314370D02*
X982768Y314572D01*
G01X1003891Y314802D02*
X1003806Y315051D01*
G01X1004028Y314572D02*
X1003891Y314802D01*
G01X1004211Y314370D02*
X1004028Y314572D01*
G01X1010977Y314802D02*
X1010893Y315051D01*
G01X1011114Y314572D02*
X1010977Y314802D01*
G01X1011298Y314370D02*
X1011114Y314572D01*
G01X1032237Y314802D02*
X1032152Y315051D01*
G01X1032374Y314572D02*
X1032237Y314802D01*
G01X1032557Y314370D02*
X1032374Y314572D01*
G01X1039324Y314802D02*
X1039239Y315051D01*
G01X1039461Y314572D02*
X1039324Y314802D01*
G01X1039644Y314370D02*
X1039461Y314572D01*
G01X968391Y314977D02*
X968343Y315298D01*
G01X968535Y314658D02*
X968391Y314977D01*
G01X968778Y314370D02*
X968535Y314658D01*
G01X989650Y314977D02*
X989603Y315298D01*
G01X989795Y314658D02*
X989650Y314977D01*
G01X990038Y314370D02*
X989795Y314658D01*
G01X1017997Y314977D02*
X1017950Y315298D01*
G01X1018141Y314658D02*
X1017997Y314977D01*
G01X1018384Y314370D02*
X1018141Y314658D01*
G01X1046343Y314977D02*
X1046296Y315298D01*
G01X1046488Y314658D02*
X1046343Y314977D01*
G01X1046731Y314370D02*
X1046488Y314658D01*
G01X975482Y315255D02*
X975430Y315762D01*
G01X975633Y314774D02*
X975482Y315255D01*
G01X975865Y314370D02*
X975633Y314774D01*
G01X989656Y315255D02*
X989603Y315762D01*
G01X989807Y314774D02*
X989656Y315255D01*
G01X990038Y314370D02*
X989807Y314774D01*
G01X1003829Y315255D02*
X1003776Y315762D01*
G01X1003980Y314774D02*
X1003829Y315255D01*
G01X1004211Y314370D02*
X1003980Y314774D01*
G01X1018002Y315255D02*
X1017950Y315762D01*
G01X1018153Y314774D02*
X1018002Y315255D01*
G01X1018384Y314370D02*
X1018153Y314774D01*
G01X1032175Y315255D02*
X1032123Y315762D01*
G01X1032326Y314774D02*
X1032175Y315255D01*
G01X1032557Y314370D02*
X1032326Y314774D01*
G01X1046348Y315255D02*
X1046296Y315762D01*
G01X1046500Y314774D02*
X1046348Y315255D01*
G01X1046731Y314370D02*
X1046500Y314774D01*
G01X968552Y314764D02*
X968778Y314370D01*
G01X968398Y315244D02*
X968552Y314764D01*
G01X968343Y315762D02*
X968398Y315244D01*
G01X982725Y314764D02*
X982951Y314370D01*
G01X982571Y315244D02*
X982725Y314764D01*
G01X982517Y315762D02*
X982571Y315244D01*
G01X996898Y314764D02*
X997124Y314370D01*
G01X996744Y315244D02*
X996898Y314764D01*
G01X996690Y315762D02*
X996744Y315244D01*
G01X1011071Y314764D02*
X1011298Y314370D01*
G01X1010918Y315244D02*
X1011071Y314764D01*
G01X1010863Y315762D02*
X1010918Y315244D01*
G01X1025244Y314764D02*
X1025471Y314370D01*
G01X1025091Y315244D02*
X1025244Y314764D01*
G01X1025036Y315762D02*
X1025091Y315244D01*
G01X982524Y315170D02*
X982546Y315044D01*
G01X982517Y315298D02*
X982524Y315170D01*
G01X975437Y315171D02*
X975430Y315298D01*
G01X975459Y315044D02*
X975437Y315171D01*
G01X1003784D02*
X1003776Y315298D01*
G01X1003806Y315044D02*
X1003784Y315171D01*
G01X1032130D02*
X1032123Y315298D01*
G01X1032152Y315044D02*
X1032130Y315171D01*
G01X996885Y314653D02*
X997124Y314370D01*
G01X996739Y314970D02*
X996885Y314653D01*
G01X996690Y315298D02*
X996739Y314970D01*
G01X1025231Y314653D02*
X1025471Y314370D01*
G01X1025085Y314970D02*
X1025231Y314653D01*
G01X1025036Y315298D02*
X1025085Y314970D01*
G01X1039418Y314764D02*
X1039644Y314370D01*
G01X1039264Y315244D02*
X1039418Y314764D01*
G01X1039209Y315762D02*
X1039264Y315244D01*
G01X1010870Y315170D02*
X1010893Y315044D01*
G01X1010863Y315298D02*
X1010870Y315170D01*
G01X1039217D02*
X1039239Y315044D01*
G01X1039209Y315298D02*
X1039217Y315170D01*
G01X978552Y315171D02*
X978530Y315044D01*
G01X978560Y315298D02*
X978552Y315171D01*
G01X985639D02*
X985617Y315044D01*
G01X985646Y315298D02*
X985639Y315171D01*
G01X1006899D02*
X1006877Y315044D01*
G01X1006906Y315298D02*
X1006899Y315171D01*
G01X1013985D02*
X1013963Y315044D01*
G01X1013993Y315298D02*
X1013985Y315171D01*
G01X971281Y314658D02*
X971039Y314370D01*
G01X971426Y314976D02*
X971281Y314658D01*
G01X971473Y315298D02*
X971426Y314976D01*
G01X992541Y314658D02*
X992298Y314370D01*
G01X992686Y314976D02*
X992541Y314658D01*
G01X992733Y315298D02*
X992686Y314976D01*
G01X1035245Y315171D02*
X1035223Y315044D01*
G01X1035253Y315298D02*
X1035245Y315171D01*
G01X1042332D02*
X1042310Y315044D01*
G01X1042339Y315298D02*
X1042332Y315171D01*
G01X999628Y314658D02*
X999385Y314370D01*
G01X999772Y314976D02*
X999628Y314658D01*
G01X999820Y315298D02*
X999772Y314976D01*
G01X1020887Y314658D02*
X1020645Y314370D01*
G01X1021032Y314976D02*
X1020887Y314658D01*
G01X1021080Y315298D02*
X1021032Y314976D01*
G01X1027974Y314658D02*
X1027731Y314370D01*
G01X1028119Y314976D02*
X1027974Y314658D01*
G01X1028166Y315298D02*
X1028119Y314976D01*
G01X1049234Y314658D02*
X1048991Y314370D01*
G01X1049379Y314976D02*
X1049234Y314658D01*
G01X1049426Y315298D02*
X1049379Y314976D01*
G01X978382Y314682D02*
X978125Y314370D01*
G01X978530Y315051D02*
X978382Y314682D01*
G01X985469D02*
X985212Y314370D01*
G01X985617Y315051D02*
X985469Y314682D01*
G01X1006729D02*
X1006472Y314370D01*
G01X1006877Y315051D02*
X1006729Y314682D01*
G01X1013815D02*
X1013558Y314370D01*
G01X1013963Y315051D02*
X1013815Y314682D01*
G01X1035075D02*
X1034818Y314370D01*
G01X1035223Y315051D02*
X1035075Y314682D01*
G01X1042162D02*
X1041905Y314370D01*
G01X1042310Y315051D02*
X1042162Y314682D01*
G01X971419Y315246D02*
X971473Y315762D01*
G01X971266Y314766D02*
X971419Y315246D01*
G01X971039Y314370D02*
X971266Y314766D01*
G01X978506Y315246D02*
X978560Y315762D01*
G01X978352Y314766D02*
X978506Y315246D01*
G01X978125Y314370D02*
X978352Y314766D01*
G01X985592Y315246D02*
X985646Y315762D01*
G01X985439Y314766D02*
X985592Y315246D01*
G01X985212Y314370D02*
X985439Y314766D01*
G01X992679Y315246D02*
X992733Y315762D01*
G01X992526Y314766D02*
X992679Y315246D01*
G01X992298Y314370D02*
X992526Y314766D01*
G01X999765Y315246D02*
X999820Y315762D01*
G01X999612Y314766D02*
X999765Y315246D01*
G01X999385Y314370D02*
X999612Y314766D01*
G01X1006852Y315246D02*
X1006906Y315762D01*
G01X1006699Y314766D02*
X1006852Y315246D01*
G01X1006472Y314370D02*
X1006699Y314766D01*
G01X1013939Y315246D02*
X1013993Y315762D01*
G01X1013785Y314766D02*
X1013939Y315246D01*
G01X1013558Y314370D02*
X1013785Y314766D01*
G01X1021025Y315246D02*
X1021080Y315762D01*
G01X1020872Y314766D02*
X1021025Y315246D01*
G01X1020645Y314370D02*
X1020872Y314766D01*
G01X1028112Y315246D02*
X1028166Y315762D01*
G01X1027959Y314766D02*
X1028112Y315246D01*
G01X1027731Y314370D02*
X1027959Y314766D01*
G01X1035198Y315246D02*
X1035253Y315762D01*
G01X1035045Y314766D02*
X1035198Y315246D01*
G01X1034818Y314370D02*
X1035045Y314766D01*
G01X1042285Y315246D02*
X1042339Y315762D01*
G01X1042132Y314766D02*
X1042285Y315246D01*
G01X1041905Y314370D02*
X1042132Y314766D01*
G01X1049372Y315246D02*
X1049426Y315762D01*
G01X1049219Y314766D02*
X1049372Y315246D01*
G01X1048991Y314370D02*
X1049219Y314766D01*
G01X1049196Y305200D02*
G03X1049311Y305478I-279J278D01*
G01X1047950Y303954D02*
G03X1047835Y303676I279J-278D01*
G01X1024705Y305363D02*
G03X1024820Y305084I394J-1D01*
G01X1026181Y303560D02*
G03X1026066Y303839I-394J1D01*
G01X1020849Y305200D02*
G03X1020965Y305478I-278J279D01*
G01X1019604Y303954D02*
G03X1019488Y303676I278J-279D01*
G01X1032165Y312992D02*
G03I-1456J0D01*
G01X1044764D02*
G03I-1457J0D01*
G01X1016417D02*
G03I-1456J0D01*
G01X1046731Y314370D02*
G03X1048991I1130J1083D01*
G01X1039644D02*
G03X1041905I1131J1082D01*
G01X1032557D02*
G03X1034818I1131J1082D01*
G01X1025471D02*
G03X1027731I1130J1083D01*
G01X1018384D02*
G03X1020645I1131J1082D01*
G01X1011298D02*
G03X1013558I1130J1083D01*
G01X1049830Y296142D02*
G03I-1969J0D01*
G01X1028570D02*
G03I-1969J0D01*
G01X1021483D02*
G03I-1968J0D01*
G01X1042743D02*
G03I-1969J0D01*
G01X1035656D02*
G03I-1968J0D01*
G01X1014396D02*
G03I-1968J0D01*
G01X996358Y305363D02*
G03X996474Y305084I394J0D01*
G01X997835Y303560D02*
G03X997719Y303839I-394J0D01*
G01X992503Y305200D02*
G03X992618Y305478I-279J278D01*
G01X991257Y303954D02*
G03X991142Y303676I279J-278D01*
G01X968012Y305363D02*
G03X968127Y305084I394J-1D01*
G01X969488Y303560D02*
G03X969373Y303839I-394J1D01*
G01X1003819Y312992D02*
G03I-1457J0D01*
G01X975472D02*
G03I-1456J0D01*
G01X988071D02*
G03I-1457J0D01*
G01X1004211Y314370D02*
G03X1006472I1131J1082D01*
G01X997124D02*
G03X999385I1131J1082D01*
G01X990038D02*
G03X992298I1130J1083D01*
G01X982951D02*
G03X985212I1131J1082D01*
G01X975865D02*
G03X978125I1130J1083D01*
G01X968778D02*
G03X971039I1131J1082D01*
G01X1000223Y296142D02*
G03I-1968J0D01*
G01X993137D02*
G03I-1969J0D01*
G01X971877D02*
G03I-1969J0D01*
G01X1007310D02*
G03I-1969J0D01*
G01X986050D02*
G03I-1968J0D01*
G01X978963D02*
G03I-1968J0D01*
G01X1049196Y305200D02*
X1047950Y303954D01*
G01X1040420Y323031D02*
X1039239Y321850D01*
G01X1020849Y305200D02*
X1019604Y303954D01*
G01X1033333Y323031D02*
X1032152Y321850D01*
G01X1012074Y323031D02*
X1010893Y321850D01*
G01X992503Y305200D02*
X991257Y303954D01*
G01X1004987Y323031D02*
X1003806Y321850D01*
G01X983727Y323031D02*
X982546Y321850D01*
G01X976641Y323031D02*
X975459Y321850D01*
G01X1049426Y321457D02*
Y315298D01*
G01X1049311Y324016D02*
Y305478D01*
G01X1046296Y321457D02*
Y315298D01*
G01X1042339Y321457D02*
Y315298D01*
G01X1042310Y321850D02*
Y310570D01*
G01X1039239D02*
Y321850D01*
G01X1039209Y321457D02*
Y315298D01*
G01X1035253Y321457D02*
Y315298D01*
G01X1035223Y321850D02*
Y310570D01*
G01X1032152D02*
Y321850D01*
G01X1032123Y321457D02*
Y315298D01*
G01X1028166Y321457D02*
Y315298D01*
G01X1025036Y321457D02*
Y315298D01*
G01X1024705Y324016D02*
Y305363D01*
G01X1021080Y321457D02*
Y315298D01*
G01X1020965Y324016D02*
Y305478D01*
G01X1017950Y321457D02*
Y315298D01*
G01X1013993Y321457D02*
Y315298D01*
G01X1013963Y321850D02*
Y310570D01*
G01X1010893D02*
Y321850D01*
G01X1010863Y321457D02*
Y315298D01*
G01X1006906Y321457D02*
Y315298D01*
G01X1006877Y321850D02*
Y310570D01*
G01X1003806D02*
Y321850D01*
G01X1003776Y321457D02*
Y315298D01*
G01X999820Y321457D02*
Y315298D01*
G01X996690Y321457D02*
Y315298D01*
G01X996358Y324016D02*
Y305363D01*
G01X992733Y321457D02*
Y315298D01*
G01X992618Y324016D02*
Y305478D01*
G01X989603Y321457D02*
Y315298D01*
G01X985646Y321457D02*
Y315298D01*
G01X985617Y321850D02*
Y310570D01*
G01X982546D02*
Y321850D01*
G01X982517Y321457D02*
Y315298D01*
G01X978560Y321457D02*
Y315298D01*
G01X978530Y321850D02*
Y310570D01*
G01X975459D02*
Y321850D01*
G01X975430Y321457D02*
Y315298D01*
G01X971473Y321457D02*
Y315298D01*
G01X968343Y321457D02*
Y315298D01*
G01X968012Y324016D02*
Y305363D01*
G01X1041129Y323031D02*
X1042310Y321850D01*
G01X1034042Y323031D02*
X1035223Y321850D01*
G01X1012782Y323031D02*
X1013963Y321850D01*
G01X1024820Y305084D02*
X1026066Y303839D01*
G01X1005696Y323031D02*
X1006877Y321850D01*
G01X984436Y323031D02*
X985617Y321850D01*
G01X996474Y305084D02*
X997719Y303839D01*
G01X977349Y323031D02*
X978530Y321850D01*
G01X968127Y305084D02*
X969373Y303839D01*
G01X992618Y324016D02*
X968012D01*
G01X1020965D02*
X996358D01*
G01X1049311D02*
X1024705D01*
G01X977349Y323031D02*
X976641D01*
G01X984436D02*
X983727D01*
G01X1005696D02*
X1004987D01*
G01X1012782D02*
X1012074D01*
G01X1034042D02*
X1033333D01*
G01X1041129D02*
X1040420D01*
G01X978530Y321850D02*
X975459D01*
G01X985617D02*
X982546D01*
G01X1006877D02*
X1003806D01*
G01X1013963D02*
X1010893D01*
G01X1035223D02*
X1032152D01*
G01X1042310D02*
X1039239D01*
G01X1050853Y321457D02*
X966375D01*
G01X992618Y320669D02*
X968012D01*
G01X1020965D02*
X996358D01*
G01X1049311D02*
X1024705D01*
G01X966375Y319094D02*
X1050853D01*
G01X971039Y314370D02*
X975865D01*
G01X968778D02*
X966375D01*
G01X982951D02*
X978125D01*
G01X990038D02*
X985212D01*
G01X997124D02*
X992298D01*
G01X1004211D02*
X999385D01*
G01X1011298D02*
X1006472D01*
G01X1018384D02*
X1013558D01*
G01X1025471D02*
X1020645D01*
G01X1032557D02*
X1027731D01*
G01X1039644D02*
X1034818D01*
G01X1046731D02*
X1041905D01*
G01X1050853D02*
X1048991D01*
G01X975459Y310570D02*
X968012D01*
G01X982546D02*
X978530D01*
G01X992618D02*
X985617D01*
G01X1003806D02*
X996358D01*
G01X1010893D02*
X1006877D01*
G01X1020965D02*
X1013963D01*
G01X1032152D02*
X1024705D01*
G01X1039239D02*
X1035223D01*
G01X1049311D02*
X1042310D01*
G01X971398Y718788D02*
G03X978323Y705657I37662J11471D01*
G01X971398Y718788D02*
G03X978323Y705657I37662J11470D01*
G01X971398Y987292D02*
G03X978323Y974161I37662J11471D01*
G01X971398Y987292D02*
G03X978323Y974161I37662J11470D01*
G01X984252Y1515748D02*
G03X980315Y1519685I-3937J0D01*
G01X972441Y1503937D02*
G03Y1496063I0J-3937D01*
G01X984252Y1503937D02*
X972441D01*
G01X984252Y1515748D02*
Y1503937D01*
G01Y1515748D02*
G03X980315Y1519685I-3937J0D01*
G01X972441Y1503937D02*
G03Y1496063I0J-3937D01*
G01X988189D02*
G03X992126Y1500000I0J3937D01*
G01Y1515748D02*
Y1500000D01*
G01X996063Y1519685D02*
G03X992126Y1515748I0J-3937D01*
G01X1059196Y1519685D02*
X996063D01*
G01X984252Y1515748D02*
Y1503937D01*
G01D02*
X972441D01*
G01X988189Y1496063D02*
G03X992126Y1500000I0J3937D01*
G01X996063Y1519685D02*
G03X992126Y1515748I0J-3937D01*
G01X1059196Y1519685D02*
X996063D01*
G01X992126Y1515748D02*
Y1500000D01*
G01X1137274Y-369410D02*
Y-388347D01*
G01X1085225Y-1400D02*
Y1400D01*
G01X1053730Y-1400D02*
Y1400D01*
G01X1133071Y189764D02*
G03Y181890I0J-3937D01*
G01X1102362D02*
G03Y189764I0J3937D01*
G01X1133071Y181890D02*
X1216535D01*
G01X1062992D02*
X1102362D01*
G01X1133071D02*
X1216535D01*
G01X1133071Y189764D02*
G03Y181890I0J-3937D01*
G01X1102362D02*
G03Y189764I0J3937D01*
G01X1062992Y181890D02*
X1102362D01*
G01X1062992Y189764D02*
X1220472D01*
G01X1059055Y193701D02*
G03X1062992Y189764I3937J0D01*
G01X1059055Y244094D02*
Y193701D01*
G01Y244094D02*
G03X1055118Y248031I-3937J0D01*
G01X1059055Y244094D02*
G03X1055118Y248031I-3937J0D01*
G01X1059055Y193701D02*
G03X1062992Y189764I3937J0D01*
G01X1059055Y244094D02*
Y193701D01*
G01X1062992Y189764D02*
X1220472D01*
G01X1132428Y1133819D02*
G03X1131444Y1134803I-984J0D01*
G01X1121089Y1132638D02*
G03I-1456J0D01*
G01X1127782D02*
G03I-1456J0D01*
G01X1131444Y1117874D02*
G03X1132428Y1118858I0J984D01*
G01X1121089Y1120039D02*
G03I-1456J0D01*
G01X1127782D02*
G03I-1456J0D01*
G01X1096286Y1134803D02*
G03X1095302Y1133819I0J-984D01*
G01X1109554Y1132638D02*
G03I-1457J0D01*
G01X1102861D02*
G03I-1457J0D01*
G01X1095302Y1118858D02*
G03X1096286Y1117874I984J0D01*
G01X1109554Y1120039D02*
G03I-1457J0D01*
G01X1102861D02*
G03I-1457J0D01*
G01X1130656Y1117087D02*
X1132428Y1115315D01*
G01X1112724Y1127814D02*
X1111247Y1129291D01*
G01X1115006Y1124863D02*
X1116483Y1123386D01*
G01X1095302Y1137362D02*
X1097074Y1135591D01*
G01X1095302Y1137362D02*
X1132428D01*
G01X1095302Y1136969D02*
X1132428D01*
G01X1095302Y1136575D02*
X1132428D01*
G01X1095302Y1135984D02*
X1132428D01*
G01X1097074Y1135591D02*
X1130656D01*
G01X1096286Y1134803D02*
X1131444D01*
G01X1095302Y1133819D02*
X1094711D01*
G01X1133019D02*
X1132428D01*
G01X1115006Y1133622D02*
X1129475D01*
G01X1098255D02*
X1112724D01*
G01X1095302Y1131457D02*
X1094711D01*
G01X1133019D02*
X1132428D01*
G01X1116483Y1131063D02*
X1129475D01*
G01X1111247D02*
X1098255D01*
G01X1111247Y1129291D02*
X1098255D01*
G01X1129475D02*
X1116483D01*
G01X1112724Y1127814D02*
X1098255D01*
G01X1129475D02*
X1115006D01*
G01Y1124863D02*
X1129475D01*
G01X1098255D02*
X1112724D01*
G01X1116483Y1123386D02*
X1129475D01*
G01X1098255D02*
X1111247D01*
G01Y1121614D02*
X1098255D01*
G01X1129475D02*
X1116483D01*
G01X1095302Y1121220D02*
X1094711D01*
G01X1133019D02*
X1132428D01*
G01X1112724Y1119055D02*
X1098255D01*
G01X1129475D02*
X1115006D01*
G01X1095302Y1118858D02*
X1094711D01*
G01X1133019D02*
X1132428D01*
G01X1131444Y1117874D02*
X1096286D01*
G01X1097074Y1117087D02*
X1130656D01*
G01X1132428Y1116693D02*
X1095302D01*
G01Y1116102D02*
X1132428D01*
G01Y1115709D02*
X1095302D01*
G01Y1115315D02*
X1132428D01*
G01X1116483Y1131063D02*
X1115006Y1133622D01*
G01X1111247Y1121614D02*
X1112724Y1119055D01*
G01X1133019Y1121220D02*
Y1118858D01*
G01Y1133819D02*
Y1131457D01*
G01X1132428Y1137362D02*
Y1115315D01*
G01X1130656Y1135591D02*
Y1117087D01*
G01X1129475Y1124863D02*
Y1119055D01*
G01Y1133622D02*
Y1127814D01*
G01X1116483Y1121614D02*
Y1123386D01*
G01Y1131063D02*
Y1129291D01*
G01X1115006Y1127814D02*
Y1133622D01*
G01Y1119055D02*
Y1124863D01*
G01X1112724D02*
Y1119055D01*
G01Y1133622D02*
Y1127814D01*
G01X1111247Y1123386D02*
Y1121614D01*
G01Y1131063D02*
Y1129291D01*
G01X1098255Y1127814D02*
Y1133622D01*
G01Y1119055D02*
Y1124863D01*
G01X1097074Y1135591D02*
Y1117087D01*
G01X1095302Y1137362D02*
Y1115315D01*
G01X1094711Y1121220D02*
Y1118858D01*
G01Y1133819D02*
Y1131457D01*
G01X1116483Y1121614D02*
X1115006Y1119055D01*
G01X1111247Y1131063D02*
X1112724Y1133622D01*
G01X1130656Y1135591D02*
X1132428Y1137362D01*
G01X1111247Y1123386D02*
X1112724Y1124863D01*
G01X1116483Y1129291D02*
X1115006Y1127814D01*
G01X1097074Y1117087D02*
X1095302Y1115315D01*
G01X1104528Y1155354D02*
G03Y1169134I0J6890D01*
G01D02*
G03Y1155354I0J-6890D01*
G01X1111417Y1162244D02*
G03I-6889J0D01*
G01X1072638Y1421260D02*
Y1506243D01*
G01Y1421260D02*
G03X1076575Y1417322I3937J-1D01*
G01X1085630Y1417323D02*
X1076575D01*
G01X1085630D02*
G03X1089567Y1421260I0J3937D01*
G01Y1506243D02*
Y1421260D01*
G01X1072638D02*
G03X1076575Y1417323I3937J0D01*
G01X1085630D02*
G03X1089567Y1421260I0J3937D01*
G01X1076575Y1417323D02*
X1085630D01*
G01X1089567Y1506243D02*
Y1421260D01*
G01X1072638Y1506243D02*
Y1421260D01*
G01X1061980Y1518532D02*
G03X1059196Y1519685I-2784J-2784D01*
G01X1071485Y1509027D02*
X1061980Y1518532D01*
G01X1072638Y1506243D02*
G03X1071485Y1509027I-3937J0D01*
G01X1090720D02*
G03X1089567Y1506243I2784J-2784D01*
G01X1100225Y1518532D02*
X1090720Y1509027D01*
G01X1103009Y1519685D02*
G03X1100225Y1518532I0J-3937D01*
G01X1207283Y1519685D02*
X1103009D01*
G01X1061980Y1518532D02*
G03X1059196Y1519685I-2784J-2784D01*
G01X1072638Y1506243D02*
G03X1071485Y1509027I-3937J0D01*
G01X1090720D02*
G03X1089567Y1506243I2784J-2784D01*
G01X1103009Y1519685D02*
G03X1100225Y1518532I0J-3937D01*
G01X1207283Y1519685D02*
X1103009D01*
G01X1095866Y1491339D02*
X1092913Y1492913D01*
G01X1066339Y1485039D02*
X1069291Y1483465D01*
G01Y1496063D02*
X1055118D01*
G01X1107087D02*
X1092913D01*
G01X1054528Y1495472D02*
X1066339D01*
G01X1107677D02*
X1095866D01*
G01X1056299Y1490945D02*
X1055118D01*
G01X1107087D02*
X1105906D01*
G01X1095866Y1490748D02*
X1107677D01*
G01X1066339D02*
X1054528D01*
G01X1095866Y1485630D02*
X1107677D01*
G01X1066339D02*
X1054528D01*
G01X1055118Y1485433D02*
X1056299D01*
G01X1107087D02*
X1105906D01*
G01X1054528Y1480906D02*
X1066339D01*
G01X1107677D02*
X1095866D01*
G01X1092913Y1480315D02*
X1107087D01*
G01X1055118D02*
X1069291D01*
G01X1061980Y1518532D02*
X1071485Y1509027D01*
G01X1107677Y1490748D02*
Y1495472D01*
G01Y1485630D02*
Y1480906D01*
G01X1107087Y1496063D02*
Y1480315D01*
G01X1105906Y1490945D02*
Y1485433D01*
G01X1098387Y1496063D02*
Y1480315D01*
G01X1095866Y1480906D02*
Y1485039D01*
G01Y1491339D02*
Y1485039D01*
G01Y1495472D02*
Y1491339D01*
G01X1092913Y1496063D02*
Y1480315D01*
G01X1069291D02*
Y1496063D01*
G01X1066339Y1480906D02*
Y1485039D01*
G01Y1491339D02*
Y1485039D01*
G01Y1495472D02*
Y1491339D01*
G01X1063818Y1480315D02*
Y1496063D01*
G01X1056299Y1485433D02*
Y1490945D01*
G01X1055118Y1496063D02*
Y1480315D01*
G01X1054528Y1490748D02*
Y1495472D01*
G01Y1485630D02*
Y1480906D01*
G01X1100225Y1518532D02*
X1090720Y1509027D01*
G01X1095866Y1485039D02*
X1092913Y1483465D01*
G01X1066339Y1491339D02*
X1069291Y1492913D01*
G01X1137274Y1808346D02*
Y1789409D01*
G01X1224409Y23622D02*
G03X1216535I-3937J0D01*
G01Y54331D02*
G03X1224409I3937J0D01*
G01X1212598Y0D02*
G03X1216535Y3937I0J3937D01*
G01Y54331D02*
Y181890D01*
G01Y3937D02*
Y23622D01*
G01Y54331D02*
Y181890D01*
G01X1224409Y23622D02*
G03X1216535I-3937J0D01*
G01Y54331D02*
G03X1224409I3937J0D01*
G01X1212598Y0D02*
G03X1216535Y3937I0J3937D01*
G01X1228346Y0D02*
X1930906D01*
G01X1224409Y3937D02*
G03X1228346Y0I3937J0D01*
G01X1224409Y185827D02*
Y3937D01*
G01X1216535D02*
Y23622D01*
G01X1224409Y3937D02*
G03X1228346Y0I3937J0D01*
G01X1224409Y3937D02*
Y185827D01*
G01X1228346Y0D02*
X1930906D01*
G01X1191454Y158304D02*
G03I-4291J0D01*
G01D02*
G03I-4291J0D01*
G01X1224409Y185827D02*
G03X1220472Y189764I-3937J0D01*
G01X1224409Y185827D02*
G03X1220472Y189764I-3937J0D01*
G01X1241732Y260630D02*
G03X1242913I591J0D01*
G01Y254331D02*
G03X1241732I-590J0D01*
G01X1239764D02*
G03X1238583I-590J0D01*
G01Y260630D02*
G03X1239764I591J0D01*
G01X1241732D02*
G03X1242913I591J0D01*
G01Y254331D02*
G03X1241732I-590J0D01*
G01X1239764D02*
G03X1238583I-590J0D01*
G01Y260630D02*
G03X1239764I591J0D01*
G01X1243701Y254331D02*
Y260630D01*
G01Y254331D02*
Y260630D01*
G01X1237795Y254331D02*
Y260630D01*
G01D02*
Y254331D01*
G01X1241732Y260630D02*
X1239764D01*
G01X1238583D02*
X1237795D01*
G01X1241732D02*
X1239764D01*
G01X1238583D02*
X1237795D01*
G01X1243701D02*
X1242913D01*
G01X1243701D02*
X1242913D01*
G01X1243701Y259646D02*
X1237795D01*
G01Y259449D02*
X1243701D01*
G01X1237795Y255512D02*
X1243701D01*
G01Y255315D02*
X1237795D01*
G01X1242913Y254331D02*
X1243701D01*
G01X1242913D02*
X1243701D01*
G01X1239764D02*
X1241732D01*
G01X1237795D02*
X1238583D01*
G01X1239764D02*
X1241732D01*
G01X1237795D02*
X1238583D01*
G01X1164984Y383609D02*
G03X1198795I16906J-13530D01*
G01X1164984D02*
G03X1198795I16906J-13530D01*
G01X1191870Y396741D02*
G03X1198795Y383610I37662J11471D01*
G01X1191870Y396741D02*
G03X1171909I-9980J-3040D01*
G01X1164984Y383610D02*
G03X1171909Y396741I-30737J24602D01*
G01X1191870D02*
G03X1198795Y383609I37663J11469D01*
G01X1191870Y396741D02*
G03X1171909I-9980J-3040D01*
G01X1164984Y383609D02*
G03X1171909Y396741I-30737J24601D01*
G01X1241732Y713386D02*
G03X1242913I591J0D01*
G01Y707087D02*
G03X1241732I-590J0D01*
G01X1239764D02*
G03X1238583I-590J0D01*
G01Y713386D02*
G03X1239764I591J0D01*
G01X1241732D02*
G03X1242913I591J0D01*
G01Y707087D02*
G03X1241732I-590J0D01*
G01X1239764D02*
G03X1238583I-590J0D01*
G01Y713386D02*
G03X1239764I591J0D01*
G01X1243701Y707087D02*
Y713386D01*
G01Y707087D02*
Y713386D01*
G01X1237795Y707087D02*
Y713386D01*
G01D02*
Y707087D01*
G01X1241732Y713386D02*
X1239764D01*
G01X1238583D02*
X1237795D01*
G01X1241732D02*
X1239764D01*
G01X1238583D02*
X1237795D01*
G01X1243701D02*
X1242913D01*
G01X1243701D02*
X1242913D01*
G01X1243701Y712402D02*
X1237795D01*
G01Y712205D02*
X1243701D01*
G01X1237795Y708268D02*
X1243701D01*
G01Y708071D02*
X1237795D01*
G01X1242913Y707087D02*
X1243701D01*
G01X1242913D02*
X1243701D01*
G01X1239764D02*
X1241732D01*
G01X1237795D02*
X1238583D01*
G01X1239764D02*
X1241732D01*
G01X1237795D02*
X1238583D01*
G01X1164984Y974161D02*
G03X1198795I16906J-13531D01*
G01X1164984D02*
G03X1198795I16906J-13531D01*
G01X1191870Y987292D02*
G03X1198795Y974161I37662J11471D01*
G01X1191870Y987292D02*
G03X1171909I-9980J-3040D01*
G01X1164984Y974161D02*
G03X1171909Y987292I-30737J24602D01*
G01X1191870D02*
G03X1198795Y974161I37662J11471D01*
G01X1191870Y987292D02*
G03X1171909I-9980J-3040D01*
G01X1164984Y974161D02*
G03X1171909Y987292I-30737J24601D01*
G01X1211220Y1515748D02*
G03X1207283Y1519685I-3937J0D01*
G01X1211220Y1509055D02*
Y1515748D01*
G01Y1509055D02*
G03X1215157Y1505118I3937J0D01*
G01X1240748D02*
X1215157D01*
G01X1240748D02*
G03X1244685Y1509055I0J3937D01*
G01X1211220D02*
G03X1215157Y1505118I3937J0D01*
G01X1240748D02*
G03X1244685Y1509055I0J3937D01*
G01X1211220Y1515748D02*
G03X1207283Y1519685I-3937J0D01*
G01X1215157Y1505118D02*
X1240748D01*
G01X1211220Y1515748D02*
Y1509055D01*
G01X1272778Y84941D02*
X1272773Y84921D01*
G01X1272793Y84955D02*
X1272778Y84941D01*
G01X1272813Y84961D02*
X1272793Y84955D01*
G01X1272778Y88091D02*
X1272773Y88071D01*
G01X1272793Y88105D02*
X1272778Y88091D01*
G01X1272813Y88110D02*
X1272793Y88105D01*
G01X1273753Y83799D02*
X1273758Y83819D01*
G01X1273739Y83785D02*
X1273753Y83799D01*
G01X1273719Y83780D02*
X1273739Y83785D01*
G01X1273753Y86949D02*
X1273758Y86969D01*
G01X1273739Y86934D02*
X1273753Y86949D01*
G01X1273719Y86929D02*
X1273739Y86934D01*
G01X1273753Y90098D02*
X1273758Y90118D01*
G01X1273739Y90084D02*
X1273753Y90098D01*
G01X1273719Y90079D02*
X1273739Y90084D01*
G01X1272778Y91240D02*
X1272773Y91220D01*
G01X1272793Y91254D02*
X1272778Y91240D01*
G01X1272813Y91260D02*
X1272793Y91254D01*
G01X1273753Y93248D02*
X1273758Y93268D01*
G01X1273739Y93233D02*
X1273753Y93248D01*
G01X1273719Y93228D02*
X1273739Y93233D01*
G01X1273737Y83772D02*
X1273741Y83774D01*
G01X1273734Y83770D02*
X1273737Y83772D01*
G01X1273731Y83770D02*
X1273734D01*
G01X1273728Y83769D02*
X1273731Y83770D01*
G01X1273724Y83769D02*
X1273728D01*
G01X1273720Y83768D02*
X1273724Y83769D01*
G01X1272798Y84968D02*
X1272795Y84967D01*
G01X1272801Y84969D02*
X1272798Y84968D01*
G01X1272805Y84970D02*
X1272801Y84969D01*
G01X1272808Y84971D02*
X1272805Y84970D01*
G01X1272811Y84972D02*
X1272808Y84971D01*
G01X1272815Y84972D02*
X1272811D01*
G01X1273737Y86921D02*
X1273741Y86923D01*
G01X1273734Y86920D02*
X1273737Y86921D01*
G01X1273731Y86919D02*
X1273734Y86920D01*
G01X1273728Y86919D02*
X1273731D01*
G01X1273724Y86918D02*
X1273728Y86919D01*
G01X1273720Y86918D02*
X1273724D01*
G01X1272798Y88118D02*
X1272795Y88116D01*
G01X1272801Y88119D02*
X1272798Y88118D01*
G01X1272805Y88120D02*
X1272801Y88119D01*
G01X1272808Y88121D02*
X1272805Y88120D01*
G01X1272811Y88121D02*
X1272808D01*
G01X1272815D02*
X1272811D01*
G01X1273737Y90071D02*
X1273741Y90073D01*
G01X1273734Y90070D02*
X1273737Y90071D01*
G01X1273731Y90069D02*
X1273734Y90070D01*
G01X1273728Y90068D02*
X1273731Y90069D01*
G01X1273724Y90068D02*
X1273728D01*
G01X1273720Y90067D02*
X1273724Y90068D01*
G01X1272798Y91267D02*
X1272795Y91266D01*
G01X1272801Y91269D02*
X1272798Y91267D01*
G01X1272805Y91270D02*
X1272801Y91269D01*
G01X1272808Y91270D02*
X1272805D01*
G01X1272811Y91271D02*
X1272808Y91270D01*
G01X1272815Y91271D02*
X1272811D01*
G01X1273737Y93220D02*
X1273741Y93222D01*
G01X1273734Y93219D02*
X1273737Y93220D01*
G01X1273731Y93219D02*
X1273734D01*
G01X1273728Y93218D02*
X1273731Y93219D01*
G01X1273724Y93217D02*
X1273728Y93218D01*
G01X1273720Y93217D02*
X1273724D01*
G01X1273750Y84959D02*
X1273754Y84954D01*
G01X1273746Y84963D02*
X1273750Y84959D01*
G01X1273740Y84967D02*
X1273746Y84963D01*
G01X1273734Y84970D02*
X1273740Y84967D01*
G01X1273727Y84971D02*
X1273734Y84970D01*
G01X1273720Y84972D02*
X1273727Y84971D01*
G01X1273750Y88109D02*
X1273754Y88103D01*
G01X1273746Y88113D02*
X1273750Y88109D01*
G01X1273740Y88117D02*
X1273746Y88113D01*
G01X1273734Y88119D02*
X1273740Y88117D01*
G01X1273727Y88121D02*
X1273734Y88119D01*
G01X1273720Y88121D02*
X1273727D01*
G01X1272776Y83798D02*
Y83805D01*
G01X1272779Y83791D02*
X1272776Y83798D01*
G01X1272782Y83785D02*
X1272779Y83791D01*
G01X1272787Y83779D02*
X1272782Y83785D01*
G01X1272793Y83774D02*
X1272787Y83779D01*
G01X1272800Y83771D02*
X1272793Y83774D01*
G01X1272807Y83769D02*
X1272800Y83771D01*
G01X1272815Y83768D02*
X1272807Y83769D01*
G01X1273750Y91258D02*
X1273754Y91253D01*
G01X1273746Y91263D02*
X1273750Y91258D01*
G01X1273740Y91266D02*
X1273746Y91263D01*
G01X1273734Y91269D02*
X1273740Y91266D01*
G01X1273727Y91270D02*
X1273734Y91269D01*
G01X1273720Y91271D02*
X1273727Y91270D01*
G01X1272776Y86948D02*
Y86955D01*
G01X1272779Y86941D02*
X1272776Y86948D01*
G01X1272782Y86934D02*
X1272779Y86941D01*
G01X1272787Y86929D02*
X1272782Y86934D01*
G01X1272793Y86924D02*
X1272787Y86929D01*
G01X1272800Y86920D02*
X1272793Y86924D01*
G01X1272807Y86919D02*
X1272800Y86920D01*
G01X1272815Y86918D02*
X1272807Y86919D01*
G01X1272776Y90097D02*
Y90104D01*
G01X1272779Y90090D02*
X1272776Y90097D01*
G01X1272782Y90084D02*
X1272779Y90090D01*
G01X1272787Y90078D02*
X1272782Y90084D01*
G01X1272793Y90074D02*
X1272787Y90078D01*
G01X1272800Y90070D02*
X1272793Y90074D01*
G01X1272807Y90068D02*
X1272800Y90070D01*
G01X1272815Y90067D02*
X1272807Y90068D01*
G01X1272776Y93247D02*
Y93254D01*
G01X1272779Y93240D02*
X1272776Y93247D01*
G01X1272782Y93233D02*
X1272779Y93240D01*
G01X1272787Y93228D02*
X1272782Y93233D01*
G01X1272793Y93223D02*
X1272787Y93228D01*
G01X1272800Y93220D02*
X1272793Y93223D01*
G01X1272807Y93218D02*
X1272800Y93220D01*
G01X1272815Y93217D02*
X1272807Y93218D01*
G01X1273730Y84959D02*
X1273739Y84955D01*
G01X1273719Y84961D02*
X1273730Y84959D01*
G01Y88109D02*
X1273739Y88105D01*
G01X1273719Y88110D02*
X1273730Y88109D01*
G01Y91258D02*
X1273739Y91254D01*
G01X1273719Y91260D02*
X1273730Y91258D01*
G01X1287172Y51999D02*
X1287183Y51984D01*
G01X1287148Y52008D02*
X1287172Y51999D01*
G01X1272776Y86959D02*
Y86955D01*
G01X1272777Y86952D02*
X1272776Y86959D01*
G01X1272789Y86937D02*
X1272777Y86952D01*
G01X1272814Y86929D02*
X1272789Y86937D01*
G01X1272776Y90108D02*
Y90104D01*
G01X1272777Y90102D02*
X1272776Y90108D01*
G01X1272789Y90087D02*
X1272777Y90102D01*
G01X1272813Y90079D02*
X1272789Y90087D01*
G01X1272776Y83809D02*
Y83806D01*
G01X1272777Y83803D02*
X1272776Y83809D01*
G01X1272789Y83788D02*
X1272777Y83803D01*
G01X1272813Y83780D02*
X1272789Y83788D01*
G01X1287172Y56999D02*
X1287183Y56984D01*
G01X1287148Y57008D02*
X1287172Y56999D01*
G01Y61999D02*
X1287183Y61984D01*
G01X1287148Y62008D02*
X1287172Y61999D01*
G01Y66999D02*
X1287183Y66984D01*
G01X1287148Y67008D02*
X1287172Y66999D01*
G01Y71999D02*
X1287183Y71984D01*
G01X1287148Y72008D02*
X1287172Y71999D01*
G01Y76999D02*
X1287183Y76984D01*
G01X1287148Y77008D02*
X1287172Y76999D01*
G01Y81999D02*
X1287183Y81984D01*
G01X1287148Y82008D02*
X1287172Y81999D01*
G01X1272776Y93258D02*
Y93254D01*
G01X1272777Y93252D02*
X1272776Y93258D01*
G01X1272787Y93238D02*
X1272777Y93252D01*
G01X1272810Y93228D02*
X1272787Y93238D01*
G01X1273728Y91259D02*
X1273719Y91260D01*
G01X1273737Y91256D02*
X1273728Y91259D01*
G01X1273745Y91250D02*
X1273737Y91256D01*
G01X1273728Y84959D02*
X1273719Y84961D01*
G01X1273737Y84956D02*
X1273728Y84959D01*
G01X1273745Y84951D02*
X1273737Y84956D01*
G01X1273728Y88109D02*
X1273719Y88110D01*
G01X1273737Y88106D02*
X1273728Y88109D01*
G01X1273745Y88100D02*
X1273737Y88106D01*
G01X1272815Y83774D02*
Y83768D01*
G01X1272814Y83778D02*
X1272815Y83774D01*
G01X1272813Y83780D02*
X1272814Y83778D01*
G01X1272815Y86924D02*
Y86918D01*
G01X1272814Y86928D02*
X1272815Y86924D01*
G01X1272813Y86929D02*
X1272814Y86928D01*
G01X1272815Y90074D02*
Y90067D01*
G01X1272814Y90078D02*
X1272815Y90074D01*
G01X1272813Y90079D02*
X1272814Y90078D01*
G01X1272815Y93223D02*
Y93217D01*
G01X1272814Y93227D02*
X1272815Y93223D01*
G01X1272813Y93228D02*
X1272814Y93227D01*
G01X1287185Y51975D02*
Y51982D01*
G01X1287186Y51970D02*
X1287185Y51975D01*
G01X1287187Y51969D02*
X1287186Y51970D01*
G01X1287185Y56975D02*
Y56982D01*
G01X1287186Y56970D02*
X1287185Y56975D01*
G01X1287187Y56969D02*
X1287186Y56970D01*
G01X1287185Y61975D02*
Y61982D01*
G01X1287186Y61970D02*
X1287185Y61975D01*
G01X1287187Y61969D02*
X1287186Y61970D01*
G01X1287185Y66975D02*
Y66982D01*
G01X1287186Y66970D02*
X1287185Y66975D01*
G01X1287187Y66969D02*
X1287186Y66970D01*
G01X1287185Y71975D02*
Y71982D01*
G01X1287186Y71970D02*
X1287185Y71975D01*
G01X1287187Y71969D02*
X1287186Y71970D01*
G01X1287185Y76975D02*
Y76982D01*
G01X1287186Y76970D02*
X1287185Y76975D01*
G01X1287187Y76969D02*
X1287186Y76970D01*
G01X1287185Y81975D02*
Y81982D01*
G01X1287186Y81970D02*
X1287185Y81975D01*
G01X1287187Y81969D02*
X1287186Y81970D01*
G01X1272798Y86931D02*
X1272813Y86929D01*
G01X1272787Y86939D02*
X1272798Y86931D01*
G01X1272775Y86957D02*
X1272787Y86939D01*
G01X1272798Y90081D02*
X1272813Y90079D01*
G01X1272786Y90089D02*
X1272798Y90081D01*
G01X1272774Y90109D02*
X1272786Y90089D01*
G01X1273760Y83813D02*
Y83805D01*
G01X1273759Y83817D02*
X1273760Y83813D01*
G01X1273758Y83819D02*
X1273759Y83817D01*
G01X1273760Y86963D02*
Y86955D01*
G01X1273759Y86967D02*
X1273760Y86963D01*
G01X1273758Y86969D02*
X1273759Y86967D01*
G01X1273760Y90112D02*
Y90104D01*
G01X1273759Y90117D02*
X1273760Y90112D01*
G01X1273758Y90118D02*
X1273759Y90117D01*
G01X1273760Y93262D02*
Y93254D01*
G01X1273759Y93266D02*
X1273760Y93262D01*
G01X1273758Y93268D02*
X1273759Y93266D01*
G01X1272798Y83782D02*
X1272813Y83780D01*
G01X1272785Y83791D02*
X1272798Y83782D01*
G01X1272774Y83811D02*
X1272785Y83791D01*
G01X1273759Y84941D02*
X1273760Y84935D01*
G01X1273757Y84948D02*
X1273759Y84941D01*
G01X1273754Y84954D02*
X1273757Y84948D01*
G01X1273759Y88091D02*
X1273760Y88084D01*
G01X1273757Y88097D02*
X1273759Y88091D01*
G01X1273754Y88103D02*
X1273757Y88097D01*
G01X1273759Y91241D02*
X1273760Y91234D01*
G01X1273757Y91247D02*
X1273759Y91241D01*
G01X1273754Y91253D02*
X1273757Y91247D01*
G01X1273721Y83774D02*
Y83768D01*
G01X1273720Y83778D02*
X1273721Y83774D01*
G01X1273719Y83780D02*
X1273720Y83778D01*
G01X1273721Y86924D02*
Y86918D01*
G01X1273720Y86928D02*
X1273721Y86924D01*
G01X1273719Y86929D02*
X1273720Y86928D01*
G01X1273721Y90074D02*
Y90067D01*
G01X1273720Y90077D02*
X1273721Y90074D01*
G01X1273719Y90079D02*
X1273720Y90077D01*
G01X1273721Y93223D02*
Y93217D01*
G01X1273720Y93227D02*
X1273721Y93223D01*
G01X1273719Y93228D02*
X1273720Y93227D01*
G01X1286201Y52015D02*
Y52024D01*
G01X1286202Y52009D02*
X1286201Y52015D01*
G01X1286202Y52008D02*
Y52009D01*
G01X1286201Y57015D02*
Y57024D01*
G01X1286202Y57009D02*
X1286201Y57015D01*
G01X1286202Y57008D02*
Y57009D01*
G01X1286201Y62015D02*
Y62024D01*
G01X1286202Y62009D02*
X1286201Y62015D01*
G01X1286202Y62008D02*
Y62009D01*
G01X1286201Y67015D02*
Y67024D01*
G01X1286202Y67009D02*
X1286201Y67015D01*
G01X1286202Y67008D02*
Y67009D01*
G01X1286201Y72015D02*
Y72024D01*
G01X1286202Y72009D02*
X1286201Y72015D01*
G01X1286202Y72008D02*
Y72009D01*
G01X1286201Y77015D02*
Y77024D01*
G01X1286202Y77009D02*
X1286201Y77015D01*
G01X1286202Y77008D02*
Y77009D01*
G01X1286201Y82015D02*
Y82024D01*
G01X1286202Y82009D02*
X1286201Y82015D01*
G01X1286202Y82008D02*
Y82009D01*
G01X1287177Y52152D02*
X1287185Y52125D01*
G01X1287167Y52178D02*
X1287177Y52152D01*
G01X1287156Y52205D02*
X1287167Y52178D01*
G01X1287177Y57152D02*
X1287185Y57125D01*
G01X1287167Y57178D02*
X1287177Y57152D01*
G01X1287156Y57205D02*
X1287167Y57178D01*
G01X1287177Y62152D02*
X1287185Y62125D01*
G01X1287167Y62178D02*
X1287177Y62152D01*
G01X1287156Y62205D02*
X1287167Y62178D01*
G01X1287177Y67152D02*
X1287185Y67125D01*
G01X1287167Y67178D02*
X1287177Y67152D01*
G01X1287156Y67205D02*
X1287167Y67178D01*
G01X1287177Y72152D02*
X1287185Y72125D01*
G01X1287167Y72178D02*
X1287177Y72152D01*
G01X1287156Y72205D02*
X1287167Y72178D01*
G01X1287177Y77152D02*
X1287185Y77125D01*
G01X1287167Y77178D02*
X1287177Y77152D01*
G01X1287156Y77205D02*
X1287167Y77178D01*
G01X1287177Y82152D02*
X1287185Y82125D01*
G01X1287167Y82178D02*
X1287177Y82152D01*
G01X1287156Y82205D02*
X1287167Y82178D01*
G01X1272793Y93233D02*
X1272813Y93228D01*
G01X1272780Y93246D02*
X1272793Y93233D01*
G01X1272773Y93263D02*
X1272780Y93246D01*
G01X1287168Y52003D02*
X1287148Y52008D01*
G01X1287182Y51988D02*
X1287168Y52003D01*
G01X1287187Y51969D02*
X1287182Y51988D01*
G01X1287168Y57003D02*
X1287148Y57008D01*
G01X1287182Y56988D02*
X1287168Y57003D01*
G01X1287187Y56969D02*
X1287182Y56988D01*
G01X1287168Y62003D02*
X1287148Y62008D01*
G01X1287182Y61988D02*
X1287168Y62003D01*
G01X1287187Y61969D02*
X1287182Y61988D01*
G01X1287168Y67003D02*
X1287148Y67008D01*
G01X1287182Y66988D02*
X1287168Y67003D01*
G01X1287187Y66969D02*
X1287182Y66988D01*
G01X1287168Y72003D02*
X1287148Y72008D01*
G01X1287182Y71988D02*
X1287168Y72003D01*
G01X1287187Y71969D02*
X1287182Y71988D01*
G01X1287168Y77003D02*
X1287148Y77008D01*
G01X1287182Y76988D02*
X1287168Y77003D01*
G01X1287187Y76969D02*
X1287182Y76988D01*
G01X1287168Y82003D02*
X1287148Y82008D01*
G01X1287182Y81988D02*
X1287168Y82003D01*
G01X1287187Y81969D02*
X1287182Y81988D01*
G01X1273752Y91242D02*
X1273745Y91250D01*
G01X1273757Y91231D02*
X1273752Y91242D01*
G01X1273759Y91220D02*
X1273757Y91231D01*
G01X1273752Y84943D02*
X1273745Y84951D01*
G01X1273757Y84932D02*
X1273752Y84943D01*
G01X1273759Y84921D02*
X1273757Y84932D01*
G01X1273752Y88092D02*
X1273745Y88100D01*
G01X1273757Y88082D02*
X1273752Y88092D01*
G01X1273759Y88071D02*
X1273757Y88082D01*
G01X1287152Y52106D02*
X1287156Y52205D01*
G01X1287146Y52034D02*
X1287152Y52106D01*
G01X1287148Y52008D02*
X1287146Y52034D01*
G01X1287152Y57106D02*
X1287156Y57205D01*
G01X1287146Y57034D02*
X1287152Y57106D01*
G01X1287148Y57008D02*
X1287146Y57034D01*
G01X1287152Y62106D02*
X1287156Y62205D01*
G01X1287146Y62034D02*
X1287152Y62106D01*
G01X1287148Y62008D02*
X1287146Y62034D01*
G01X1287152Y67106D02*
X1287156Y67205D01*
G01X1287146Y67034D02*
X1287152Y67106D01*
G01X1287148Y67008D02*
X1287146Y67034D01*
G01X1287152Y72106D02*
X1287156Y72205D01*
G01X1287146Y72034D02*
X1287152Y72106D01*
G01X1287148Y72008D02*
X1287146Y72034D01*
G01X1287152Y77106D02*
X1287156Y77205D01*
G01X1287146Y77034D02*
X1287152Y77106D01*
G01X1287148Y77008D02*
X1287146Y77034D01*
G01X1287152Y82106D02*
X1287156Y82205D01*
G01X1287146Y82034D02*
X1287152Y82106D01*
G01X1287148Y82008D02*
X1287146Y82034D01*
G01X1272816Y91444D02*
X1272815Y91457D01*
G01X1272813Y91431D02*
X1272816Y91444D01*
G01X1272813Y91417D02*
Y91431D01*
G01X1272816Y88294D02*
X1272815Y88307D01*
G01X1272813Y88281D02*
X1272816Y88294D01*
G01X1272813Y88268D02*
Y88281D01*
G01X1272816Y85145D02*
X1272815Y85157D01*
G01X1272813Y85132D02*
X1272816Y85145D01*
G01X1272813Y85118D02*
Y85132D01*
G01X1286202Y80628D02*
Y80630D01*
G01X1286201Y80622D02*
X1286202Y80628D01*
G01X1286201Y80614D02*
Y80622D01*
G01X1286202Y75628D02*
Y75630D01*
G01X1286201Y75622D02*
X1286202Y75628D01*
G01X1286201Y75614D02*
Y75622D01*
G01X1286202Y70628D02*
Y70630D01*
G01X1286201Y70622D02*
X1286202Y70628D01*
G01X1286201Y70614D02*
Y70622D01*
G01X1286202Y65628D02*
Y65630D01*
G01X1286201Y65622D02*
X1286202Y65628D01*
G01X1286201Y65614D02*
Y65622D01*
G01X1286202Y60628D02*
Y60630D01*
G01X1286201Y60622D02*
X1286202Y60628D01*
G01X1286201Y60614D02*
Y60622D01*
G01X1286202Y55628D02*
Y55630D01*
G01X1286201Y55622D02*
X1286202Y55628D01*
G01X1286201Y55614D02*
Y55622D01*
G01X1286202Y50628D02*
Y50630D01*
G01X1286201Y50622D02*
X1286202Y50628D01*
G01X1286201Y50614D02*
Y50622D01*
G01X1272813Y93057D02*
X1272811Y93070D01*
G01X1272816Y93044D02*
X1272813Y93057D01*
G01X1272815Y93031D02*
X1272816Y93044D01*
G01X1272813Y89907D02*
X1272811Y89921D01*
G01X1272816Y89894D02*
X1272813Y89907D01*
G01X1272815Y89882D02*
X1272816Y89894D01*
G01X1272813Y86757D02*
X1272811Y86771D01*
G01X1272816Y86745D02*
X1272813Y86757D01*
G01X1272815Y86732D02*
X1272816Y86745D01*
G01X1272813Y83608D02*
X1272811Y83622D01*
G01X1272816Y83595D02*
X1272813Y83608D01*
G01X1272815Y83583D02*
X1272816Y83595D01*
G01X1273723Y91431D02*
X1273724Y91417D01*
G01X1273720Y91444D02*
X1273723Y91431D01*
G01X1273720Y91457D02*
Y91444D01*
G01X1273723Y88281D02*
X1273724Y88268D01*
G01X1273720Y88294D02*
X1273723Y88281D01*
G01X1273720Y88307D02*
Y88294D01*
G01X1273723Y85132D02*
X1273724Y85118D01*
G01X1273720Y85145D02*
X1273723Y85132D01*
G01X1273720Y85157D02*
Y85145D01*
G01X1272775Y90112D02*
X1272776Y90105D01*
G01X1272774Y90117D02*
X1272775Y90112D01*
G01X1272774Y90109D02*
Y90117D01*
G01X1273720Y93044D02*
Y93031D01*
G01X1273722Y93057D02*
X1273720Y93044D01*
G01X1273724Y93070D02*
X1273722Y93057D01*
G01X1273720Y89894D02*
Y89882D01*
G01X1273722Y89907D02*
X1273720Y89894D01*
G01X1273724Y89921D02*
X1273722Y89907D01*
G01X1273720Y86745D02*
Y86732D01*
G01X1273722Y86757D02*
X1273720Y86745D01*
G01X1273724Y86771D02*
X1273722Y86757D01*
G01X1273720Y83595D02*
Y83583D01*
G01X1273722Y83608D02*
X1273720Y83595D01*
G01X1273724Y83622D02*
X1273722Y83608D01*
G01X1272775Y83813D02*
X1272776Y83806D01*
G01X1272774Y83817D02*
X1272775Y83813D01*
G01X1272774Y83811D02*
Y83817D01*
G01X1272789Y91251D02*
X1272813Y91260D01*
G01X1272778Y91237D02*
X1272789Y91251D01*
G01X1272776Y91230D02*
X1272778Y91237D01*
G01X1272789Y88102D02*
X1272813Y88110D01*
G01X1272778Y88087D02*
X1272789Y88102D01*
G01X1272776Y88080D02*
X1272778Y88087D01*
G01X1272789Y84952D02*
X1272813Y84961D01*
G01X1272778Y84937D02*
X1272789Y84952D01*
G01X1272776Y84931D02*
X1272778Y84937D01*
G01X1273760Y91227D02*
Y91234D01*
G01X1273759Y91222D02*
X1273760Y91227D01*
G01X1273759Y91220D02*
Y91222D01*
G01X1273760Y88077D02*
Y88084D01*
G01X1273759Y88072D02*
X1273760Y88077D01*
G01X1273759Y88071D02*
Y88072D01*
G01X1273760Y84928D02*
Y84935D01*
G01X1273759Y84923D02*
X1273760Y84928D01*
G01X1273759Y84921D02*
Y84923D01*
G01X1272775Y93262D02*
X1272776Y93254D01*
G01X1272774Y93266D02*
X1272775Y93262D01*
G01X1272773Y93263D02*
X1272774Y93266D01*
G01X1272775Y86963D02*
X1272776Y86955D01*
G01X1272774Y86967D02*
X1272775Y86963D01*
G01X1272773Y86965D02*
X1272774Y86967D01*
G01X1273720Y91265D02*
Y91271D01*
G01Y91261D02*
Y91265D01*
G01X1273719Y91260D02*
X1273720Y91261D01*
G01Y88115D02*
Y88121D01*
G01Y88111D02*
Y88115D01*
G01X1273719Y88110D02*
X1273720Y88111D01*
G01Y84966D02*
Y84972D01*
G01Y84962D02*
Y84966D01*
G01X1273719Y84961D02*
X1273720Y84962D01*
G01X1287185Y80622D02*
Y80613D01*
G01X1287186Y80628D02*
X1287185Y80622D01*
G01X1287188Y80630D02*
X1287186Y80628D01*
G01X1287185Y75622D02*
Y75613D01*
G01X1287186Y75628D02*
X1287185Y75622D01*
G01X1287188Y75630D02*
X1287186Y75628D01*
G01X1287185Y70622D02*
Y70613D01*
G01X1287186Y70628D02*
X1287185Y70622D01*
G01X1287188Y70630D02*
X1287186Y70628D01*
G01X1287185Y65622D02*
Y65613D01*
G01X1287186Y65628D02*
X1287185Y65622D01*
G01X1287188Y65630D02*
X1287186Y65628D01*
G01X1287185Y60622D02*
Y60613D01*
G01X1287186Y60628D02*
X1287185Y60622D01*
G01X1287188Y60630D02*
X1287186Y60628D01*
G01X1287185Y55622D02*
Y55613D01*
G01X1287186Y55628D02*
X1287185Y55622D01*
G01X1287188Y55630D02*
X1287186Y55628D01*
G01X1287185Y50622D02*
Y50613D01*
G01X1287186Y50628D02*
X1287185Y50622D01*
G01X1287188Y50630D02*
X1287186Y50628D01*
G01X1272775Y91226D02*
X1272776Y91234D01*
G01X1272774Y91222D02*
X1272775Y91226D01*
G01X1272773Y91220D02*
X1272774Y91222D01*
G01X1272775Y88077D02*
X1272776Y88084D01*
G01X1272774Y88072D02*
X1272775Y88077D01*
G01X1272773Y88071D02*
X1272774Y88072D01*
G01X1272775Y84927D02*
X1272776Y84935D01*
G01X1272774Y84923D02*
X1272775Y84927D01*
G01X1272773Y84921D02*
X1272774Y84923D01*
G01X1273757Y93242D02*
X1273760Y93254D01*
G01X1273751Y93230D02*
X1273757Y93242D01*
G01X1273741Y93222D02*
X1273751Y93230D01*
G01X1273757Y90092D02*
X1273760Y90104D01*
G01X1273751Y90081D02*
X1273757Y90092D01*
G01X1273741Y90073D02*
X1273751Y90081D01*
G01X1273757Y86943D02*
X1273760Y86955D01*
G01X1273751Y86931D02*
X1273757Y86943D01*
G01X1273741Y86923D02*
X1273751Y86931D01*
G01X1273757Y83793D02*
X1273760Y83805D01*
G01X1273751Y83781D02*
X1273757Y83793D01*
G01X1273741Y83774D02*
X1273751Y83781D01*
G01X1272814Y91265D02*
Y91271D01*
G01Y91261D02*
Y91265D01*
G01X1272813Y91260D02*
X1272814Y91261D01*
G01Y88115D02*
Y88121D01*
G01Y88111D02*
Y88115D01*
G01X1272813Y88110D02*
X1272814Y88111D01*
G01Y84965D02*
Y84972D01*
G01Y84962D02*
Y84965D01*
G01X1272813Y84961D02*
X1272814Y84962D01*
G01X1272776Y91240D02*
Y91234D01*
G01X1272778Y91246D02*
X1272776Y91240D01*
G01X1272781Y91252D02*
X1272778Y91246D01*
G01X1272785Y91257D02*
X1272781Y91252D01*
G01X1272789Y91262D02*
X1272785Y91257D01*
G01X1272795Y91266D02*
X1272789Y91262D01*
G01X1272776Y88091D02*
Y88084D01*
G01X1272778Y88097D02*
X1272776Y88091D01*
G01X1272781Y88103D02*
X1272778Y88097D01*
G01X1272785Y88108D02*
X1272781Y88103D01*
G01X1272789Y88113D02*
X1272785Y88108D01*
G01X1272795Y88116D02*
X1272789Y88113D01*
G01X1272776Y84941D02*
Y84935D01*
G01X1272778Y84947D02*
X1272776Y84941D01*
G01X1272781Y84953D02*
X1272778Y84947D01*
G01X1272785Y84958D02*
X1272781Y84953D01*
G01X1272789Y84963D02*
X1272785Y84958D01*
G01X1272795Y84967D02*
X1272789Y84963D01*
G01X1273731Y93230D02*
X1273719Y93228D01*
G01X1273741Y93235D02*
X1273731Y93230D01*
G01Y90081D02*
X1273719Y90079D01*
G01X1273741Y90085D02*
X1273731Y90081D01*
G01Y86931D02*
X1273719Y86929D01*
G01X1273741Y86936D02*
X1273731Y86931D01*
G01Y83781D02*
X1273719Y83780D01*
G01X1273741Y83786D02*
X1273731Y83781D01*
G01X1336713Y55118D02*
G03X1350689I6988J0D01*
G01D02*
G03X1336713I-6988J0D01*
G01X1350689D02*
G03I-6988J0D01*
G01X1277756Y25138D02*
G03X1278346Y24547I591J0D01*
G01X1285039D02*
G03X1285630Y25138I0J591D01*
G01X1282874Y26319D02*
G03Y28287I0J984D01*
G01X1280512D02*
G03Y26319I0J-984D01*
G01X1282795Y39508D02*
G03I-1102J0D01*
G01X1284252Y34232D02*
G03X1285433Y35413I0J1181D01*
G01X1277953D02*
G03X1279134Y34232I1181J0D01*
G01X1283268Y39508D02*
G03I-1575J0D01*
G01X1270866Y25728D02*
G03X1272835Y23760I1968J0D01*
G01X1290551D02*
G03X1292520Y25728I0J1969D01*
G01X1277165Y47500D02*
X1275984Y46319D01*
G01X1274213Y44823D02*
X1270866Y41476D01*
G01X1284178Y42579D02*
X1282874Y40610D01*
G01X1278202Y34688D02*
X1280512Y38917D01*
G01X1273759Y84923D02*
X1273760Y84935D01*
G01X1273759Y88073D02*
X1273760Y88084D01*
G01X1273759Y91222D02*
X1273760Y91234D01*
G01X1287185Y51982D02*
Y51991D01*
G01Y56982D02*
Y56991D01*
G01Y61982D02*
Y61991D01*
G01Y66982D02*
Y66991D01*
G01Y71982D02*
Y71991D01*
G01Y76982D02*
Y76991D01*
G01Y81982D02*
Y81991D01*
G01X1292520Y25728D02*
Y41476D01*
G01X1291535Y80630D02*
Y82008D01*
G01Y75630D02*
Y77008D01*
G01Y70630D02*
Y72008D01*
G01Y65630D02*
Y67008D01*
G01Y60630D02*
Y62008D01*
G01Y55630D02*
Y57008D01*
G01Y50630D02*
Y52008D01*
G01X1289173Y182815D02*
Y44823D01*
G01X1288583Y185059D02*
Y42579D01*
G01X1288366Y52008D02*
Y50630D01*
G01Y57008D02*
Y55630D01*
G01Y62008D02*
Y60630D01*
G01Y67008D02*
Y65630D01*
G01Y72008D02*
Y70630D01*
G01Y77008D02*
Y75630D01*
G01Y82008D02*
Y80630D01*
G01X1287795Y104862D02*
Y82776D01*
G01X1287185Y51982D02*
Y52125D01*
G01Y56982D02*
Y57125D01*
G01Y61982D02*
Y62125D01*
G01Y66982D02*
Y67125D01*
G01Y71982D02*
Y72125D01*
G01Y76982D02*
Y77125D01*
G01Y81982D02*
Y82125D01*
G01Y80138D02*
Y82500D01*
G01Y75138D02*
Y77500D01*
G01Y70138D02*
Y72500D01*
G01Y65138D02*
Y67500D01*
G01Y60138D02*
Y62500D01*
G01Y55138D02*
Y57500D01*
G01Y50138D02*
Y52500D01*
G01X1286614Y103681D02*
Y83957D01*
G01X1286201Y52500D02*
Y50138D01*
G01Y57500D02*
Y55138D01*
G01Y62500D02*
Y60138D01*
G01Y67500D02*
Y65138D01*
G01Y72500D02*
Y70138D01*
G01Y77500D02*
Y75138D01*
G01Y82500D02*
Y80138D01*
G01X1285630Y31240D02*
Y25138D01*
G01X1285433Y43957D02*
Y35413D01*
G01X1283858Y82776D02*
Y46319D01*
G01X1282874Y40610D02*
Y38917D01*
G01X1282677Y83957D02*
Y47500D01*
G01X1280512Y38917D02*
Y40610D01*
G01X1277953Y35413D02*
Y43957D01*
G01X1277756Y31240D02*
Y25138D01*
G01X1277165Y47500D02*
Y180138D01*
G01X1275984Y46319D02*
Y181319D01*
G01X1274213Y81614D02*
Y42579D01*
G01X1273760Y93070D02*
Y94567D01*
G01Y89921D02*
Y91417D01*
G01Y86771D02*
Y88268D01*
G01Y83622D02*
Y85118D01*
G01X1273720Y86918D02*
Y86771D01*
G01Y83768D02*
Y83621D01*
G01Y85119D02*
Y84972D01*
G01Y90067D02*
Y89920D01*
G01Y91418D02*
Y91271D01*
G01Y88268D02*
Y88121D01*
G01Y93217D02*
Y93070D01*
G01X1272815D02*
Y93217D01*
G01Y89920D02*
Y90067D01*
G01Y91271D02*
Y91418D01*
G01Y88121D02*
Y88268D01*
G01Y86771D02*
Y86918D01*
G01Y83621D02*
Y83768D01*
G01Y84972D02*
Y85119D01*
G01X1272776Y85118D02*
Y83622D01*
G01Y91417D02*
Y89921D01*
G01Y88268D02*
Y86772D01*
G01Y94567D02*
Y93071D01*
G01X1271594Y88110D02*
Y86929D01*
G01Y84961D02*
Y83780D01*
G01Y91260D02*
Y90079D01*
G01Y94409D02*
Y93228D01*
G01X1271260Y106024D02*
Y81614D01*
G01X1270866D02*
Y106024D01*
G01Y41476D02*
Y25728D01*
G01X1267835Y93228D02*
Y94409D01*
G01Y90079D02*
Y91260D01*
G01Y86929D02*
Y88110D01*
G01Y83780D02*
Y84961D01*
G01X1273760Y93254D02*
X1273759Y93265D01*
G01X1273760Y90105D02*
X1273759Y90115D01*
G01X1273760Y86955D02*
X1273759Y86966D01*
G01X1273760Y83806D02*
X1273759Y83816D01*
G01X1282874Y38917D02*
X1285184Y34688D01*
G01X1280512Y40610D02*
X1279208Y42579D01*
G01X1286614Y83957D02*
X1287795Y82776D01*
G01X1282677Y83957D02*
X1283858Y82776D01*
G01X1289173Y44823D02*
X1292520Y41476D01*
G01X1282677Y47500D02*
X1283858Y46319D01*
G01X1272773Y93263D02*
X1272662Y93268D01*
G01X1272773Y86965D02*
X1272662Y86969D01*
G01X1272028Y93268D02*
X1271594D01*
G01X1273758D02*
X1267835D01*
G01X1273719Y93228D02*
X1267835D01*
G01X1272776Y93071D02*
X1273760D01*
G01X1272815Y93031D02*
X1273720D01*
G01Y91457D02*
X1272815D01*
G01X1273760Y91417D02*
X1272776D01*
G01X1273719Y91260D02*
X1267835D01*
G01Y91220D02*
X1273759D01*
G01X1273758Y90118D02*
X1267835D01*
G01X1273719Y90079D02*
X1267835D01*
G01X1272776Y89921D02*
X1273760D01*
G01X1272815Y89882D02*
X1273720D01*
G01Y88307D02*
X1272815D01*
G01X1273760Y88268D02*
X1272776D01*
G01X1273719Y88110D02*
X1267835D01*
G01Y88071D02*
X1273759D01*
G01X1272028Y86969D02*
X1271594D01*
G01X1273758D02*
X1267835D01*
G01X1273719Y86929D02*
X1267835D01*
G01X1272776Y86772D02*
X1273760D01*
G01X1272815Y86732D02*
X1273720D01*
G01Y85157D02*
X1272815D01*
G01X1273760Y85118D02*
X1272776D01*
G01X1273719Y84961D02*
X1267835D01*
G01Y84921D02*
X1273759D01*
G01X1286614Y83957D02*
X1282677D01*
G01X1273758Y83819D02*
X1267835D01*
G01X1273719Y83780D02*
X1267835D01*
G01X1272776Y83622D02*
X1273760D01*
G01X1272815Y83583D02*
X1273720D01*
G01X1287795Y82776D02*
X1283858D01*
G01X1287185Y82500D02*
X1286201D01*
G01X1286202Y82008D02*
X1291535D01*
G01Y81969D02*
X1287187D01*
G01X1274213Y81614D02*
X1270866D01*
G01X1291535Y80630D02*
X1286202D01*
G01X1286201Y80138D02*
X1287185D01*
G01Y77500D02*
X1286201D01*
G01X1286202Y77008D02*
X1291535D01*
G01Y76969D02*
X1287187D01*
G01X1291535Y75630D02*
X1286202D01*
G01X1286201Y75138D02*
X1287185D01*
G01Y72500D02*
X1286201D01*
G01X1286202Y72008D02*
X1291535D01*
G01Y71969D02*
X1287187D01*
G01X1291535Y70630D02*
X1286202D01*
G01X1286201Y70138D02*
X1287185D01*
G01Y67500D02*
X1286201D01*
G01X1286202Y67008D02*
X1291535D01*
G01Y66969D02*
X1287187D01*
G01X1291535Y65630D02*
X1286202D01*
G01X1286201Y65138D02*
X1287185D01*
G01Y62500D02*
X1286201D01*
G01X1286202Y62008D02*
X1291535D01*
G01Y61969D02*
X1287187D01*
G01X1291535Y60630D02*
X1286202D01*
G01X1286201Y60138D02*
X1287185D01*
G01Y57500D02*
X1286201D01*
G01X1286202Y57008D02*
X1291535D01*
G01Y56969D02*
X1287187D01*
G01X1291535Y55630D02*
X1286202D01*
G01X1286201Y55138D02*
X1287185D01*
G01Y52500D02*
X1286201D01*
G01X1286202Y52008D02*
X1291535D01*
G01Y51969D02*
X1287187D01*
G01X1291535Y50630D02*
X1286202D01*
G01X1286201Y50138D02*
X1287185D01*
G01X1282677Y47500D02*
X1277165D01*
G01X1283858Y46319D02*
X1275984D01*
G01X1289173Y44823D02*
X1274213D01*
G01X1285433Y43957D02*
X1288583D01*
G01X1277953D02*
X1274213D01*
G01Y42579D02*
X1288583D01*
G01X1282874Y40610D02*
X1280512D01*
G01X1282874Y38917D02*
X1280512D01*
G01X1286201Y82204D02*
X1287156Y82205D01*
G01X1287185Y80434D02*
X1286201Y80433D01*
G01Y77204D02*
X1287156Y77205D01*
G01X1287185Y75434D02*
X1286201Y75433D01*
G01Y72204D02*
X1287156Y72205D01*
G01X1287185Y70434D02*
X1286201Y70433D01*
G01Y67204D02*
X1287156Y67205D01*
G01X1287185Y65434D02*
X1286201Y65433D01*
G01Y62204D02*
X1287156Y62205D01*
G01X1287185Y60434D02*
X1286201Y60433D01*
G01Y57204D02*
X1287156Y57205D01*
G01X1287185Y55434D02*
X1286201Y55433D01*
G01Y52204D02*
X1287156Y52205D01*
G01X1287185Y50434D02*
X1286201Y50433D01*
G01X1284252Y34232D02*
X1279134D01*
G01X1292520Y34193D02*
X1270866D01*
G01X1285630Y31240D02*
X1277756D01*
G01Y29665D02*
X1285630D01*
G01X1282874Y28287D02*
X1280512D01*
G01Y26319D02*
X1282874D01*
G01X1285039Y24547D02*
X1278346D01*
G01X1290551Y23760D02*
X1272835D01*
G01X1272778Y94390D02*
X1272773Y94370D01*
G01X1272793Y94404D02*
X1272778Y94390D01*
G01X1272813Y94409D02*
X1272793Y94404D01*
G01X1272778Y97539D02*
X1272773Y97520D01*
G01X1272793Y97554D02*
X1272778Y97539D01*
G01X1272813Y97559D02*
X1272793Y97554D01*
G01X1272778Y100689D02*
X1272773Y100669D01*
G01X1272793Y100703D02*
X1272778Y100689D01*
G01X1272813Y100709D02*
X1272793Y100703D01*
G01X1272778Y103839D02*
X1272773Y103819D01*
G01X1272793Y103853D02*
X1272778Y103839D01*
G01X1272813Y103858D02*
X1272793Y103853D01*
G01X1273753Y96398D02*
X1273758Y96417D01*
G01X1273739Y96383D02*
X1273753Y96398D01*
G01X1273719Y96378D02*
X1273739Y96383D01*
G01X1273753Y99547D02*
X1273758Y99567D01*
G01X1273739Y99533D02*
X1273753Y99547D01*
G01X1273719Y99528D02*
X1273739Y99533D01*
G01X1273753Y102697D02*
X1273758Y102717D01*
G01X1273739Y102682D02*
X1273753Y102697D01*
G01X1273719Y102677D02*
X1273739Y102682D01*
G01X1273759Y99546D02*
X1273760Y99553D01*
G01X1273757Y99539D02*
X1273759Y99546D01*
G01X1273753Y99533D02*
X1273757Y99539D01*
G01X1273748Y99527D02*
X1273753Y99533D01*
G01X1273742Y99522D02*
X1273748Y99527D01*
G01X1273735Y99519D02*
X1273742Y99522D01*
G01X1273728Y99517D02*
X1273735Y99519D01*
G01X1273720Y99516D02*
X1273728Y99517D01*
G01X1272798Y94417D02*
X1272795Y94415D01*
G01X1272801Y94418D02*
X1272798Y94417D01*
G01X1272805Y94419D02*
X1272801Y94418D01*
G01X1272808Y94420D02*
X1272805Y94419D01*
G01X1272811Y94420D02*
X1272808D01*
G01X1272815D02*
X1272811D01*
G01X1273737Y96370D02*
X1273741Y96372D01*
G01X1273734Y96369D02*
X1273737Y96370D01*
G01X1273731Y96368D02*
X1273734Y96369D01*
G01X1273728Y96367D02*
X1273731Y96368D01*
G01X1273724Y96367D02*
X1273728D01*
G01X1273720D02*
X1273724D01*
G01X1272798Y97567D02*
X1272795Y97565D01*
G01X1272801Y97568D02*
X1272798Y97567D01*
G01X1272805Y97569D02*
X1272801Y97568D01*
G01X1272808Y97570D02*
X1272805Y97569D01*
G01X1272811Y97570D02*
X1272808D01*
G01X1272815D02*
X1272811D01*
G01X1272798Y100716D02*
X1272795Y100715D01*
G01X1272801Y100717D02*
X1272798Y100716D01*
G01X1272805Y100719D02*
X1272801Y100717D01*
G01X1272808Y100719D02*
X1272805D01*
G01X1272811Y100720D02*
X1272808Y100719D01*
G01X1272815Y100720D02*
X1272811D01*
G01X1273737Y102669D02*
X1273741Y102671D01*
G01X1273734Y102668D02*
X1273737Y102669D01*
G01X1273731Y102667D02*
X1273734Y102668D01*
G01X1273728Y102667D02*
X1273731D01*
G01X1273724Y102666D02*
X1273728Y102667D01*
G01X1273720Y102666D02*
X1273724D01*
G01X1272798Y103866D02*
X1272795Y103864D01*
G01X1272801Y103867D02*
X1272798Y103866D01*
G01X1272805Y103868D02*
X1272801Y103867D01*
G01X1272808Y103869D02*
X1272805Y103868D01*
G01X1272811Y103869D02*
X1272808D01*
G01X1272815D02*
X1272811D01*
G01X1273750Y94408D02*
X1273754Y94402D01*
G01X1273746Y94412D02*
X1273750Y94408D01*
G01X1273740Y94416D02*
X1273746Y94412D01*
G01X1273734Y94419D02*
X1273740Y94416D01*
G01X1273727Y94420D02*
X1273734Y94419D01*
G01X1273720Y94420D02*
X1273727D01*
G01X1273750Y97557D02*
X1273754Y97552D01*
G01X1273746Y97562D02*
X1273750Y97557D01*
G01X1273740Y97565D02*
X1273746Y97562D01*
G01X1273734Y97568D02*
X1273740Y97565D01*
G01X1273727Y97570D02*
X1273734Y97568D01*
G01X1273720Y97570D02*
X1273727D01*
G01X1273750Y100707D02*
X1273754Y100702D01*
G01X1273746Y100711D02*
X1273750Y100707D01*
G01X1273740Y100715D02*
X1273746Y100711D01*
G01X1273734Y100718D02*
X1273740Y100715D01*
G01X1273727Y100719D02*
X1273734Y100718D01*
G01X1273720Y100720D02*
X1273727Y100719D01*
G01X1273750Y103857D02*
X1273754Y103851D01*
G01X1273746Y103861D02*
X1273750Y103857D01*
G01X1273740Y103865D02*
X1273746Y103861D01*
G01X1273734Y103867D02*
X1273740Y103865D01*
G01X1273727Y103869D02*
X1273734Y103867D01*
G01X1273720Y103869D02*
X1273727D01*
G01X1272776Y96396D02*
Y96404D01*
G01X1272779Y96389D02*
X1272776Y96396D01*
G01X1272782Y96383D02*
X1272779Y96389D01*
G01X1272787Y96378D02*
X1272782Y96383D01*
G01X1272793Y96373D02*
X1272787Y96378D01*
G01X1272800Y96369D02*
X1272793Y96373D01*
G01X1272807Y96367D02*
X1272800Y96369D01*
G01X1272815Y96367D02*
X1272807D01*
G01X1272776Y99546D02*
Y99553D01*
G01X1272779Y99539D02*
X1272776Y99546D01*
G01X1272782Y99533D02*
X1272779Y99539D01*
G01X1272787Y99527D02*
X1272782Y99533D01*
G01X1272793Y99522D02*
X1272787Y99527D01*
G01X1272800Y99519D02*
X1272793Y99522D01*
G01X1272807Y99517D02*
X1272800Y99519D01*
G01X1272815Y99516D02*
X1272807Y99517D01*
G01X1272776Y102696D02*
Y102703D01*
G01X1272779Y102689D02*
X1272776Y102696D01*
G01X1272782Y102682D02*
X1272779Y102689D01*
G01X1272787Y102677D02*
X1272782Y102682D01*
G01X1272793Y102672D02*
X1272787Y102677D01*
G01X1272800Y102669D02*
X1272793Y102672D01*
G01X1272807Y102667D02*
X1272800Y102669D01*
G01X1272815Y102666D02*
X1272807Y102667D01*
G01X1273730Y94408D02*
X1273739Y94404D01*
G01X1273719Y94409D02*
X1273730Y94408D01*
G01Y97557D02*
X1273739Y97554D01*
G01X1273719Y97559D02*
X1273730Y97557D01*
G01Y100707D02*
X1273739Y100703D01*
G01X1273719Y100709D02*
X1273730Y100707D01*
G01Y103857D02*
X1273739Y103853D01*
G01X1273719Y103858D02*
X1273730Y103857D01*
G01X1272776Y96407D02*
Y96404D01*
G01X1272777Y96401D02*
X1272776Y96407D01*
G01X1272789Y96386D02*
X1272777Y96401D01*
G01X1272813Y96378D02*
X1272789Y96386D01*
G01X1272776Y99557D02*
Y99553D01*
G01X1272777Y99551D02*
X1272776Y99557D01*
G01X1272789Y99536D02*
X1272777Y99551D01*
G01X1272813Y99528D02*
X1272789Y99536D01*
G01X1272776Y102707D02*
Y102703D01*
G01X1272777Y102701D02*
X1272776Y102707D01*
G01X1272789Y102685D02*
X1272777Y102701D01*
G01X1272813Y102677D02*
X1272789Y102685D01*
G01X1287172Y106999D02*
X1287183Y106984D01*
G01X1287148Y107008D02*
X1287172Y106999D01*
G01Y111999D02*
X1287183Y111984D01*
G01X1287148Y112008D02*
X1287172Y111999D01*
G01Y116999D02*
X1287183Y116984D01*
G01X1287148Y117008D02*
X1287172Y116999D01*
G01Y121999D02*
X1287183Y121984D01*
G01X1287148Y122008D02*
X1287172Y121999D01*
G01Y126999D02*
X1287183Y126984D01*
G01X1287148Y127008D02*
X1287172Y126999D01*
G01Y131999D02*
X1287183Y131984D01*
G01X1287148Y132008D02*
X1287172Y131999D01*
G01Y136999D02*
X1287183Y136984D01*
G01X1287148Y137008D02*
X1287172Y136999D01*
G01Y141999D02*
X1287183Y141984D01*
G01X1287148Y142008D02*
X1287172Y141999D01*
G01Y146999D02*
X1287183Y146984D01*
G01X1287148Y147008D02*
X1287172Y146999D01*
G01Y151999D02*
X1287183Y151984D01*
G01X1287148Y152008D02*
X1287172Y151999D01*
G01Y156999D02*
X1287183Y156984D01*
G01X1287148Y157008D02*
X1287172Y156999D01*
G01Y161999D02*
X1287183Y161984D01*
G01X1287148Y162008D02*
X1287172Y161999D01*
G01Y166999D02*
X1287183Y166984D01*
G01X1287148Y167008D02*
X1287172Y166999D01*
G01Y171999D02*
X1287183Y171984D01*
G01X1287148Y172008D02*
X1287172Y171999D01*
G01Y176999D02*
X1287183Y176984D01*
G01X1287148Y177008D02*
X1287172Y176999D01*
G01X1273728Y94408D02*
X1273719Y94409D01*
G01X1273737Y94405D02*
X1273728Y94408D01*
G01X1273745Y94400D02*
X1273737Y94405D01*
G01X1273728Y97558D02*
X1273719Y97559D01*
G01X1273737Y97555D02*
X1273728Y97558D01*
G01X1273745Y97549D02*
X1273737Y97555D01*
G01X1273728Y100707D02*
X1273719Y100709D01*
G01X1273737Y100704D02*
X1273728Y100707D01*
G01X1273745Y100699D02*
X1273737Y100704D01*
G01X1273728Y103857D02*
X1273719Y103858D01*
G01X1273737Y103854D02*
X1273728Y103857D01*
G01X1273745Y103848D02*
X1273737Y103854D01*
G01X1272815Y96373D02*
Y96367D01*
G01X1272814Y96377D02*
X1272815Y96373D01*
G01X1272813Y96378D02*
X1272814Y96377D01*
G01X1272815Y99522D02*
Y99516D01*
G01X1272814Y99526D02*
X1272815Y99522D01*
G01X1272813Y99528D02*
X1272814Y99526D01*
G01X1272815Y102672D02*
Y102666D01*
G01X1272814Y102676D02*
X1272815Y102672D01*
G01X1272813Y102677D02*
X1272814Y102676D01*
G01X1287185Y106975D02*
Y106982D01*
G01X1287186Y106970D02*
X1287185Y106975D01*
G01X1287187Y106969D02*
X1287186Y106970D01*
G01X1287185Y111975D02*
Y111982D01*
G01X1287186Y111970D02*
X1287185Y111975D01*
G01X1287187Y111969D02*
X1287186Y111970D01*
G01X1287185Y116975D02*
Y116982D01*
G01X1287186Y116970D02*
X1287185Y116975D01*
G01X1287187Y116969D02*
X1287186Y116970D01*
G01X1287185Y121975D02*
Y121982D01*
G01X1287186Y121970D02*
X1287185Y121975D01*
G01X1287187Y121969D02*
X1287186Y121970D01*
G01X1287185Y126975D02*
Y126982D01*
G01X1287186Y126970D02*
X1287185Y126975D01*
G01X1287187Y126969D02*
X1287186Y126970D01*
G01X1287185Y131975D02*
Y131982D01*
G01X1287186Y131970D02*
X1287185Y131975D01*
G01X1287187Y131969D02*
X1287186Y131970D01*
G01X1287185Y136975D02*
Y136982D01*
G01X1287186Y136970D02*
X1287185Y136975D01*
G01X1287187Y136969D02*
X1287186Y136970D01*
G01X1287185Y141975D02*
Y141982D01*
G01X1287186Y141970D02*
X1287185Y141975D01*
G01X1287187Y141969D02*
X1287186Y141970D01*
G01X1287185Y146975D02*
Y146982D01*
G01X1287186Y146970D02*
X1287185Y146975D01*
G01X1287187Y146969D02*
X1287186Y146970D01*
G01X1287185Y151975D02*
Y151982D01*
G01X1287186Y151970D02*
X1287185Y151975D01*
G01X1287187Y151969D02*
X1287186Y151970D01*
G01X1287185Y156975D02*
Y156982D01*
G01X1287186Y156970D02*
X1287185Y156975D01*
G01X1287187Y156969D02*
X1287186Y156970D01*
G01X1287185Y161975D02*
Y161982D01*
G01X1287186Y161970D02*
X1287185Y161975D01*
G01X1287187Y161969D02*
X1287186Y161970D01*
G01X1287185Y166975D02*
Y166982D01*
G01X1287186Y166970D02*
X1287185Y166975D01*
G01X1287187Y166969D02*
X1287186Y166970D01*
G01X1287185Y171975D02*
Y171982D01*
G01X1287186Y171970D02*
X1287185Y171975D01*
G01X1287187Y171969D02*
X1287186Y171970D01*
G01X1287185Y176975D02*
Y176982D01*
G01X1287186Y176970D02*
X1287185Y176975D01*
G01X1287187Y176969D02*
X1287186Y176970D01*
G01X1272798Y96380D02*
X1272813Y96378D01*
G01X1272787Y96388D02*
X1272798Y96380D01*
G01X1272775Y96406D02*
X1272787Y96388D01*
G01X1272798Y99530D02*
X1272813Y99528D01*
G01X1272786Y99538D02*
X1272798Y99530D01*
G01X1272774Y99558D02*
X1272786Y99538D01*
G01X1273760Y96411D02*
Y96404D01*
G01X1273759Y96416D02*
X1273760Y96411D01*
G01X1273758Y96417D02*
X1273759Y96416D01*
G01X1273760Y99561D02*
Y99553D01*
G01X1273759Y99565D02*
X1273760Y99561D01*
G01X1273758Y99567D02*
X1273759Y99565D01*
G01X1273760Y102711D02*
Y102703D01*
G01X1273759Y102715D02*
X1273760Y102711D01*
G01X1273758Y102717D02*
X1273759Y102715D01*
G01X1272798Y102680D02*
X1272813Y102677D01*
G01X1272785Y102688D02*
X1272798Y102680D01*
G01X1272774Y102708D02*
X1272785Y102688D01*
G01X1273759Y94390D02*
X1273760Y94383D01*
G01X1273757Y94396D02*
X1273759Y94390D01*
G01X1273754Y94402D02*
X1273757Y94396D01*
G01X1273759Y97540D02*
X1273760Y97533D01*
G01X1273757Y97546D02*
X1273759Y97540D01*
G01X1273754Y97552D02*
X1273757Y97546D01*
G01X1273759Y100689D02*
X1273760Y100683D01*
G01X1273757Y100696D02*
X1273759Y100689D01*
G01X1273754Y100702D02*
X1273757Y100696D01*
G01X1273759Y103839D02*
X1273760Y103832D01*
G01X1273757Y103845D02*
X1273759Y103839D01*
G01X1273754Y103851D02*
X1273757Y103845D01*
G01X1273721Y96373D02*
Y96367D01*
G01X1273720Y96376D02*
X1273721Y96373D01*
G01X1273719Y96378D02*
X1273720Y96376D01*
G01X1273721Y102672D02*
Y102666D01*
G01X1273720Y102676D02*
X1273721Y102672D01*
G01X1273719Y102677D02*
X1273720Y102676D01*
G01X1286201Y107015D02*
Y107024D01*
G01X1286202Y107009D02*
X1286201Y107015D01*
G01X1286202Y107008D02*
Y107009D01*
G01X1286201Y112015D02*
Y112024D01*
G01X1286202Y112009D02*
X1286201Y112015D01*
G01X1286202Y112008D02*
Y112009D01*
G01X1286201Y117015D02*
Y117024D01*
G01X1286202Y117009D02*
X1286201Y117015D01*
G01X1286202Y117008D02*
Y117009D01*
G01X1286201Y122015D02*
Y122024D01*
G01X1286202Y122009D02*
X1286201Y122015D01*
G01X1286202Y122008D02*
Y122009D01*
G01X1286201Y127015D02*
Y127024D01*
G01X1286202Y127009D02*
X1286201Y127015D01*
G01X1286202Y127008D02*
Y127009D01*
G01X1286201Y132015D02*
Y132024D01*
G01X1286202Y132009D02*
X1286201Y132015D01*
G01X1286202Y132008D02*
Y132009D01*
G01X1286201Y137015D02*
Y137024D01*
G01X1286202Y137009D02*
X1286201Y137015D01*
G01X1286202Y137008D02*
Y137009D01*
G01X1286201Y142015D02*
Y142024D01*
G01X1286202Y142009D02*
X1286201Y142015D01*
G01X1286202Y142008D02*
Y142009D01*
G01X1286201Y147015D02*
Y147024D01*
G01X1286202Y147009D02*
X1286201Y147015D01*
G01X1286202Y147008D02*
Y147009D01*
G01X1286201Y152015D02*
Y152024D01*
G01X1286202Y152009D02*
X1286201Y152015D01*
G01X1286202Y152008D02*
Y152009D01*
G01X1286201Y157015D02*
Y157024D01*
G01X1286202Y157009D02*
X1286201Y157015D01*
G01X1286202Y157008D02*
Y157009D01*
G01X1286201Y162015D02*
Y162024D01*
G01X1286202Y162009D02*
X1286201Y162015D01*
G01X1286202Y162008D02*
Y162009D01*
G01X1286201Y167015D02*
Y167024D01*
G01X1286202Y167009D02*
X1286201Y167015D01*
G01X1286202Y167008D02*
Y167009D01*
G01X1286201Y172015D02*
Y172024D01*
G01X1286202Y172009D02*
X1286201Y172015D01*
G01X1286202Y172008D02*
Y172009D01*
G01X1286201Y177015D02*
Y177024D01*
G01X1286202Y177009D02*
X1286201Y177015D01*
G01X1286202Y177008D02*
Y177009D01*
G01X1287177Y107152D02*
X1287185Y107125D01*
G01X1287167Y107178D02*
X1287177Y107152D01*
G01X1287156Y107205D02*
X1287167Y107178D01*
G01X1287177Y112152D02*
X1287185Y112125D01*
G01X1287167Y112178D02*
X1287177Y112152D01*
G01X1287156Y112205D02*
X1287167Y112178D01*
G01X1287177Y117152D02*
X1287185Y117125D01*
G01X1287167Y117178D02*
X1287177Y117152D01*
G01X1287156Y117205D02*
X1287167Y117178D01*
G01X1287177Y122152D02*
X1287185Y122125D01*
G01X1287167Y122178D02*
X1287177Y122152D01*
G01X1287156Y122205D02*
X1287167Y122178D01*
G01X1287177Y127152D02*
X1287185Y127125D01*
G01X1287167Y127178D02*
X1287177Y127152D01*
G01X1287156Y127205D02*
X1287167Y127178D01*
G01X1287177Y132152D02*
X1287185Y132125D01*
G01X1287167Y132178D02*
X1287177Y132152D01*
G01X1287156Y132205D02*
X1287167Y132178D01*
G01X1287177Y137152D02*
X1287185Y137125D01*
G01X1287167Y137178D02*
X1287177Y137152D01*
G01X1287156Y137205D02*
X1287167Y137178D01*
G01X1287177Y142152D02*
X1287185Y142125D01*
G01X1287167Y142178D02*
X1287177Y142152D01*
G01X1287156Y142205D02*
X1287167Y142178D01*
G01X1287177Y147152D02*
X1287185Y147125D01*
G01X1287167Y147178D02*
X1287177Y147152D01*
G01X1287156Y147205D02*
X1287167Y147178D01*
G01X1287177Y152152D02*
X1287185Y152125D01*
G01X1287167Y152178D02*
X1287177Y152152D01*
G01X1287156Y152205D02*
X1287167Y152178D01*
G01X1287177Y157152D02*
X1287185Y157125D01*
G01X1287167Y157178D02*
X1287177Y157152D01*
G01X1287156Y157205D02*
X1287167Y157178D01*
G01X1287177Y162152D02*
X1287185Y162125D01*
G01X1287167Y162178D02*
X1287177Y162152D01*
G01X1287156Y162205D02*
X1287167Y162178D01*
G01X1287177Y167152D02*
X1287185Y167125D01*
G01X1287167Y167178D02*
X1287177Y167152D01*
G01X1287156Y167205D02*
X1287167Y167178D01*
G01X1287177Y172152D02*
X1287185Y172125D01*
G01X1287167Y172178D02*
X1287177Y172152D01*
G01X1287156Y172205D02*
X1287167Y172178D01*
G01X1287177Y177152D02*
X1287185Y177125D01*
G01X1287167Y177178D02*
X1287177Y177152D01*
G01X1287156Y177205D02*
X1287167Y177178D01*
G01X1287168Y107003D02*
X1287148Y107008D01*
G01X1287182Y106988D02*
X1287168Y107003D01*
G01X1287187Y106969D02*
X1287182Y106988D01*
G01X1287168Y112003D02*
X1287148Y112008D01*
G01X1287182Y111988D02*
X1287168Y112003D01*
G01X1287187Y111969D02*
X1287182Y111988D01*
G01X1287168Y117003D02*
X1287148Y117008D01*
G01X1287182Y116988D02*
X1287168Y117003D01*
G01X1287187Y116969D02*
X1287182Y116988D01*
G01X1287168Y122003D02*
X1287148Y122008D01*
G01X1287182Y121988D02*
X1287168Y122003D01*
G01X1287187Y121969D02*
X1287182Y121988D01*
G01X1287168Y127003D02*
X1287148Y127008D01*
G01X1287182Y126988D02*
X1287168Y127003D01*
G01X1287187Y126969D02*
X1287182Y126988D01*
G01X1287168Y132003D02*
X1287148Y132008D01*
G01X1287182Y131988D02*
X1287168Y132003D01*
G01X1287187Y131969D02*
X1287182Y131988D01*
G01X1287168Y137003D02*
X1287148Y137008D01*
G01X1287182Y136988D02*
X1287168Y137003D01*
G01X1287187Y136969D02*
X1287182Y136988D01*
G01X1287168Y142003D02*
X1287148Y142008D01*
G01X1287182Y141988D02*
X1287168Y142003D01*
G01X1287187Y141969D02*
X1287182Y141988D01*
G01X1287168Y147003D02*
X1287148Y147008D01*
G01X1287182Y146988D02*
X1287168Y147003D01*
G01X1287187Y146969D02*
X1287182Y146988D01*
G01X1287168Y152003D02*
X1287148Y152008D01*
G01X1287182Y151988D02*
X1287168Y152003D01*
G01X1287187Y151969D02*
X1287182Y151988D01*
G01X1287168Y157003D02*
X1287148Y157008D01*
G01X1287182Y156988D02*
X1287168Y157003D01*
G01X1287187Y156969D02*
X1287182Y156988D01*
G01X1287168Y162003D02*
X1287148Y162008D01*
G01X1287182Y161988D02*
X1287168Y162003D01*
G01X1287187Y161969D02*
X1287182Y161988D01*
G01X1287168Y167003D02*
X1287148Y167008D01*
G01X1287182Y166988D02*
X1287168Y167003D01*
G01X1287187Y166969D02*
X1287182Y166988D01*
G01X1287168Y172003D02*
X1287148Y172008D01*
G01X1287182Y171988D02*
X1287168Y172003D01*
G01X1287187Y171969D02*
X1287182Y171988D01*
G01X1287168Y177003D02*
X1287148Y177008D01*
G01X1287182Y176988D02*
X1287168Y177003D01*
G01X1287187Y176969D02*
X1287182Y176988D01*
G01X1273752Y94391D02*
X1273745Y94400D01*
G01X1273757Y94381D02*
X1273752Y94391D01*
G01X1273759Y94370D02*
X1273757Y94381D01*
G01X1273752Y97541D02*
X1273745Y97549D01*
G01X1273757Y97531D02*
X1273752Y97541D01*
G01X1273759Y97520D02*
X1273757Y97531D01*
G01X1273752Y100691D02*
X1273745Y100699D01*
G01X1273757Y100680D02*
X1273752Y100691D01*
G01X1273759Y100669D02*
X1273757Y100680D01*
G01X1273752Y103840D02*
X1273745Y103848D01*
G01X1273757Y103830D02*
X1273752Y103840D01*
G01X1273759Y103819D02*
X1273757Y103830D01*
G01X1287152Y107106D02*
X1287156Y107205D01*
G01X1287146Y107034D02*
X1287152Y107106D01*
G01X1287148Y107008D02*
X1287146Y107034D01*
G01X1287152Y112106D02*
X1287156Y112205D01*
G01X1287146Y112034D02*
X1287152Y112106D01*
G01X1287148Y112008D02*
X1287146Y112034D01*
G01X1287152Y117106D02*
X1287156Y117205D01*
G01X1287146Y117034D02*
X1287152Y117106D01*
G01X1287148Y117008D02*
X1287146Y117034D01*
G01X1287152Y122106D02*
X1287156Y122205D01*
G01X1287146Y122034D02*
X1287152Y122106D01*
G01X1287148Y122008D02*
X1287146Y122034D01*
G01X1287152Y127106D02*
X1287156Y127205D01*
G01X1287146Y127034D02*
X1287152Y127106D01*
G01X1287148Y127008D02*
X1287146Y127034D01*
G01X1287152Y132106D02*
X1287156Y132205D01*
G01X1287146Y132034D02*
X1287152Y132106D01*
G01X1287148Y132008D02*
X1287146Y132034D01*
G01X1287152Y137106D02*
X1287156Y137205D01*
G01X1287146Y137034D02*
X1287152Y137106D01*
G01X1287148Y137008D02*
X1287146Y137034D01*
G01X1287152Y142106D02*
X1287156Y142205D01*
G01X1287146Y142034D02*
X1287152Y142106D01*
G01X1287148Y142008D02*
X1287146Y142034D01*
G01X1287152Y147106D02*
X1287156Y147205D01*
G01X1287146Y147034D02*
X1287152Y147106D01*
G01X1287148Y147008D02*
X1287146Y147034D01*
G01X1287152Y152106D02*
X1287156Y152205D01*
G01X1287146Y152034D02*
X1287152Y152106D01*
G01X1287148Y152008D02*
X1287146Y152034D01*
G01X1287152Y157106D02*
X1287156Y157205D01*
G01X1287146Y157034D02*
X1287152Y157106D01*
G01X1287148Y157008D02*
X1287146Y157034D01*
G01X1287152Y162106D02*
X1287156Y162205D01*
G01X1287146Y162034D02*
X1287152Y162106D01*
G01X1287148Y162008D02*
X1287146Y162034D01*
G01X1287152Y167106D02*
X1287156Y167205D01*
G01X1287146Y167034D02*
X1287152Y167106D01*
G01X1287148Y167008D02*
X1287146Y167034D01*
G01X1287152Y172106D02*
X1287156Y172205D01*
G01X1287146Y172034D02*
X1287152Y172106D01*
G01X1287148Y172008D02*
X1287146Y172034D01*
G01X1287152Y177106D02*
X1287156Y177205D01*
G01X1287146Y177034D02*
X1287152Y177106D01*
G01X1287148Y177008D02*
X1287146Y177034D01*
G01X1272775Y96411D02*
X1272776Y96404D01*
G01X1272774Y96416D02*
X1272775Y96411D01*
G01Y96406D02*
X1272774Y96416D01*
G01X1272816Y104043D02*
X1272815Y104055D01*
G01X1272813Y104030D02*
X1272816Y104043D01*
G01X1272813Y104016D02*
Y104030D01*
G01X1272816Y100893D02*
X1272815Y100906D01*
G01X1272813Y100880D02*
X1272816Y100893D01*
G01X1272813Y100866D02*
Y100880D01*
G01X1272816Y97743D02*
X1272815Y97756D01*
G01X1272813Y97730D02*
X1272816Y97743D01*
G01X1272813Y97717D02*
Y97730D01*
G01X1272816Y94594D02*
X1272815Y94606D01*
G01X1272813Y94581D02*
X1272816Y94594D01*
G01X1272813Y94567D02*
Y94581D01*
G01X1286202Y175628D02*
Y175630D01*
G01X1286201Y175622D02*
X1286202Y175628D01*
G01X1286201Y175614D02*
Y175622D01*
G01X1286202Y170628D02*
Y170630D01*
G01X1286201Y170622D02*
X1286202Y170628D01*
G01X1286201Y170614D02*
Y170622D01*
G01X1286202Y165628D02*
Y165630D01*
G01X1286201Y165622D02*
X1286202Y165628D01*
G01X1286201Y165614D02*
Y165622D01*
G01X1286202Y160628D02*
Y160630D01*
G01X1286201Y160622D02*
X1286202Y160628D01*
G01X1286201Y160614D02*
Y160622D01*
G01X1286202Y155628D02*
Y155630D01*
G01X1286201Y155622D02*
X1286202Y155628D01*
G01X1286201Y155614D02*
Y155622D01*
G01X1286202Y150628D02*
Y150630D01*
G01X1286201Y150622D02*
X1286202Y150628D01*
G01X1286201Y150614D02*
Y150622D01*
G01X1286202Y145628D02*
Y145630D01*
G01X1286201Y145622D02*
X1286202Y145628D01*
G01X1286201Y145614D02*
Y145622D01*
G01X1286202Y140628D02*
Y140630D01*
G01X1286201Y140622D02*
X1286202Y140628D01*
G01X1286201Y140614D02*
Y140622D01*
G01X1286202Y135628D02*
Y135630D01*
G01X1286201Y135622D02*
X1286202Y135628D01*
G01X1286201Y135614D02*
Y135622D01*
G01X1286202Y130628D02*
Y130630D01*
G01X1286201Y130622D02*
X1286202Y130628D01*
G01X1286201Y130614D02*
Y130622D01*
G01X1286202Y125628D02*
Y125630D01*
G01X1286201Y125622D02*
X1286202Y125628D01*
G01X1286201Y125614D02*
Y125622D01*
G01X1286202Y120628D02*
Y120630D01*
G01X1286201Y120622D02*
X1286202Y120628D01*
G01X1286201Y120614D02*
Y120622D01*
G01X1286202Y115628D02*
Y115630D01*
G01X1286201Y115622D02*
X1286202Y115628D01*
G01X1286201Y115614D02*
Y115622D01*
G01X1286202Y110628D02*
Y110630D01*
G01X1286201Y110622D02*
X1286202Y110628D01*
G01X1286201Y110614D02*
Y110622D01*
G01X1286202Y105628D02*
Y105630D01*
G01X1286201Y105622D02*
X1286202Y105628D01*
G01X1286201Y105614D02*
Y105622D01*
G01X1272775Y102711D02*
X1272776Y102703D01*
G01X1272774Y102715D02*
X1272775Y102711D01*
G01X1272774Y102707D02*
Y102715D01*
G01X1272813Y102506D02*
X1272811Y102519D01*
G01X1272816Y102493D02*
X1272813Y102506D01*
G01X1272815Y102480D02*
X1272816Y102493D01*
G01X1272813Y99356D02*
X1272811Y99370D01*
G01X1272816Y99343D02*
X1272813Y99356D01*
G01X1272815Y99331D02*
X1272816Y99343D01*
G01X1272813Y96206D02*
X1272811Y96220D01*
G01X1272816Y96194D02*
X1272813Y96206D01*
G01X1272815Y96181D02*
X1272816Y96194D01*
G01X1273723Y104030D02*
X1273724Y104016D01*
G01X1273720Y104043D02*
X1273723Y104030D01*
G01X1273720Y104055D02*
Y104043D01*
G01X1273723Y100880D02*
X1273724Y100866D01*
G01X1273720Y100893D02*
X1273723Y100880D01*
G01X1273720Y100906D02*
Y100893D01*
G01X1273723Y97730D02*
X1273724Y97717D01*
G01X1273720Y97743D02*
X1273723Y97730D01*
G01X1273720Y97756D02*
Y97743D01*
G01X1273723Y94581D02*
X1273724Y94567D01*
G01X1273720Y94594D02*
X1273723Y94581D01*
G01X1273720Y94606D02*
Y94594D01*
G01X1272775Y99561D02*
X1272776Y99554D01*
G01X1272774Y99565D02*
X1272775Y99561D01*
G01X1272774Y99558D02*
Y99565D01*
G01X1273720Y102493D02*
Y102480D01*
G01X1273722Y102506D02*
X1273720Y102493D01*
G01X1273724Y102519D02*
X1273722Y102506D01*
G01X1273720Y99343D02*
Y99331D01*
G01X1273722Y99356D02*
X1273720Y99343D01*
G01X1273724Y99370D02*
X1273722Y99356D01*
G01X1273720Y96194D02*
Y96181D01*
G01X1273722Y96206D02*
X1273720Y96194D01*
G01X1273724Y96220D02*
X1273722Y96206D01*
G01X1272789Y103850D02*
X1272813Y103858D01*
G01X1272778Y103835D02*
X1272789Y103850D01*
G01X1272776Y103828D02*
X1272778Y103835D01*
G01X1272789Y100700D02*
X1272813Y100709D01*
G01X1272778Y100685D02*
X1272789Y100700D01*
G01X1272776Y100679D02*
X1272778Y100685D01*
G01X1272789Y97550D02*
X1272813Y97559D01*
G01X1272778Y97536D02*
X1272789Y97550D01*
G01X1272776Y97529D02*
X1272778Y97536D01*
G01X1272789Y94401D02*
X1272813Y94409D01*
G01X1272778Y94386D02*
X1272789Y94401D01*
G01X1272776Y94380D02*
X1272778Y94386D01*
G01X1273760Y103825D02*
Y103832D01*
G01X1273759Y103820D02*
X1273760Y103825D01*
G01X1273759Y103819D02*
Y103820D01*
G01X1273760Y100676D02*
Y100683D01*
G01X1273759Y100671D02*
X1273760Y100676D01*
G01X1273759Y100669D02*
Y100671D01*
G01X1273760Y97526D02*
Y97533D01*
G01X1273759Y97521D02*
X1273760Y97526D01*
G01X1273759Y97520D02*
Y97521D01*
G01X1273760Y94376D02*
Y94383D01*
G01X1273759Y94372D02*
X1273760Y94376D01*
G01X1273759Y94370D02*
Y94372D01*
G01X1273720Y103863D02*
Y103869D01*
G01Y103859D02*
Y103863D01*
G01X1273719Y103858D02*
X1273720Y103859D01*
G01Y100714D02*
Y100720D01*
G01Y100710D02*
Y100714D01*
G01X1273719Y100709D02*
X1273720Y100710D01*
G01Y97564D02*
Y97570D01*
G01Y97560D02*
Y97564D01*
G01X1273719Y97559D02*
X1273720Y97560D01*
G01Y94415D02*
Y94420D01*
G01Y94411D02*
Y94415D01*
G01X1273719Y94409D02*
X1273720Y94411D01*
G01X1287185Y175622D02*
Y175613D01*
G01X1287186Y175628D02*
X1287185Y175622D01*
G01X1287188Y175630D02*
X1287186Y175628D01*
G01X1287185Y170622D02*
Y170613D01*
G01X1287186Y170628D02*
X1287185Y170622D01*
G01X1287188Y170630D02*
X1287186Y170628D01*
G01X1287185Y165622D02*
Y165613D01*
G01X1287186Y165628D02*
X1287185Y165622D01*
G01X1287188Y165630D02*
X1287186Y165628D01*
G01X1287185Y160622D02*
Y160613D01*
G01X1287186Y160628D02*
X1287185Y160622D01*
G01X1287188Y160630D02*
X1287186Y160628D01*
G01X1287185Y155622D02*
Y155613D01*
G01X1287186Y155628D02*
X1287185Y155622D01*
G01X1287188Y155630D02*
X1287186Y155628D01*
G01X1287185Y150622D02*
Y150613D01*
G01X1287186Y150628D02*
X1287185Y150622D01*
G01X1287188Y150630D02*
X1287186Y150628D01*
G01X1287185Y145622D02*
Y145613D01*
G01X1287186Y145628D02*
X1287185Y145622D01*
G01X1287188Y145630D02*
X1287186Y145628D01*
G01X1287185Y140622D02*
Y140613D01*
G01X1287186Y140628D02*
X1287185Y140622D01*
G01X1287188Y140630D02*
X1287186Y140628D01*
G01X1287185Y135622D02*
Y135613D01*
G01X1287186Y135628D02*
X1287185Y135622D01*
G01X1287188Y135630D02*
X1287186Y135628D01*
G01X1287185Y130622D02*
Y130613D01*
G01X1287186Y130628D02*
X1287185Y130622D01*
G01X1287188Y130630D02*
X1287186Y130628D01*
G01X1287185Y125622D02*
Y125613D01*
G01X1287186Y125628D02*
X1287185Y125622D01*
G01X1287188Y125630D02*
X1287186Y125628D01*
G01X1287185Y120622D02*
Y120613D01*
G01X1287186Y120628D02*
X1287185Y120622D01*
G01X1287188Y120630D02*
X1287186Y120628D01*
G01X1287185Y115622D02*
Y115613D01*
G01X1287186Y115628D02*
X1287185Y115622D01*
G01X1287188Y115630D02*
X1287186Y115628D01*
G01X1287185Y110622D02*
Y110613D01*
G01X1287186Y110628D02*
X1287185Y110622D01*
G01X1287188Y110630D02*
X1287186Y110628D01*
G01X1287185Y105622D02*
Y105613D01*
G01X1287186Y105628D02*
X1287185Y105622D01*
G01X1287188Y105630D02*
X1287186Y105628D01*
G01X1272775Y103825D02*
X1272776Y103832D01*
G01X1272774Y103820D02*
X1272775Y103825D01*
G01X1272773Y103819D02*
X1272774Y103820D01*
G01X1272775Y100675D02*
X1272776Y100683D01*
G01X1272774Y100671D02*
X1272775Y100675D01*
G01X1272773Y100669D02*
X1272774Y100671D01*
G01X1272775Y97526D02*
X1272776Y97533D01*
G01X1272774Y97521D02*
X1272775Y97526D01*
G01X1272773Y97520D02*
X1272774Y97521D01*
G01X1272775Y94376D02*
X1272776Y94383D01*
G01X1272774Y94372D02*
X1272775Y94376D01*
G01X1272773Y94370D02*
X1272774Y94372D01*
G01X1273757Y102691D02*
X1273760Y102703D01*
G01X1273751Y102679D02*
X1273757Y102691D01*
G01X1273741Y102671D02*
X1273751Y102679D01*
G01X1273757Y96391D02*
X1273760Y96404D01*
G01X1273751Y96380D02*
X1273757Y96391D01*
G01X1273741Y96372D02*
X1273751Y96380D01*
G01X1272814Y103863D02*
Y103869D01*
G01Y103859D02*
Y103863D01*
G01X1272813Y103858D02*
X1272814Y103859D01*
G01Y100713D02*
Y100720D01*
G01Y100710D02*
Y100713D01*
G01X1272813Y100709D02*
X1272814Y100710D01*
G01Y97564D02*
Y97570D01*
G01Y97560D02*
Y97564D01*
G01X1272813Y97559D02*
X1272814Y97560D01*
G01Y94414D02*
Y94420D01*
G01Y94411D02*
Y94414D01*
G01X1272813Y94409D02*
X1272814Y94411D01*
G01X1272776Y103839D02*
Y103832D01*
G01X1272778Y103845D02*
X1272776Y103839D01*
G01X1272781Y103851D02*
X1272778Y103845D01*
G01X1272785Y103856D02*
X1272781Y103851D01*
G01X1272789Y103861D02*
X1272785Y103856D01*
G01X1272795Y103864D02*
X1272789Y103861D01*
G01X1272776Y100689D02*
Y100683D01*
G01X1272778Y100695D02*
X1272776Y100689D01*
G01X1272781Y100701D02*
X1272778Y100695D01*
G01X1272785Y100706D02*
X1272781Y100701D01*
G01X1272789Y100711D02*
X1272785Y100706D01*
G01X1272795Y100715D02*
X1272789Y100711D01*
G01X1272776Y97539D02*
Y97533D01*
G01X1272778Y97546D02*
X1272776Y97539D01*
G01X1272781Y97552D02*
X1272778Y97546D01*
G01X1272785Y97557D02*
X1272781Y97552D01*
G01X1272789Y97561D02*
X1272785Y97557D01*
G01X1272795Y97565D02*
X1272789Y97561D01*
G01X1272776Y94390D02*
Y94383D01*
G01X1272778Y94396D02*
X1272776Y94390D01*
G01X1272781Y94402D02*
X1272778Y94396D01*
G01X1272785Y94407D02*
X1272781Y94402D01*
G01X1272789Y94412D02*
X1272785Y94407D01*
G01X1272795Y94415D02*
X1272789Y94412D01*
G01X1273731Y102679D02*
X1273719Y102677D01*
G01X1273741Y102684D02*
X1273731Y102679D01*
G01Y99530D02*
X1273719Y99528D01*
G01X1273741Y99534D02*
X1273731Y99530D01*
G01Y96380D02*
X1273719Y96378D01*
G01X1273741Y96385D02*
X1273731Y96380D01*
G01X1338189Y122047D02*
G03X1349213I5512J0D01*
G01D02*
G03X1338189I-5512J0D01*
G01X1283583Y188130D02*
G03I-1890J0D01*
G01X1284055D02*
G03I-2362J0D01*
G01X1349213Y122047D02*
G03I-5512J0D01*
G01X1286614Y103681D02*
X1287795Y104862D01*
G01X1282677Y103681D02*
X1283858Y104862D01*
G01X1292520Y186161D02*
X1289173Y182815D01*
G01X1282677Y180138D02*
X1283858Y181319D01*
G01X1279208Y185059D02*
X1280512Y187028D01*
G01X1285184Y192950D02*
X1282874Y188720D01*
G01X1273759Y94372D02*
X1273760Y94383D01*
G01X1273759Y97522D02*
X1273760Y97533D01*
G01X1273759Y100671D02*
X1273760Y100683D01*
G01X1273759Y103821D02*
X1273760Y103832D01*
G01X1287185Y106982D02*
Y106991D01*
G01Y111982D02*
Y111991D01*
G01Y116982D02*
Y116991D01*
G01Y121982D02*
Y121991D01*
G01Y126982D02*
Y126991D01*
G01Y131982D02*
Y131991D01*
G01Y136982D02*
Y136991D01*
G01Y141982D02*
Y141991D01*
G01Y146982D02*
Y146991D01*
G01Y151982D02*
Y151991D01*
G01Y156982D02*
Y156991D01*
G01Y161982D02*
Y161991D01*
G01Y166982D02*
Y166991D01*
G01Y171982D02*
Y171991D01*
G01Y176982D02*
Y176991D01*
G01X1292520Y186161D02*
Y201909D01*
G01X1291535Y175630D02*
Y177008D01*
G01Y170630D02*
Y172008D01*
G01Y165630D02*
Y167008D01*
G01Y160630D02*
Y162008D01*
G01Y155630D02*
Y157008D01*
G01Y150630D02*
Y152008D01*
G01Y145630D02*
Y147008D01*
G01Y140630D02*
Y142008D01*
G01Y135630D02*
Y137008D01*
G01Y130630D02*
Y132008D01*
G01Y125630D02*
Y127008D01*
G01Y120630D02*
Y122008D01*
G01Y115630D02*
Y117008D01*
G01Y110630D02*
Y112008D01*
G01Y105630D02*
Y107008D01*
G01X1288366D02*
Y105630D01*
G01Y112008D02*
Y110630D01*
G01Y117008D02*
Y115630D01*
G01Y122008D02*
Y120630D01*
G01Y127008D02*
Y125630D01*
G01Y132008D02*
Y130630D01*
G01Y137008D02*
Y135630D01*
G01Y142008D02*
Y140630D01*
G01Y147008D02*
Y145630D01*
G01Y152008D02*
Y150630D01*
G01Y157008D02*
Y155630D01*
G01Y162008D02*
Y160630D01*
G01Y167008D02*
Y165630D01*
G01Y172008D02*
Y170630D01*
G01Y177008D02*
Y175630D01*
G01X1287185Y106982D02*
Y107125D01*
G01Y111982D02*
Y112125D01*
G01Y116982D02*
Y117125D01*
G01Y121982D02*
Y122125D01*
G01Y126982D02*
Y127125D01*
G01Y131982D02*
Y132125D01*
G01Y136982D02*
Y137125D01*
G01Y141982D02*
Y142125D01*
G01Y146982D02*
Y147125D01*
G01Y151982D02*
Y152125D01*
G01Y156982D02*
Y157125D01*
G01Y161982D02*
Y162125D01*
G01Y166982D02*
Y167125D01*
G01Y171982D02*
Y172125D01*
G01Y176982D02*
Y177125D01*
G01Y175138D02*
Y177500D01*
G01Y170138D02*
Y172500D01*
G01Y165138D02*
Y167500D01*
G01Y160138D02*
Y162500D01*
G01Y155138D02*
Y157500D01*
G01Y150138D02*
Y152500D01*
G01Y145138D02*
Y147500D01*
G01Y140138D02*
Y142500D01*
G01Y135138D02*
Y137500D01*
G01Y130138D02*
Y132500D01*
G01Y125138D02*
Y127500D01*
G01Y120138D02*
Y122500D01*
G01Y115138D02*
Y117500D01*
G01Y110138D02*
Y112500D01*
G01Y105138D02*
Y107500D01*
G01X1286201D02*
Y105138D01*
G01Y112500D02*
Y110138D01*
G01Y117500D02*
Y115138D01*
G01Y122500D02*
Y120138D01*
G01Y127500D02*
Y125138D01*
G01Y132500D02*
Y130138D01*
G01Y137500D02*
Y135138D01*
G01Y142500D02*
Y140138D01*
G01Y147500D02*
Y145138D01*
G01Y152500D02*
Y150138D01*
G01Y157500D02*
Y155138D01*
G01Y162500D02*
Y160138D01*
G01Y167500D02*
Y165138D01*
G01Y172500D02*
Y170138D01*
G01Y177500D02*
Y175138D01*
G01X1285433Y192224D02*
Y183681D01*
G01X1283858Y181319D02*
Y104862D01*
G01X1282874Y188720D02*
Y187028D01*
G01X1282677Y180138D02*
Y103681D01*
G01X1280512Y187028D02*
Y188720D01*
G01X1277953Y183681D02*
Y192224D01*
G01X1274213Y185059D02*
Y106024D01*
G01X1273760Y102519D02*
Y104016D01*
G01Y99370D02*
Y100866D01*
G01Y96220D02*
Y97717D01*
G01X1273720Y96367D02*
Y96220D01*
G01Y94567D02*
Y94420D01*
G01Y99516D02*
Y99369D01*
G01Y100867D02*
Y100720D01*
G01Y97717D02*
Y97570D01*
G01Y102666D02*
Y102519D01*
G01Y104016D02*
Y103869D01*
G01X1272815Y102519D02*
Y102666D01*
G01Y103869D02*
Y104016D01*
G01Y99369D02*
Y99516D01*
G01Y100720D02*
Y100867D01*
G01Y97570D02*
Y97717D01*
G01Y96220D02*
Y96367D01*
G01Y94420D02*
Y94567D01*
G01X1272776Y100866D02*
Y99370D01*
G01Y97717D02*
Y96220D01*
G01Y104016D02*
Y102520D01*
G01X1271594Y97559D02*
Y96378D01*
G01Y100709D02*
Y99528D01*
G01Y103858D02*
Y102677D01*
G01X1270866Y201909D02*
Y186161D01*
G01X1267835Y102677D02*
Y103858D01*
G01Y99528D02*
Y100709D01*
G01Y96378D02*
Y97559D01*
G01X1273760Y102703D02*
X1273759Y102714D01*
G01X1273760Y99554D02*
X1273759Y99564D01*
G01X1273760Y96404D02*
X1273759Y96415D01*
G01X1273719Y99528D02*
X1273722Y99516D01*
G01X1280512Y188720D02*
X1278202Y192950D01*
G01X1282874Y187028D02*
X1284178Y185059D01*
G01X1275984Y181319D02*
X1277165Y180138D01*
G01X1270866Y186161D02*
X1274213Y182815D01*
G01X1272662Y102717D02*
X1272774Y102708D01*
G01X1280512Y187028D02*
X1282874D01*
G01X1274213Y185059D02*
X1288583D01*
G01X1274213Y183681D02*
X1277953D01*
G01X1288583D02*
X1285433D01*
G01X1274213Y182815D02*
X1289173D01*
G01X1275984Y181319D02*
X1283858D01*
G01X1277165Y180138D02*
X1282677D01*
G01X1287185Y177500D02*
X1286201D01*
G01X1286202Y177008D02*
X1291535D01*
G01Y176969D02*
X1287187D01*
G01X1291535Y175630D02*
X1286202D01*
G01X1286201Y175138D02*
X1287185D01*
G01Y172500D02*
X1286201D01*
G01X1286202Y172008D02*
X1291535D01*
G01Y171969D02*
X1287187D01*
G01X1291535Y170630D02*
X1286202D01*
G01X1286201Y170138D02*
X1287185D01*
G01Y167500D02*
X1286201D01*
G01X1286202Y167008D02*
X1291535D01*
G01Y166969D02*
X1287187D01*
G01X1291535Y165630D02*
X1286202D01*
G01X1286201Y165138D02*
X1287185D01*
G01Y162500D02*
X1286201D01*
G01X1286202Y162008D02*
X1291535D01*
G01Y161969D02*
X1287187D01*
G01X1291535Y160630D02*
X1286202D01*
G01X1286201Y160138D02*
X1287185D01*
G01Y157500D02*
X1286201D01*
G01X1286202Y157008D02*
X1291535D01*
G01Y156969D02*
X1287187D01*
G01X1291535Y155630D02*
X1286202D01*
G01X1286201Y155138D02*
X1287185D01*
G01Y152500D02*
X1286201D01*
G01X1286202Y152008D02*
X1291535D01*
G01Y151969D02*
X1287187D01*
G01X1291535Y150630D02*
X1286202D01*
G01X1286201Y150138D02*
X1287185D01*
G01Y147500D02*
X1286201D01*
G01X1286202Y147008D02*
X1291535D01*
G01Y146969D02*
X1287187D01*
G01X1291535Y145630D02*
X1286202D01*
G01X1286201Y145138D02*
X1287185D01*
G01Y142500D02*
X1286201D01*
G01X1286202Y142008D02*
X1291535D01*
G01Y141969D02*
X1287187D01*
G01X1291535Y140630D02*
X1286202D01*
G01X1286201Y140138D02*
X1287185D01*
G01Y137500D02*
X1286201D01*
G01X1286202Y137008D02*
X1291535D01*
G01Y136969D02*
X1287187D01*
G01X1291535Y135630D02*
X1286202D01*
G01X1286201Y135138D02*
X1287185D01*
G01Y132500D02*
X1286201D01*
G01X1286202Y132008D02*
X1291535D01*
G01Y131969D02*
X1287187D01*
G01X1291535Y130630D02*
X1286202D01*
G01X1286201Y130138D02*
X1287185D01*
G01Y127500D02*
X1286201D01*
G01X1286202Y127008D02*
X1291535D01*
G01Y126969D02*
X1287187D01*
G01X1291535Y125630D02*
X1286202D01*
G01X1286201Y125138D02*
X1287185D01*
G01Y122500D02*
X1286201D01*
G01X1286202Y122008D02*
X1291535D01*
G01Y121969D02*
X1287187D01*
G01X1291535Y120630D02*
X1286202D01*
G01X1286201Y120138D02*
X1287185D01*
G01Y117500D02*
X1286201D01*
G01Y177204D02*
X1287156Y177205D01*
G01X1287185Y175434D02*
X1286201Y175433D01*
G01Y172204D02*
X1287156Y172205D01*
G01X1287185Y170434D02*
X1286201Y170433D01*
G01Y167204D02*
X1287156Y167205D01*
G01X1287185Y165434D02*
X1286201Y165433D01*
G01Y162204D02*
X1287156Y162205D01*
G01X1287185Y160434D02*
X1286201Y160433D01*
G01Y157204D02*
X1287156Y157205D01*
G01X1287185Y155434D02*
X1286201Y155433D01*
G01Y152204D02*
X1287156Y152205D01*
G01X1287185Y150434D02*
X1286201Y150433D01*
G01Y147204D02*
X1287156Y147205D01*
G01X1287185Y145434D02*
X1286201Y145433D01*
G01Y142204D02*
X1287156Y142205D01*
G01X1287185Y140434D02*
X1286201Y140433D01*
G01Y137204D02*
X1287156Y137205D01*
G01X1287185Y135434D02*
X1286201Y135433D01*
G01Y132204D02*
X1287156Y132205D01*
G01X1287185Y130434D02*
X1286201Y130433D01*
G01Y127204D02*
X1287156Y127205D01*
G01X1287185Y125434D02*
X1286201Y125433D01*
G01Y122204D02*
X1287156Y122205D01*
G01X1287185Y120434D02*
X1286201Y120433D01*
G01X1272773Y96414D02*
X1272662Y96417D01*
G01X1286202Y117008D02*
X1291535D01*
G01Y116969D02*
X1287187D01*
G01X1291535Y115630D02*
X1286202D01*
G01X1286201Y115138D02*
X1287185D01*
G01Y112500D02*
X1286201D01*
G01X1286202Y112008D02*
X1291535D01*
G01Y111969D02*
X1287187D01*
G01X1291535Y110630D02*
X1286202D01*
G01X1286201Y110138D02*
X1287185D01*
G01Y107500D02*
X1286201D01*
G01X1286202Y107008D02*
X1291535D01*
G01Y106969D02*
X1287187D01*
G01X1274213Y106024D02*
X1270866D01*
G01X1291535Y105630D02*
X1286202D01*
G01X1286201Y105138D02*
X1287185D01*
G01X1283858Y104862D02*
X1287795D01*
G01X1273720Y104055D02*
X1272815D01*
G01X1273760Y104016D02*
X1272776D01*
G01X1273719Y103858D02*
X1267835D01*
G01Y103819D02*
X1273759D01*
G01X1282677Y103681D02*
X1286614D01*
G01X1273758Y102717D02*
X1267835D01*
G01X1273719Y102677D02*
X1267835D01*
G01X1272776Y102520D02*
X1273760D01*
G01X1272815Y102480D02*
X1273720D01*
G01Y100906D02*
X1272815D01*
G01X1273760Y100866D02*
X1272776D01*
G01X1273719Y100709D02*
X1267835D01*
G01Y100669D02*
X1273759D01*
G01X1273758Y99567D02*
X1267835D01*
G01X1273719Y99528D02*
X1267835D01*
G01X1272776Y99370D02*
X1273760D01*
G01X1272815Y99331D02*
X1273720D01*
G01Y97756D02*
X1272815D01*
G01X1273760Y97717D02*
X1272776D01*
G01X1273719Y97559D02*
X1267835D01*
G01Y97520D02*
X1273759D01*
G01X1272028Y96417D02*
X1271594D01*
G01X1273758D02*
X1267835D01*
G01X1273719Y96378D02*
X1267835D01*
G01X1272776Y96220D02*
X1273760D01*
G01X1272815Y96181D02*
X1273720D01*
G01Y94606D02*
X1272815D01*
G01X1273760Y94567D02*
X1272776D01*
G01X1273719Y94409D02*
X1267835D01*
G01Y94370D02*
X1273759D01*
G01X1286201Y117204D02*
X1287156Y117205D01*
G01X1287185Y115434D02*
X1286201Y115433D01*
G01Y112204D02*
X1287156Y112205D01*
G01X1287185Y110434D02*
X1286201Y110433D01*
G01Y107204D02*
X1287156Y107205D01*
G01X1287185Y105434D02*
X1286201Y105433D01*
G01X1284965Y264712D02*
G03X1318775I16905J-13531D01*
G01X1311851Y277843D02*
G03X1318775Y264712I37663J11469D01*
G01X1311851Y277843D02*
G03X1291890I-9980J-3040D01*
G01X1284965Y264712D02*
G03X1291890Y277843I-30737J24602D01*
G01X1311850D02*
G03X1318776Y264712I37661J11473D01*
G01X1311850Y277843D02*
G03X1291890I-9980J-3040D01*
G01X1284965Y264712D02*
G03X1318776I16906J-13531D01*
G01X1284965D02*
G03X1291890Y277843I-30737J24602D01*
G01X1285630Y202500D02*
G03X1285039Y203091I-591J0D01*
G01X1278346D02*
G03X1277756Y202500I1J-591D01*
G01X1280512Y201319D02*
G03Y199350I0J-985D01*
G01X1282874D02*
G03Y201319I0J984D01*
G01X1279134Y193406D02*
G03X1277953Y192224I0J-1181D01*
G01X1285433D02*
G03X1284252Y193406I-1181J1D01*
G01X1292520Y201909D02*
G03X1290551Y203878I-1969J0D01*
G01X1272835D02*
G03X1270866Y201909I0J-1969D01*
G01X1285630Y196398D02*
Y202500D01*
G01X1277756Y196398D02*
Y202500D01*
G01X1290551Y203878D02*
X1272835D01*
G01X1285039Y203091D02*
X1278346D01*
G01X1282874Y201319D02*
X1280512D01*
G01Y199350D02*
X1282874D01*
G01X1285630Y197972D02*
X1277756D01*
G01Y196398D02*
X1285630D01*
G01X1292520Y193445D02*
X1270866D01*
G01X1279134Y193406D02*
X1284252D01*
G01X1280512Y188720D02*
X1282874D01*
G01X1272778Y537697D02*
X1272773Y537677D01*
G01X1272793Y537711D02*
X1272778Y537697D01*
G01X1272813Y537717D02*
X1272793Y537711D01*
G01X1272778Y540846D02*
X1272773Y540827D01*
G01X1272793Y540861D02*
X1272778Y540846D01*
G01X1272813Y540866D02*
X1272793Y540861D01*
G01X1272778Y543996D02*
X1272773Y543976D01*
G01X1272793Y544010D02*
X1272778Y543996D01*
G01X1272813Y544016D02*
X1272793Y544010D01*
G01X1272778Y547146D02*
X1272773Y547126D01*
G01X1272793Y547160D02*
X1272778Y547146D01*
G01X1272813Y547165D02*
X1272793Y547160D01*
G01X1272778Y550295D02*
X1272773Y550276D01*
G01X1272793Y550309D02*
X1272778Y550295D01*
G01X1272813Y550315D02*
X1272793Y550309D01*
G01X1272778Y553445D02*
X1272773Y553425D01*
G01X1272793Y553459D02*
X1272778Y553445D01*
G01X1272813Y553465D02*
X1272793Y553459D01*
G01X1272778Y556594D02*
X1272773Y556575D01*
G01X1272793Y556609D02*
X1272778Y556594D01*
G01X1272813Y556614D02*
X1272793Y556609D01*
G01X1273753Y536555D02*
X1273758Y536575D01*
G01X1273739Y536541D02*
X1273753Y536555D01*
G01X1273719Y536535D02*
X1273739Y536541D01*
G01X1273753Y539705D02*
X1273758Y539724D01*
G01X1273739Y539690D02*
X1273753Y539705D01*
G01X1273719Y539685D02*
X1273739Y539690D01*
G01X1273753Y542854D02*
X1273758Y542874D01*
G01X1273739Y542840D02*
X1273753Y542854D01*
G01X1273719Y542835D02*
X1273739Y542840D01*
G01X1273753Y546004D02*
X1273758Y546024D01*
G01X1273739Y545989D02*
X1273753Y546004D01*
G01X1273719Y545984D02*
X1273739Y545989D01*
G01X1273753Y549154D02*
X1273758Y549173D01*
G01X1273739Y549139D02*
X1273753Y549154D01*
G01X1273719Y549134D02*
X1273739Y549139D01*
G01X1273753Y552303D02*
X1273758Y552323D01*
G01X1273739Y552289D02*
X1273753Y552303D01*
G01X1273719Y552283D02*
X1273739Y552289D01*
G01X1273753Y555453D02*
X1273758Y555472D01*
G01X1273739Y555438D02*
X1273753Y555453D01*
G01X1273719Y555433D02*
X1273739Y555438D01*
G01X1273759Y552302D02*
X1273760Y552309D01*
G01X1273757Y552295D02*
X1273759Y552302D01*
G01X1273753Y552289D02*
X1273757Y552295D01*
G01X1273748Y552283D02*
X1273753Y552289D01*
G01X1273742Y552278D02*
X1273748Y552283D01*
G01X1273735Y552275D02*
X1273742Y552278D01*
G01X1273728Y552273D02*
X1273735Y552275D01*
G01X1273720Y552272D02*
X1273728Y552273D01*
G01X1273737Y536528D02*
X1273741Y536530D01*
G01X1273734Y536526D02*
X1273737Y536528D01*
G01X1273731Y536526D02*
X1273734D01*
G01X1273728Y536525D02*
X1273731Y536526D01*
G01X1273724Y536524D02*
X1273728Y536525D01*
G01X1273720Y536524D02*
X1273724D01*
G01X1272798Y537724D02*
X1272795Y537722D01*
G01X1272801Y537725D02*
X1272798Y537724D01*
G01X1272805Y537726D02*
X1272801Y537725D01*
G01X1272808Y537727D02*
X1272805Y537726D01*
G01X1272811Y537728D02*
X1272808Y537727D01*
G01X1272815Y537728D02*
X1272811D01*
G01X1273737Y539677D02*
X1273741Y539679D01*
G01X1273734Y539676D02*
X1273737Y539677D01*
G01X1273731Y539675D02*
X1273734Y539676D01*
G01X1273728Y539674D02*
X1273731Y539675D01*
G01X1273724Y539674D02*
X1273728D01*
G01X1273720D02*
X1273724D01*
G01X1272798Y540874D02*
X1272795Y540872D01*
G01X1272801Y540875D02*
X1272798Y540874D01*
G01X1272805Y540876D02*
X1272801Y540875D01*
G01X1272808Y540877D02*
X1272805Y540876D01*
G01X1272811Y540877D02*
X1272808D01*
G01X1272815D02*
X1272811D01*
G01X1273737Y542827D02*
X1273741Y542829D01*
G01X1273734Y542826D02*
X1273737Y542827D01*
G01X1273731Y542825D02*
X1273734Y542826D01*
G01X1273728Y542824D02*
X1273731Y542825D01*
G01X1273724Y542824D02*
X1273728D01*
G01X1273720Y542823D02*
X1273724Y542824D01*
G01X1272798Y544023D02*
X1272795Y544022D01*
G01X1272801Y544024D02*
X1272798Y544023D01*
G01X1272805Y544026D02*
X1272801Y544024D01*
G01X1272808Y544026D02*
X1272805D01*
G01X1272811Y544027D02*
X1272808Y544026D01*
G01X1272815Y544027D02*
X1272811D01*
G01X1273737Y545976D02*
X1273741Y545978D01*
G01X1273734Y545975D02*
X1273737Y545976D01*
G01X1273731Y545974D02*
X1273734Y545975D01*
G01X1273728Y545974D02*
X1273731D01*
G01X1273724Y545973D02*
X1273728Y545974D01*
G01X1273720Y545973D02*
X1273724D01*
G01X1272798Y547173D02*
X1272795Y547171D01*
G01X1272801Y547174D02*
X1272798Y547173D01*
G01X1272805Y547175D02*
X1272801Y547174D01*
G01X1272808Y547176D02*
X1272805Y547175D01*
G01X1272811Y547176D02*
X1272808D01*
G01X1272815D02*
X1272811D01*
G01X1273737Y549126D02*
X1273741Y549128D01*
G01X1273734Y549125D02*
X1273737Y549126D01*
G01X1273731Y549124D02*
X1273734Y549125D01*
G01X1273728Y549123D02*
X1273731Y549124D01*
G01X1273724Y549123D02*
X1273728D01*
G01X1273720Y549122D02*
X1273724Y549123D01*
G01X1272798Y550322D02*
X1272795Y550321D01*
G01X1272801Y550324D02*
X1272798Y550322D01*
G01X1272805Y550325D02*
X1272801Y550324D01*
G01X1272808Y550326D02*
X1272805Y550325D01*
G01X1272811Y550326D02*
X1272808D01*
G01X1272815D02*
X1272811D01*
G01X1272798Y553472D02*
X1272795Y553470D01*
G01X1272801Y553473D02*
X1272798Y553472D01*
G01X1272805Y553474D02*
X1272801Y553473D01*
G01X1272808Y553475D02*
X1272805Y553474D01*
G01X1272811Y553476D02*
X1272808Y553475D01*
G01X1272815Y553476D02*
X1272811D01*
G01X1273737Y555425D02*
X1273741Y555427D01*
G01X1273734Y555424D02*
X1273737Y555425D01*
G01X1273731Y555423D02*
X1273734Y555424D01*
G01X1273728Y555422D02*
X1273731Y555423D01*
G01X1273724Y555422D02*
X1273728D01*
G01X1273720D02*
X1273724D01*
G01X1272798Y556622D02*
X1272795Y556620D01*
G01X1272801Y556623D02*
X1272798Y556622D01*
G01X1272805Y556624D02*
X1272801Y556623D01*
G01X1272808Y556625D02*
X1272805Y556624D01*
G01X1272811Y556625D02*
X1272808D01*
G01X1272815D02*
X1272811D01*
G01X1273750Y537715D02*
X1273754Y537709D01*
G01X1273746Y537719D02*
X1273750Y537715D01*
G01X1273740Y537723D02*
X1273746Y537719D01*
G01X1273734Y537726D02*
X1273740Y537723D01*
G01X1273727Y537727D02*
X1273734Y537726D01*
G01X1273720Y537728D02*
X1273727Y537727D01*
G01X1273750Y540865D02*
X1273754Y540859D01*
G01X1273746Y540869D02*
X1273750Y540865D01*
G01X1273740Y540872D02*
X1273746Y540869D01*
G01X1273734Y540875D02*
X1273740Y540872D01*
G01X1273727Y540877D02*
X1273734Y540875D01*
G01X1273720Y540877D02*
X1273727D01*
G01X1273750Y544014D02*
X1273754Y544009D01*
G01X1273746Y544019D02*
X1273750Y544014D01*
G01X1273740Y544022D02*
X1273746Y544019D01*
G01X1273734Y544025D02*
X1273740Y544022D01*
G01X1273727Y544026D02*
X1273734Y544025D01*
G01X1273720Y544027D02*
X1273727Y544026D01*
G01X1273750Y547164D02*
X1273754Y547158D01*
G01X1273746Y547168D02*
X1273750Y547164D01*
G01X1273740Y547172D02*
X1273746Y547168D01*
G01X1273734Y547174D02*
X1273740Y547172D01*
G01X1273727Y547176D02*
X1273734Y547174D01*
G01X1273720Y547176D02*
X1273727D01*
G01X1273750Y550313D02*
X1273754Y550308D01*
G01X1273746Y550318D02*
X1273750Y550313D01*
G01X1273740Y550321D02*
X1273746Y550318D01*
G01X1273734Y550324D02*
X1273740Y550321D01*
G01X1273727Y550326D02*
X1273734Y550324D01*
G01X1273720Y550326D02*
X1273727D01*
G01X1273750Y553463D02*
X1273754Y553457D01*
G01X1273746Y553467D02*
X1273750Y553463D01*
G01X1273740Y553471D02*
X1273746Y553467D01*
G01X1273734Y553474D02*
X1273740Y553471D01*
G01X1273727Y553475D02*
X1273734Y553474D01*
G01X1273720Y553476D02*
X1273727Y553475D01*
G01X1273750Y556613D02*
X1273754Y556607D01*
G01X1273746Y556617D02*
X1273750Y556613D01*
G01X1273740Y556620D02*
X1273746Y556617D01*
G01X1273734Y556623D02*
X1273740Y556620D01*
G01X1273727Y556625D02*
X1273734Y556623D01*
G01X1273720Y556625D02*
X1273727D01*
G01X1272776Y536554D02*
Y536561D01*
G01X1272779Y536547D02*
X1272776Y536554D01*
G01X1272782Y536541D02*
X1272779Y536547D01*
G01X1272787Y536535D02*
X1272782Y536541D01*
G01X1272793Y536530D02*
X1272787Y536535D01*
G01X1272800Y536527D02*
X1272793Y536530D01*
G01X1272807Y536525D02*
X1272800Y536527D01*
G01X1272815Y536524D02*
X1272807Y536525D01*
G01X1272776Y539704D02*
Y539711D01*
G01X1272779Y539696D02*
X1272776Y539704D01*
G01X1272782Y539690D02*
X1272779Y539696D01*
G01X1272787Y539685D02*
X1272782Y539690D01*
G01X1272793Y539680D02*
X1272787Y539685D01*
G01X1272800Y539676D02*
X1272793Y539680D01*
G01X1272807Y539674D02*
X1272800Y539676D01*
G01X1272815Y539674D02*
X1272807D01*
G01X1272776Y542853D02*
Y542860D01*
G01X1272779Y542846D02*
X1272776Y542853D01*
G01X1272782Y542840D02*
X1272779Y542846D01*
G01X1272787Y542834D02*
X1272782Y542840D01*
G01X1272793Y542830D02*
X1272787Y542834D01*
G01X1272800Y542826D02*
X1272793Y542830D01*
G01X1272807Y542824D02*
X1272800Y542826D01*
G01X1272815Y542823D02*
X1272807Y542824D01*
G01X1272776Y546003D02*
Y546010D01*
G01X1272779Y545996D02*
X1272776Y546003D01*
G01X1272782Y545989D02*
X1272779Y545996D01*
G01X1272787Y545984D02*
X1272782Y545989D01*
G01X1272793Y545979D02*
X1272787Y545984D01*
G01X1272800Y545976D02*
X1272793Y545979D01*
G01X1272807Y545974D02*
X1272800Y545976D01*
G01X1272815Y545973D02*
X1272807Y545974D01*
G01X1272776Y549152D02*
Y549159D01*
G01X1272779Y549145D02*
X1272776Y549152D01*
G01X1272782Y549139D02*
X1272779Y549145D01*
G01X1272787Y549133D02*
X1272782Y549139D01*
G01X1272793Y549129D02*
X1272787Y549133D01*
G01X1272800Y549125D02*
X1272793Y549129D01*
G01X1272807Y549123D02*
X1272800Y549125D01*
G01X1272815Y549122D02*
X1272807Y549123D01*
G01X1272776Y552302D02*
Y552309D01*
G01X1272779Y552295D02*
X1272776Y552302D01*
G01X1272782Y552289D02*
X1272779Y552295D01*
G01X1272787Y552283D02*
X1272782Y552289D01*
G01X1272793Y552278D02*
X1272787Y552283D01*
G01X1272800Y552275D02*
X1272793Y552278D01*
G01X1272807Y552273D02*
X1272800Y552275D01*
G01X1272815Y552272D02*
X1272807Y552273D01*
G01X1272776Y555452D02*
Y555459D01*
G01X1272779Y555444D02*
X1272776Y555452D01*
G01X1272782Y555438D02*
X1272779Y555444D01*
G01X1272787Y555433D02*
X1272782Y555438D01*
G01X1272793Y555428D02*
X1272787Y555433D01*
G01X1272800Y555424D02*
X1272793Y555428D01*
G01X1272807Y555422D02*
X1272800Y555424D01*
G01X1272815Y555422D02*
X1272807D01*
G01X1273730Y537715D02*
X1273739Y537711D01*
G01X1273719Y537717D02*
X1273730Y537715D01*
G01Y540865D02*
X1273739Y540861D01*
G01X1273719Y540866D02*
X1273730Y540865D01*
G01Y544014D02*
X1273739Y544010D01*
G01X1273719Y544016D02*
X1273730Y544014D01*
G01Y547164D02*
X1273739Y547160D01*
G01X1273719Y547165D02*
X1273730Y547164D01*
G01Y550313D02*
X1273739Y550309D01*
G01X1273719Y550315D02*
X1273730Y550313D01*
G01Y553463D02*
X1273739Y553459D01*
G01X1273719Y553465D02*
X1273730Y553463D01*
G01Y556613D02*
X1273739Y556609D01*
G01X1273719Y556614D02*
X1273730Y556613D01*
G01X1272776Y539715D02*
Y539711D01*
G01X1272777Y539708D02*
X1272776Y539715D01*
G01X1272789Y539693D02*
X1272777Y539708D01*
G01X1272814Y539685D02*
X1272789Y539693D01*
G01X1272776Y542864D02*
Y542860D01*
G01X1272777Y542858D02*
X1272776Y542864D01*
G01X1272789Y542843D02*
X1272777Y542858D01*
G01X1272813Y542835D02*
X1272789Y542843D01*
G01X1272776Y549163D02*
Y549159D01*
G01X1272777Y549157D02*
X1272776Y549163D01*
G01X1272789Y549142D02*
X1272777Y549157D01*
G01X1272813Y549134D02*
X1272789Y549142D01*
G01X1272776Y552313D02*
Y552309D01*
G01X1272777Y552307D02*
X1272776Y552313D01*
G01X1272789Y552292D02*
X1272777Y552307D01*
G01X1272813Y552283D02*
X1272789Y552292D01*
G01X1272776Y536565D02*
Y536561D01*
G01X1272777Y536559D02*
X1272776Y536565D01*
G01X1272789Y536544D02*
X1272777Y536559D01*
G01X1272813Y536535D02*
X1272789Y536544D01*
G01X1272776Y555463D02*
Y555459D01*
G01X1272777Y555457D02*
X1272776Y555463D01*
G01X1272789Y555441D02*
X1272777Y555457D01*
G01X1272813Y555433D02*
X1272789Y555441D01*
G01X1287172Y504755D02*
X1287183Y504740D01*
G01X1287148Y504764D02*
X1287172Y504755D01*
G01Y509755D02*
X1287183Y509740D01*
G01X1287148Y509764D02*
X1287172Y509755D01*
G01Y514755D02*
X1287183Y514740D01*
G01X1287148Y514764D02*
X1287172Y514755D01*
G01Y519755D02*
X1287183Y519740D01*
G01X1287148Y519764D02*
X1287172Y519755D01*
G01Y524755D02*
X1287183Y524740D01*
G01X1287148Y524764D02*
X1287172Y524755D01*
G01Y529755D02*
X1287183Y529740D01*
G01X1287148Y529764D02*
X1287172Y529755D01*
G01Y534755D02*
X1287183Y534740D01*
G01X1287148Y534764D02*
X1287172Y534755D01*
G01Y559755D02*
X1287183Y559740D01*
G01X1287148Y559764D02*
X1287172Y559755D01*
G01X1287183Y564740D02*
X1287185Y564734D01*
G01X1287172Y564755D02*
X1287183Y564740D01*
G01X1287148Y564764D02*
X1287172Y564755D01*
G01Y569755D02*
X1287183Y569740D01*
G01X1287148Y569764D02*
X1287172Y569755D01*
G01X1272776Y546014D02*
Y546010D01*
G01X1272777Y546008D02*
X1272776Y546014D01*
G01X1272787Y545994D02*
X1272777Y546008D01*
G01X1272810Y545984D02*
X1272787Y545994D01*
G01X1273728Y544015D02*
X1273719Y544016D01*
G01X1273737Y544011D02*
X1273728Y544015D01*
G01X1273745Y544006D02*
X1273737Y544011D01*
G01X1273728Y537715D02*
X1273719Y537717D01*
G01X1273737Y537712D02*
X1273728Y537715D01*
G01X1273745Y537707D02*
X1273737Y537712D01*
G01X1273728Y540865D02*
X1273719Y540866D01*
G01X1273737Y540862D02*
X1273728Y540865D01*
G01X1273745Y540856D02*
X1273737Y540862D01*
G01X1273728Y547164D02*
X1273719Y547165D01*
G01X1273737Y547161D02*
X1273728Y547164D01*
G01X1273745Y547156D02*
X1273737Y547161D01*
G01X1273728Y550314D02*
X1273719Y550315D01*
G01X1273737Y550311D02*
X1273728Y550314D01*
G01X1273745Y550305D02*
X1273737Y550311D01*
G01X1273728Y553463D02*
X1273719Y553465D01*
G01X1273737Y553460D02*
X1273728Y553463D01*
G01X1273745Y553455D02*
X1273737Y553460D01*
G01X1273728Y556613D02*
X1273719Y556614D01*
G01X1273737Y556610D02*
X1273728Y556613D01*
G01X1273745Y556604D02*
X1273737Y556610D01*
G01X1272815Y536530D02*
Y536524D01*
G01X1272814Y536534D02*
X1272815Y536530D01*
G01X1272813Y536535D02*
X1272814Y536534D01*
G01X1272815Y539680D02*
Y539674D01*
G01X1272814Y539684D02*
X1272815Y539680D01*
G01X1272813Y539685D02*
X1272814Y539684D01*
G01X1272815Y542830D02*
Y542823D01*
G01X1272814Y542833D02*
X1272815Y542830D01*
G01X1272813Y542835D02*
X1272814Y542833D01*
G01X1272815Y545979D02*
Y545973D01*
G01X1272814Y545983D02*
X1272815Y545979D01*
G01X1272813Y545984D02*
X1272814Y545983D01*
G01X1272815Y549129D02*
Y549122D01*
G01X1272814Y549133D02*
X1272815Y549129D01*
G01X1272813Y549134D02*
X1272814Y549133D01*
G01X1272815Y552278D02*
Y552272D01*
G01X1272814Y552282D02*
X1272815Y552278D01*
G01X1272813Y552283D02*
X1272814Y552282D01*
G01X1272815Y555428D02*
Y555422D01*
G01X1272814Y555432D02*
X1272815Y555428D01*
G01X1272813Y555433D02*
X1272814Y555432D01*
G01X1287185Y504731D02*
Y504738D01*
G01X1287186Y504726D02*
X1287185Y504731D01*
G01X1287187Y504724D02*
X1287186Y504726D01*
G01X1287185Y509731D02*
Y509738D01*
G01X1287186Y509726D02*
X1287185Y509731D01*
G01X1287187Y509724D02*
X1287186Y509726D01*
G01X1287185Y514731D02*
Y514738D01*
G01X1287186Y514726D02*
X1287185Y514731D01*
G01X1287187Y514724D02*
X1287186Y514726D01*
G01X1287185Y519731D02*
Y519738D01*
G01X1287186Y519726D02*
X1287185Y519731D01*
G01X1287187Y519724D02*
X1287186Y519726D01*
G01X1287185Y524731D02*
Y524738D01*
G01X1287186Y524726D02*
X1287185Y524731D01*
G01X1287187Y524724D02*
X1287186Y524726D01*
G01X1287185Y529731D02*
Y529738D01*
G01X1287186Y529726D02*
X1287185Y529731D01*
G01X1287187Y529724D02*
X1287186Y529726D01*
G01X1287185Y534731D02*
Y534738D01*
G01X1287186Y534726D02*
X1287185Y534731D01*
G01X1287187Y534724D02*
X1287186Y534726D01*
G01X1287185Y559731D02*
Y559738D01*
G01X1287186Y559726D02*
X1287185Y559731D01*
G01X1287187Y559724D02*
X1287186Y559726D01*
G01X1287185Y564731D02*
Y564738D01*
G01X1287186Y564726D02*
X1287185Y564731D01*
G01X1287187Y564724D02*
X1287186Y564726D01*
G01X1287185Y569731D02*
Y569738D01*
G01X1287186Y569726D02*
X1287185Y569731D01*
G01X1287187Y569724D02*
X1287186Y569726D01*
G01X1272798Y539687D02*
X1272813Y539685D01*
G01X1272787Y539694D02*
X1272798Y539687D01*
G01X1272775Y539713D02*
X1272787Y539694D01*
G01X1272798Y549136D02*
X1272813Y549134D01*
G01X1272787Y549144D02*
X1272798Y549136D01*
G01X1272775Y549162D02*
X1272787Y549144D01*
G01X1272798Y542837D02*
X1272813Y542835D01*
G01X1272786Y542845D02*
X1272798Y542837D01*
G01X1272774Y542865D02*
X1272786Y542845D01*
G01X1272798Y552286D02*
X1272813Y552283D01*
G01X1272786Y552294D02*
X1272798Y552286D01*
G01X1272774Y552314D02*
X1272786Y552294D01*
G01X1273760Y536569D02*
Y536561D01*
G01X1273759Y536573D02*
X1273760Y536569D01*
G01X1273758Y536575D02*
X1273759Y536573D01*
G01X1273760Y539719D02*
Y539711D01*
G01X1273759Y539723D02*
X1273760Y539719D01*
G01X1273758Y539724D02*
X1273759Y539723D01*
G01X1273760Y542868D02*
Y542860D01*
G01X1273759Y542872D02*
X1273760Y542868D01*
G01X1273758Y542874D02*
X1273759Y542872D01*
G01X1273760Y546018D02*
Y546010D01*
G01X1273759Y546022D02*
X1273760Y546018D01*
G01X1273758Y546024D02*
X1273759Y546022D01*
G01X1273760Y549167D02*
Y549159D01*
G01X1273759Y549172D02*
X1273760Y549167D01*
G01X1273758Y549173D02*
X1273759Y549172D01*
G01X1273760Y552317D02*
Y552309D01*
G01X1273759Y552321D02*
X1273760Y552317D01*
G01X1273758Y552323D02*
X1273759Y552321D01*
G01X1273760Y555467D02*
Y555459D01*
G01X1273759Y555471D02*
X1273760Y555467D01*
G01X1273758Y555472D02*
X1273759Y555471D01*
G01X1272798Y555436D02*
X1272813Y555433D01*
G01X1272785Y555444D02*
X1272798Y555436D01*
G01X1272774Y555464D02*
X1272785Y555444D01*
G01X1272798Y536538D02*
X1272813Y536535D01*
G01X1272785Y536547D02*
X1272798Y536538D01*
G01X1272774Y536567D02*
X1272785Y536547D01*
G01X1273759Y537697D02*
X1273760Y537691D01*
G01X1273757Y537704D02*
X1273759Y537697D01*
G01X1273754Y537709D02*
X1273757Y537704D01*
G01X1273759Y540847D02*
X1273760Y540840D01*
G01X1273757Y540853D02*
X1273759Y540847D01*
G01X1273754Y540859D02*
X1273757Y540853D01*
G01X1273759Y543996D02*
X1273760Y543990D01*
G01X1273757Y544003D02*
X1273759Y543996D01*
G01X1273754Y544009D02*
X1273757Y544003D01*
G01X1273759Y547146D02*
X1273760Y547139D01*
G01X1273757Y547152D02*
X1273759Y547146D01*
G01X1273754Y547158D02*
X1273757Y547152D01*
G01X1273759Y550296D02*
X1273760Y550289D01*
G01X1273757Y550302D02*
X1273759Y550296D01*
G01X1273754Y550308D02*
X1273757Y550302D01*
G01X1273759Y553445D02*
X1273760Y553439D01*
G01X1273757Y553452D02*
X1273759Y553445D01*
G01X1273754Y553457D02*
X1273757Y553452D01*
G01X1273759Y556595D02*
X1273760Y556588D01*
G01X1273757Y556601D02*
X1273759Y556595D01*
G01X1273754Y556607D02*
X1273757Y556601D01*
G01X1273721Y536530D02*
Y536524D01*
G01X1273720Y536534D02*
X1273721Y536530D01*
G01X1273719Y536535D02*
X1273720Y536534D01*
G01X1273721Y539680D02*
Y539674D01*
G01X1273720Y539683D02*
X1273721Y539680D01*
G01X1273719Y539685D02*
X1273720Y539683D01*
G01X1273721Y542830D02*
Y542823D01*
G01X1273720Y542833D02*
X1273721Y542830D01*
G01X1273719Y542835D02*
X1273720Y542833D01*
G01X1273721Y545979D02*
Y545973D01*
G01X1273720Y545983D02*
X1273721Y545979D01*
G01X1273719Y545984D02*
X1273720Y545983D01*
G01X1273721Y549129D02*
Y549122D01*
G01X1273720Y549132D02*
X1273721Y549129D01*
G01X1273719Y549134D02*
X1273720Y549132D01*
G01X1273721Y555428D02*
Y555422D01*
G01X1273720Y555431D02*
X1273721Y555428D01*
G01X1273719Y555433D02*
X1273720Y555431D01*
G01X1286201Y504771D02*
Y504780D01*
G01X1286202Y504765D02*
X1286201Y504771D01*
G01X1286202Y504764D02*
Y504765D01*
G01X1286201Y509771D02*
Y509780D01*
G01X1286202Y509765D02*
X1286201Y509771D01*
G01X1286202Y509764D02*
Y509765D01*
G01X1286201Y514771D02*
Y514780D01*
G01X1286202Y514765D02*
X1286201Y514771D01*
G01X1286202Y514764D02*
Y514765D01*
G01X1286201Y519771D02*
Y519780D01*
G01X1286202Y519765D02*
X1286201Y519771D01*
G01X1286202Y519764D02*
Y519765D01*
G01X1286201Y524771D02*
Y524780D01*
G01X1286202Y524765D02*
X1286201Y524771D01*
G01X1286202Y524764D02*
Y524765D01*
G01X1286201Y529771D02*
Y529780D01*
G01X1286202Y529765D02*
X1286201Y529771D01*
G01X1286202Y529764D02*
Y529765D01*
G01X1286201Y534771D02*
Y534780D01*
G01X1286202Y534765D02*
X1286201Y534771D01*
G01X1286202Y534764D02*
Y534765D01*
G01X1286201Y559771D02*
Y559780D01*
G01X1286202Y559765D02*
X1286201Y559771D01*
G01X1286202Y559764D02*
Y559765D01*
G01X1286201Y564771D02*
Y564780D01*
G01X1286202Y564765D02*
X1286201Y564771D01*
G01X1286202Y564764D02*
Y564765D01*
G01X1286201Y569771D02*
Y569780D01*
G01X1286202Y569765D02*
X1286201Y569771D01*
G01X1286202Y569764D02*
Y569765D01*
G01X1287177Y504907D02*
X1287185Y504881D01*
G01X1287167Y504934D02*
X1287177Y504907D01*
G01X1287156Y504961D02*
X1287167Y504934D01*
G01X1287177Y509907D02*
X1287185Y509881D01*
G01X1287167Y509934D02*
X1287177Y509907D01*
G01X1287156Y509961D02*
X1287167Y509934D01*
G01X1287177Y514907D02*
X1287185Y514881D01*
G01X1287167Y514934D02*
X1287177Y514907D01*
G01X1287156Y514961D02*
X1287167Y514934D01*
G01X1287177Y519907D02*
X1287185Y519881D01*
G01X1287167Y519934D02*
X1287177Y519907D01*
G01X1287156Y519961D02*
X1287167Y519934D01*
G01X1287177Y524907D02*
X1287185Y524881D01*
G01X1287167Y524934D02*
X1287177Y524907D01*
G01X1287156Y524961D02*
X1287167Y524934D01*
G01X1287177Y529907D02*
X1287185Y529881D01*
G01X1287167Y529934D02*
X1287177Y529907D01*
G01X1287156Y529961D02*
X1287167Y529934D01*
G01X1287177Y534907D02*
X1287185Y534881D01*
G01X1287167Y534934D02*
X1287177Y534907D01*
G01X1287156Y534961D02*
X1287167Y534934D01*
G01X1287177Y559907D02*
X1287185Y559881D01*
G01X1287167Y559934D02*
X1287177Y559907D01*
G01X1287156Y559961D02*
X1287167Y559934D01*
G01X1287177Y564907D02*
X1287185Y564881D01*
G01X1287167Y564934D02*
X1287177Y564907D01*
G01X1287156Y564961D02*
X1287167Y564934D01*
G01X1287177Y569907D02*
X1287185Y569881D01*
G01X1287167Y569934D02*
X1287177Y569907D01*
G01X1287156Y569961D02*
X1287167Y569934D01*
G01X1272793Y545989D02*
X1272813Y545984D01*
G01X1272780Y546002D02*
X1272793Y545989D01*
G01X1272773Y546019D02*
X1272780Y546002D01*
G01X1287168Y504759D02*
X1287148Y504764D01*
G01X1287182Y504744D02*
X1287168Y504759D01*
G01X1287187Y504724D02*
X1287182Y504744D01*
G01X1287168Y509759D02*
X1287148Y509764D01*
G01X1287182Y509744D02*
X1287168Y509759D01*
G01X1287187Y509724D02*
X1287182Y509744D01*
G01X1287168Y514759D02*
X1287148Y514764D01*
G01X1287182Y514744D02*
X1287168Y514759D01*
G01X1287187Y514724D02*
X1287182Y514744D01*
G01X1287168Y519759D02*
X1287148Y519764D01*
G01X1287182Y519744D02*
X1287168Y519759D01*
G01X1287187Y519724D02*
X1287182Y519744D01*
G01X1287168Y524759D02*
X1287148Y524764D01*
G01X1287182Y524744D02*
X1287168Y524759D01*
G01X1287187Y524724D02*
X1287182Y524744D01*
G01X1287168Y529759D02*
X1287148Y529764D01*
G01X1287182Y529744D02*
X1287168Y529759D01*
G01X1287187Y529724D02*
X1287182Y529744D01*
G01X1287168Y534759D02*
X1287148Y534764D01*
G01X1287182Y534744D02*
X1287168Y534759D01*
G01X1287187Y534724D02*
X1287182Y534744D01*
G01X1287168Y559759D02*
X1287148Y559764D01*
G01X1287182Y559744D02*
X1287168Y559759D01*
G01X1287187Y559724D02*
X1287182Y559744D01*
G01X1287152Y504862D02*
X1287156Y504961D01*
G01X1287146Y504790D02*
X1287152Y504862D01*
G01X1287148Y504764D02*
X1287146Y504790D01*
G01X1287152Y509862D02*
X1287156Y509961D01*
G01X1287146Y509790D02*
X1287152Y509862D01*
G01X1287148Y509764D02*
X1287146Y509790D01*
G01X1287152Y514862D02*
X1287156Y514961D01*
G01X1287146Y514790D02*
X1287152Y514862D01*
G01X1287148Y514764D02*
X1287146Y514790D01*
G01X1287152Y519862D02*
X1287156Y519961D01*
G01X1287146Y519790D02*
X1287152Y519862D01*
G01X1287148Y519764D02*
X1287146Y519790D01*
G01X1287152Y524862D02*
X1287156Y524961D01*
G01X1287146Y524790D02*
X1287152Y524862D01*
G01X1287148Y524764D02*
X1287146Y524790D01*
G01X1287152Y529862D02*
X1287156Y529961D01*
G01X1287146Y529790D02*
X1287152Y529862D01*
G01X1287148Y529764D02*
X1287146Y529790D01*
G01X1287152Y534862D02*
X1287156Y534961D01*
G01X1287146Y534790D02*
X1287152Y534862D01*
G01X1287148Y534764D02*
X1287146Y534790D01*
G01X1287152Y559862D02*
X1287156Y559961D01*
G01X1287146Y559790D02*
X1287152Y559862D01*
G01X1287148Y559764D02*
X1287146Y559790D01*
G01X1287152Y564862D02*
X1287156Y564961D01*
G01X1287146Y564790D02*
X1287152Y564862D01*
G01X1287148Y564764D02*
X1287146Y564790D01*
G01X1287152Y569862D02*
X1287156Y569961D01*
G01X1287146Y569790D02*
X1287152Y569862D01*
G01X1287148Y569764D02*
X1287146Y569790D01*
G01X1272775Y549167D02*
X1272776Y549160D01*
G01X1272774Y549172D02*
X1272775Y549167D01*
G01Y549162D02*
X1272774Y549172D01*
G01X1272816Y556798D02*
X1272815Y556811D01*
G01X1272813Y556785D02*
X1272816Y556798D01*
G01X1272813Y556772D02*
Y556785D01*
G01X1272816Y553649D02*
X1272815Y553661D01*
G01X1272813Y553636D02*
X1272816Y553649D01*
G01X1272813Y553622D02*
Y553636D01*
G01X1272816Y550499D02*
X1272815Y550512D01*
G01X1272813Y550486D02*
X1272816Y550499D01*
G01X1272813Y550472D02*
Y550486D01*
G01X1272816Y547350D02*
X1272815Y547362D01*
G01X1272813Y547337D02*
X1272816Y547350D01*
G01X1272813Y547323D02*
Y547337D01*
G01X1272816Y544200D02*
X1272815Y544213D01*
G01X1272813Y544187D02*
X1272816Y544200D01*
G01X1272813Y544173D02*
Y544187D01*
G01X1272816Y541050D02*
X1272815Y541063D01*
G01X1272813Y541037D02*
X1272816Y541050D01*
G01X1272813Y541024D02*
Y541037D01*
G01X1272816Y537901D02*
X1272815Y537913D01*
G01X1272813Y537888D02*
X1272816Y537901D01*
G01X1272813Y537874D02*
Y537888D01*
G01X1286202Y568384D02*
Y568386D01*
G01X1286201Y568378D02*
X1286202Y568384D01*
G01X1286201Y568370D02*
Y568378D01*
G01X1286202Y563384D02*
Y563386D01*
G01X1286201Y563378D02*
X1286202Y563384D01*
G01X1286201Y563370D02*
Y563378D01*
G01X1286202Y558384D02*
Y558386D01*
G01X1286201Y558378D02*
X1286202Y558384D01*
G01X1286201Y558370D02*
Y558378D01*
G01X1286202Y533384D02*
Y533386D01*
G01X1286201Y533378D02*
X1286202Y533384D01*
G01X1286201Y533370D02*
Y533378D01*
G01X1286202Y528384D02*
Y528386D01*
G01X1286201Y528378D02*
X1286202Y528384D01*
G01X1286201Y528370D02*
Y528378D01*
G01X1286202Y523384D02*
Y523386D01*
G01X1286201Y523378D02*
X1286202Y523384D01*
G01X1286201Y523370D02*
Y523378D01*
G01X1286202Y518384D02*
Y518386D01*
G01X1286201Y518378D02*
X1286202Y518384D01*
G01X1286201Y518370D02*
Y518378D01*
G01X1286202Y513384D02*
Y513386D01*
G01X1286201Y513378D02*
X1286202Y513384D01*
G01X1286201Y513370D02*
Y513378D01*
G01X1286202Y508384D02*
Y508386D01*
G01X1286201Y508378D02*
X1286202Y508384D01*
G01X1286201Y508370D02*
Y508378D01*
G01X1286202Y503384D02*
Y503386D01*
G01X1286201Y503378D02*
X1286202Y503384D01*
G01X1286201Y503370D02*
Y503378D01*
G01X1272775Y555467D02*
X1272776Y555459D01*
G01X1272774Y555471D02*
X1272775Y555467D01*
G01X1272774Y555463D02*
Y555471D01*
G01X1272813Y555261D02*
X1272811Y555275D01*
G01X1272816Y555249D02*
X1272813Y555261D01*
G01X1272815Y555236D02*
X1272816Y555249D01*
G01X1272813Y552112D02*
X1272811Y552126D01*
G01X1272816Y552099D02*
X1272813Y552112D01*
G01X1272815Y552087D02*
X1272816Y552099D01*
G01X1272813Y548962D02*
X1272811Y548976D01*
G01X1272816Y548950D02*
X1272813Y548962D01*
G01X1272815Y548937D02*
X1272816Y548950D01*
G01X1272813Y545813D02*
X1272811Y545826D01*
G01X1272816Y545800D02*
X1272813Y545813D01*
G01X1272815Y545787D02*
X1272816Y545800D01*
G01X1272813Y542663D02*
X1272811Y542677D01*
G01X1272816Y542650D02*
X1272813Y542663D01*
G01X1272815Y542638D02*
X1272816Y542650D01*
G01X1272813Y539513D02*
X1272811Y539527D01*
G01X1272816Y539501D02*
X1272813Y539513D01*
G01X1272815Y539488D02*
X1272816Y539501D01*
G01X1272813Y536364D02*
X1272811Y536378D01*
G01X1272816Y536351D02*
X1272813Y536364D01*
G01X1272815Y536339D02*
X1272816Y536351D01*
G01X1273723Y556785D02*
X1273724Y556772D01*
G01X1273720Y556798D02*
X1273723Y556785D01*
G01X1273720Y556811D02*
Y556798D01*
G01X1273723Y553636D02*
X1273724Y553622D01*
G01X1273720Y553649D02*
X1273723Y553636D01*
G01X1273720Y553661D02*
Y553649D01*
G01X1273723Y550486D02*
X1273724Y550472D01*
G01X1273720Y550499D02*
X1273723Y550486D01*
G01X1273720Y550512D02*
Y550499D01*
G01X1273723Y547337D02*
X1273724Y547323D01*
G01X1273720Y547350D02*
X1273723Y547337D01*
G01X1273720Y547362D02*
Y547350D01*
G01X1273723Y544187D02*
X1273724Y544173D01*
G01X1273720Y544200D02*
X1273723Y544187D01*
G01X1273720Y544213D02*
Y544200D01*
G01X1273723Y541037D02*
X1273724Y541024D01*
G01X1273720Y541050D02*
X1273723Y541037D01*
G01X1273720Y541063D02*
Y541050D01*
G01X1273723Y537888D02*
X1273724Y537874D01*
G01X1273720Y537901D02*
X1273723Y537888D01*
G01X1273720Y537913D02*
Y537901D01*
G01X1272775Y542868D02*
X1272776Y542861D01*
G01X1272774Y542872D02*
X1272775Y542868D01*
G01X1272774Y542865D02*
Y542872D01*
G01X1272775Y552317D02*
X1272776Y552309D01*
G01X1272774Y552321D02*
X1272775Y552317D01*
G01X1272774Y552314D02*
Y552321D01*
G01X1273720Y555249D02*
Y555236D01*
G01X1273722Y555261D02*
X1273720Y555249D01*
G01X1273724Y555275D02*
X1273722Y555261D01*
G01X1273720Y552099D02*
Y552087D01*
G01X1273722Y552112D02*
X1273720Y552099D01*
G01X1273724Y552126D02*
X1273722Y552112D01*
G01X1273720Y548950D02*
Y548937D01*
G01X1273722Y548962D02*
X1273720Y548950D01*
G01X1273724Y548976D02*
X1273722Y548962D01*
G01X1273720Y545800D02*
Y545787D01*
G01X1273722Y545813D02*
X1273720Y545800D01*
G01X1273724Y545826D02*
X1273722Y545813D01*
G01X1273720Y542650D02*
Y542638D01*
G01X1273722Y542663D02*
X1273720Y542650D01*
G01X1273724Y542677D02*
X1273722Y542663D01*
G01X1273720Y539501D02*
Y539488D01*
G01X1273722Y539513D02*
X1273720Y539501D01*
G01X1273724Y539527D02*
X1273722Y539513D01*
G01X1273720Y536351D02*
Y536339D01*
G01X1273722Y536364D02*
X1273720Y536351D01*
G01X1273724Y536378D02*
X1273722Y536364D01*
G01X1272775Y536569D02*
X1272776Y536561D01*
G01X1272774Y536573D02*
X1272775Y536569D01*
G01X1272774Y536567D02*
Y536573D01*
G01X1273731Y555435D02*
X1273719Y555433D01*
G01X1273741Y555440D02*
X1273731Y555435D01*
G01Y552285D02*
X1273719Y552283D01*
G01X1273741Y552290D02*
X1273731Y552285D01*
G01Y549136D02*
X1273719Y549134D01*
G01X1273741Y549141D02*
X1273731Y549136D01*
G01Y545986D02*
X1273719Y545984D01*
G01X1273741Y545991D02*
X1273731Y545986D01*
G01Y542837D02*
X1273719Y542835D01*
G01X1273741Y542841D02*
X1273731Y542837D01*
G01Y539687D02*
X1273719Y539685D01*
G01X1273741Y539692D02*
X1273731Y539687D01*
G01Y536537D02*
X1273719Y536535D01*
G01X1273741Y536542D02*
X1273731Y536537D01*
G01X1287168Y564759D02*
X1287148Y564764D01*
G01X1287182Y564744D02*
X1287168Y564759D01*
G01X1287187Y564724D02*
X1287182Y564744D01*
G01X1287168Y569759D02*
X1287148Y569764D01*
G01X1287182Y569744D02*
X1287168Y569759D01*
G01X1287187Y569724D02*
X1287182Y569744D01*
G01X1273752Y543998D02*
X1273745Y544006D01*
G01X1273757Y543987D02*
X1273752Y543998D01*
G01X1273759Y543976D02*
X1273757Y543987D01*
G01X1273752Y537698D02*
X1273745Y537707D01*
G01X1273757Y537688D02*
X1273752Y537698D01*
G01X1273759Y537677D02*
X1273757Y537688D01*
G01X1273752Y540848D02*
X1273745Y540856D01*
G01X1273757Y540838D02*
X1273752Y540848D01*
G01X1273759Y540827D02*
X1273757Y540838D01*
G01X1273752Y547147D02*
X1273745Y547156D01*
G01X1273757Y547137D02*
X1273752Y547147D01*
G01X1273759Y547126D02*
X1273757Y547137D01*
G01X1273752Y550297D02*
X1273745Y550305D01*
G01X1273757Y550287D02*
X1273752Y550297D01*
G01X1273759Y550276D02*
X1273757Y550287D01*
G01X1273752Y553446D02*
X1273745Y553455D01*
G01X1273757Y553436D02*
X1273752Y553446D01*
G01X1273759Y553425D02*
X1273757Y553436D01*
G01X1273752Y556596D02*
X1273745Y556604D01*
G01X1273757Y556586D02*
X1273752Y556596D01*
G01X1273759Y556575D02*
X1273757Y556586D01*
G01X1272789Y556606D02*
X1272813Y556614D01*
G01X1272778Y556591D02*
X1272789Y556606D01*
G01X1272776Y556584D02*
X1272778Y556591D01*
G01X1272789Y553456D02*
X1272813Y553465D01*
G01X1272778Y553441D02*
X1272789Y553456D01*
G01X1272776Y553435D02*
X1272778Y553441D01*
G01X1272789Y550306D02*
X1272813Y550315D01*
G01X1272778Y550292D02*
X1272789Y550306D01*
G01X1272776Y550285D02*
X1272778Y550292D01*
G01X1272789Y547157D02*
X1272813Y547165D01*
G01X1272778Y547142D02*
X1272789Y547157D01*
G01X1272776Y547135D02*
X1272778Y547142D01*
G01X1272789Y544007D02*
X1272813Y544016D01*
G01X1272778Y543993D02*
X1272789Y544007D01*
G01X1272776Y543986D02*
X1272778Y543993D01*
G01X1272789Y540857D02*
X1272813Y540866D01*
G01X1272778Y540843D02*
X1272789Y540857D01*
G01X1272776Y540836D02*
X1272778Y540843D01*
G01X1272789Y537708D02*
X1272813Y537717D01*
G01X1272778Y537693D02*
X1272789Y537708D01*
G01X1272776Y537687D02*
X1272778Y537693D01*
G01X1273760Y556581D02*
Y556588D01*
G01X1273759Y556576D02*
X1273760Y556581D01*
G01X1273759Y556575D02*
Y556576D01*
G01X1273760Y553431D02*
Y553439D01*
G01X1273759Y553427D02*
X1273760Y553431D01*
G01X1273759Y553425D02*
Y553427D01*
G01X1273760Y550282D02*
Y550289D01*
G01X1273759Y550277D02*
X1273760Y550282D01*
G01X1273759Y550276D02*
Y550277D01*
G01X1273760Y547132D02*
Y547139D01*
G01X1273759Y547128D02*
X1273760Y547132D01*
G01X1273759Y547126D02*
Y547128D01*
G01X1273760Y543983D02*
Y543990D01*
G01X1273759Y543978D02*
X1273760Y543983D01*
G01X1273759Y543976D02*
Y543978D01*
G01X1273760Y540833D02*
Y540840D01*
G01X1273759Y540828D02*
X1273760Y540833D01*
G01X1273759Y540827D02*
Y540828D01*
G01X1273760Y537683D02*
Y537691D01*
G01X1273759Y537679D02*
X1273760Y537683D01*
G01X1273759Y537677D02*
Y537679D01*
G01X1272775Y546018D02*
X1272776Y546010D01*
G01X1272774Y546022D02*
X1272775Y546018D01*
G01X1272773Y546019D02*
X1272774Y546022D01*
G01X1272775Y539719D02*
X1272776Y539711D01*
G01X1272774Y539723D02*
X1272775Y539719D01*
G01X1272773Y539721D02*
X1272774Y539723D01*
G01X1273720Y556619D02*
Y556625D01*
G01Y556615D02*
Y556619D01*
G01X1273719Y556614D02*
X1273720Y556615D01*
G01Y553470D02*
Y553476D01*
G01Y553466D02*
Y553470D01*
G01X1273719Y553465D02*
X1273720Y553466D01*
G01Y550320D02*
Y550326D01*
G01Y550316D02*
Y550320D01*
G01X1273719Y550315D02*
X1273720Y550316D01*
G01Y547170D02*
Y547176D01*
G01Y547167D02*
Y547170D01*
G01X1273719Y547165D02*
X1273720Y547167D01*
G01Y544021D02*
Y544027D01*
G01Y544017D02*
Y544021D01*
G01X1273719Y544016D02*
X1273720Y544017D01*
G01Y540871D02*
Y540877D01*
G01Y540867D02*
Y540871D01*
G01X1273719Y540866D02*
X1273720Y540867D01*
G01Y537722D02*
Y537728D01*
G01Y537718D02*
Y537722D01*
G01X1273719Y537717D02*
X1273720Y537718D01*
G01X1287185Y568378D02*
Y568369D01*
G01X1287186Y568384D02*
X1287185Y568378D01*
G01X1287188Y568386D02*
X1287186Y568384D01*
G01X1287185Y563378D02*
Y563369D01*
G01X1287186Y563384D02*
X1287185Y563378D01*
G01X1287188Y563386D02*
X1287186Y563384D01*
G01X1287185Y558378D02*
Y558369D01*
G01X1287186Y558384D02*
X1287185Y558378D01*
G01X1287188Y558386D02*
X1287186Y558384D01*
G01X1287185Y533378D02*
Y533369D01*
G01X1287186Y533384D02*
X1287185Y533378D01*
G01X1287188Y533386D02*
X1287186Y533384D01*
G01X1287185Y528378D02*
Y528369D01*
G01X1287186Y528384D02*
X1287185Y528378D01*
G01X1287188Y528386D02*
X1287186Y528384D01*
G01X1287185Y523378D02*
Y523369D01*
G01X1287186Y523384D02*
X1287185Y523378D01*
G01X1287188Y523386D02*
X1287186Y523384D01*
G01X1287185Y518378D02*
Y518369D01*
G01X1287186Y518384D02*
X1287185Y518378D01*
G01X1287188Y518386D02*
X1287186Y518384D01*
G01X1287185Y513378D02*
Y513369D01*
G01X1287186Y513384D02*
X1287185Y513378D01*
G01X1287188Y513386D02*
X1287186Y513384D01*
G01X1287185Y508378D02*
Y508369D01*
G01X1287186Y508384D02*
X1287185Y508378D01*
G01X1287188Y508386D02*
X1287186Y508384D01*
G01X1287185Y503378D02*
Y503369D01*
G01X1287186Y503384D02*
X1287185Y503378D01*
G01X1287188Y503386D02*
X1287186Y503384D01*
G01X1272775Y556581D02*
X1272776Y556588D01*
G01X1272774Y556576D02*
X1272775Y556581D01*
G01X1272773Y556575D02*
X1272774Y556576D01*
G01X1272775Y553431D02*
X1272776Y553439D01*
G01X1272774Y553427D02*
X1272775Y553431D01*
G01X1272773Y553425D02*
X1272774Y553427D01*
G01X1272775Y550281D02*
X1272776Y550289D01*
G01X1272774Y550277D02*
X1272775Y550281D01*
G01X1272773Y550276D02*
X1272774Y550277D01*
G01X1272775Y547132D02*
X1272776Y547139D01*
G01X1272774Y547128D02*
X1272775Y547132D01*
G01X1272773Y547126D02*
X1272774Y547128D01*
G01X1272775Y543982D02*
X1272776Y543990D01*
G01X1272774Y543978D02*
X1272775Y543982D01*
G01X1272773Y543976D02*
X1272774Y543978D01*
G01X1272775Y540833D02*
X1272776Y540840D01*
G01X1272774Y540828D02*
X1272775Y540833D01*
G01X1272773Y540827D02*
X1272774Y540828D01*
G01X1272775Y537683D02*
X1272776Y537691D01*
G01X1272774Y537679D02*
X1272775Y537683D01*
G01X1272773Y537677D02*
X1272774Y537679D01*
G01X1273757Y555446D02*
X1273760Y555459D01*
G01X1273751Y555435D02*
X1273757Y555446D01*
G01X1273741Y555427D02*
X1273751Y555435D01*
G01X1273757Y549147D02*
X1273760Y549159D01*
G01X1273751Y549136D02*
X1273757Y549147D01*
G01X1273741Y549128D02*
X1273751Y549136D01*
G01X1273757Y545998D02*
X1273760Y546010D01*
G01X1273751Y545986D02*
X1273757Y545998D01*
G01X1273741Y545978D02*
X1273751Y545986D01*
G01X1273757Y542848D02*
X1273760Y542860D01*
G01X1273751Y542837D02*
X1273757Y542848D01*
G01X1273741Y542829D02*
X1273751Y542837D01*
G01X1273757Y539698D02*
X1273760Y539711D01*
G01X1273751Y539687D02*
X1273757Y539698D01*
G01X1273741Y539679D02*
X1273751Y539687D01*
G01X1273757Y536549D02*
X1273760Y536561D01*
G01X1273751Y536537D02*
X1273757Y536549D01*
G01X1273741Y536530D02*
X1273751Y536537D01*
G01X1272814Y556619D02*
Y556625D01*
G01Y556615D02*
Y556619D01*
G01X1272813Y556614D02*
X1272814Y556615D01*
G01Y553469D02*
Y553476D01*
G01Y553466D02*
Y553469D01*
G01X1272813Y553465D02*
X1272814Y553466D01*
G01Y550320D02*
Y550326D01*
G01Y550316D02*
Y550320D01*
G01X1272813Y550315D02*
X1272814Y550316D01*
G01Y547170D02*
Y547176D01*
G01Y547167D02*
Y547170D01*
G01X1272813Y547165D02*
X1272814Y547167D01*
G01Y544020D02*
Y544027D01*
G01Y544017D02*
Y544020D01*
G01X1272813Y544016D02*
X1272814Y544017D01*
G01Y540871D02*
Y540877D01*
G01Y540867D02*
Y540871D01*
G01X1272813Y540866D02*
X1272814Y540867D01*
G01Y537721D02*
Y537728D01*
G01Y537718D02*
Y537721D01*
G01X1272813Y537717D02*
X1272814Y537718D01*
G01X1272776Y556594D02*
Y556588D01*
G01X1272778Y556601D02*
X1272776Y556594D01*
G01X1272781Y556607D02*
X1272778Y556601D01*
G01X1272785Y556612D02*
X1272781Y556607D01*
G01X1272789Y556617D02*
X1272785Y556612D01*
G01X1272795Y556620D02*
X1272789Y556617D01*
G01X1272776Y553445D02*
Y553439D01*
G01X1272778Y553451D02*
X1272776Y553445D01*
G01X1272781Y553457D02*
X1272778Y553451D01*
G01X1272785Y553462D02*
X1272781Y553457D01*
G01X1272789Y553467D02*
X1272785Y553462D01*
G01X1272795Y553470D02*
X1272789Y553467D01*
G01X1272776Y550295D02*
Y550289D01*
G01X1272778Y550302D02*
X1272776Y550295D01*
G01X1272781Y550307D02*
X1272778Y550302D01*
G01X1272785Y550313D02*
X1272781Y550307D01*
G01X1272789Y550317D02*
X1272785Y550313D01*
G01X1272795Y550321D02*
X1272789Y550317D01*
G01X1272776Y547146D02*
Y547139D01*
G01X1272778Y547152D02*
X1272776Y547146D01*
G01X1272781Y547158D02*
X1272778Y547152D01*
G01X1272785Y547163D02*
X1272781Y547158D01*
G01X1272789Y547168D02*
X1272785Y547163D01*
G01X1272795Y547171D02*
X1272789Y547168D01*
G01X1272776Y543996D02*
Y543990D01*
G01X1272778Y544002D02*
X1272776Y543996D01*
G01X1272781Y544008D02*
X1272778Y544002D01*
G01X1272785Y544013D02*
X1272781Y544008D01*
G01X1272789Y544018D02*
X1272785Y544013D01*
G01X1272795Y544022D02*
X1272789Y544018D01*
G01X1272776Y540846D02*
Y540840D01*
G01X1272778Y540853D02*
X1272776Y540846D01*
G01X1272781Y540859D02*
X1272778Y540853D01*
G01X1272785Y540864D02*
X1272781Y540859D01*
G01X1272789Y540869D02*
X1272785Y540864D01*
G01X1272795Y540872D02*
X1272789Y540869D01*
G01X1272776Y537697D02*
Y537691D01*
G01X1272778Y537703D02*
X1272776Y537697D01*
G01X1272781Y537709D02*
X1272778Y537703D01*
G01X1272785Y537714D02*
X1272781Y537709D01*
G01X1272789Y537719D02*
X1272785Y537714D01*
G01X1272795Y537722D02*
X1272789Y537719D01*
G01X1277756Y477894D02*
G03X1278346Y477303I591J0D01*
G01X1285039D02*
G03X1285630Y477894I0J591D01*
G01X1282874Y479075D02*
G03Y481043I0J984D01*
G01X1280512D02*
G03Y479075I0J-984D01*
G01X1282795Y492264D02*
G03I-1102J0D01*
G01X1284252Y486988D02*
G03X1285433Y488169I0J1181D01*
G01X1277953D02*
G03X1279134Y486988I1181J0D01*
G01X1283268Y492264D02*
G03I-1575J0D01*
G01X1270866Y478484D02*
G03X1272835Y476516I1968J0D01*
G01X1290551D02*
G03X1292520Y478484I1J1968D01*
G01X1277165Y500256D02*
X1275984Y499075D01*
G01X1274213Y497579D02*
X1270866Y494232D01*
G01X1286614Y556437D02*
X1287795Y557618D01*
G01X1282677Y556437D02*
X1283858Y557618D01*
G01X1284178Y495335D02*
X1282874Y493366D01*
G01X1278202Y487444D02*
X1280512Y491673D01*
G01X1273759Y537679D02*
X1273760Y537691D01*
G01X1273759Y540829D02*
X1273760Y540840D01*
G01X1273759Y543978D02*
X1273760Y543990D01*
G01X1273759Y547128D02*
X1273760Y547139D01*
G01X1273759Y550278D02*
X1273760Y550289D01*
G01X1273759Y553427D02*
X1273760Y553439D01*
G01X1273759Y556577D02*
X1273760Y556588D01*
G01X1287185Y504738D02*
Y504746D01*
G01Y509738D02*
Y509746D01*
G01Y514738D02*
Y514746D01*
G01Y519738D02*
Y519746D01*
G01Y524738D02*
Y524746D01*
G01Y529738D02*
Y529746D01*
G01Y534738D02*
Y534746D01*
G01Y559738D02*
Y559746D01*
G01Y564738D02*
Y564746D01*
G01Y569738D02*
Y569746D01*
G01X1292520Y478484D02*
Y494232D01*
G01X1291535Y568386D02*
Y569764D01*
G01Y563386D02*
Y564764D01*
G01Y558386D02*
Y559764D01*
G01Y533386D02*
Y534764D01*
G01Y528386D02*
Y529764D01*
G01Y523386D02*
Y524764D01*
G01Y518386D02*
Y519764D01*
G01Y513386D02*
Y514764D01*
G01Y508386D02*
Y509764D01*
G01Y503386D02*
Y504764D01*
G01X1289173Y635571D02*
Y497579D01*
G01X1288583Y637815D02*
Y495335D01*
G01X1288366Y504764D02*
Y503386D01*
G01Y509764D02*
Y508386D01*
G01Y514764D02*
Y513386D01*
G01Y519764D02*
Y518386D01*
G01Y524764D02*
Y523386D01*
G01Y529764D02*
Y528386D01*
G01Y534764D02*
Y533386D01*
G01Y559764D02*
Y558386D01*
G01Y564764D02*
Y563386D01*
G01Y569764D02*
Y568386D01*
G01X1287795Y557618D02*
Y535531D01*
G01X1287185Y504738D02*
Y504881D01*
G01Y509738D02*
Y509881D01*
G01Y514738D02*
Y514881D01*
G01Y519738D02*
Y519881D01*
G01Y524738D02*
Y524881D01*
G01Y529738D02*
Y529881D01*
G01Y534738D02*
Y534881D01*
G01Y559738D02*
Y559881D01*
G01Y564738D02*
Y564881D01*
G01Y567894D02*
Y570256D01*
G01Y562894D02*
Y565256D01*
G01Y557894D02*
Y560256D01*
G01Y532894D02*
Y535256D01*
G01Y527894D02*
Y530256D01*
G01Y522894D02*
Y525256D01*
G01Y517894D02*
Y520256D01*
G01Y512894D02*
Y515256D01*
G01Y507894D02*
Y510256D01*
G01Y502894D02*
Y505256D01*
G01X1286614Y556437D02*
Y536713D01*
G01X1286201Y505256D02*
Y502894D01*
G01Y510256D02*
Y507894D01*
G01Y515256D02*
Y512894D01*
G01Y520256D02*
Y517894D01*
G01Y525256D02*
Y522894D01*
G01Y530256D02*
Y527894D01*
G01Y535256D02*
Y532894D01*
G01Y560256D02*
Y557894D01*
G01Y565256D02*
Y562894D01*
G01Y570256D02*
Y567894D01*
G01X1285630Y483996D02*
Y477894D01*
G01X1285433Y496713D02*
Y488169D01*
G01X1283858Y535531D02*
Y499075D01*
G01Y634075D02*
Y557618D01*
G01X1282874Y493366D02*
Y491673D01*
G01X1282677Y536713D02*
Y500256D01*
G01Y632894D02*
Y556437D01*
G01X1280512Y491673D02*
Y493366D01*
G01X1277953Y488169D02*
Y496713D01*
G01X1277756Y483996D02*
Y477894D01*
G01X1277165Y500256D02*
Y632894D01*
G01X1275984Y499075D02*
Y634075D01*
G01X1274213Y534370D02*
Y495335D01*
G01Y637815D02*
Y558780D01*
G01X1273760Y555275D02*
Y556772D01*
G01Y552126D02*
Y553622D01*
G01Y548976D02*
Y550472D01*
G01Y545826D02*
Y547323D01*
G01Y542677D02*
Y544173D01*
G01Y539527D02*
Y541024D01*
G01Y536378D02*
Y537874D01*
G01X1273720Y536524D02*
Y536377D01*
G01Y539674D02*
Y539527D01*
G01Y541024D02*
Y540877D01*
G01Y537874D02*
Y537728D01*
G01Y545973D02*
Y545826D01*
G01Y542823D02*
Y542676D01*
G01Y544174D02*
Y544027D01*
G01Y549122D02*
Y548976D01*
G01Y550473D02*
Y550326D01*
G01Y547323D02*
Y547176D01*
G01Y555422D02*
Y555275D01*
G01Y552272D02*
Y552125D01*
G01Y553622D02*
Y553476D01*
G01Y556772D02*
Y556625D01*
G01X1272815D02*
Y556772D01*
G01Y555275D02*
Y555422D01*
G01Y552125D02*
Y552272D01*
G01Y553476D02*
Y553622D01*
G01Y548976D02*
Y549122D01*
G01Y550326D02*
Y550473D01*
G01Y547176D02*
Y547323D01*
G01Y545826D02*
Y545973D01*
G01Y542676D02*
Y542823D01*
G01Y544027D02*
Y544174D01*
G01Y539527D02*
Y539674D01*
G01Y540877D02*
Y541024D01*
G01Y537728D02*
Y537874D01*
G01Y536377D02*
Y536524D01*
G01X1272776Y541024D02*
Y539528D01*
G01Y537874D02*
Y536378D01*
G01Y544173D02*
Y542677D01*
G01Y550472D02*
Y548976D01*
G01Y547323D02*
Y545827D01*
G01Y553622D02*
Y552126D01*
G01Y556772D02*
Y555276D01*
G01X1271594Y537717D02*
Y536535D01*
G01Y540866D02*
Y539685D01*
G01Y547165D02*
Y545984D01*
G01Y544016D02*
Y542835D01*
G01Y550315D02*
Y549134D01*
G01Y556614D02*
Y555433D01*
G01Y553465D02*
Y552283D01*
G01X1271260Y558780D02*
Y534370D01*
G01X1270866D02*
Y558780D01*
G01Y494232D02*
Y478484D01*
G01X1267835Y555433D02*
Y556614D01*
G01Y552283D02*
Y553465D01*
G01Y549134D02*
Y550315D01*
G01Y545984D02*
Y547165D01*
G01Y542835D02*
Y544016D01*
G01Y539685D02*
Y540866D01*
G01Y536535D02*
Y537717D01*
G01X1273760Y555459D02*
X1273759Y555470D01*
G01X1273760Y552309D02*
X1273759Y552320D01*
G01X1273760Y549160D02*
X1273759Y549170D01*
G01X1273760Y546010D02*
X1273759Y546021D01*
G01X1273760Y542861D02*
X1273759Y542871D01*
G01X1273760Y539711D02*
X1273759Y539722D01*
G01X1273760Y536561D02*
X1273759Y536572D01*
G01X1273719Y552283D02*
X1273722Y552272D01*
G01X1282874Y491673D02*
X1285184Y487444D01*
G01X1280512Y493366D02*
X1279208Y495335D01*
G01X1286614Y536713D02*
X1287795Y535531D01*
G01X1282677Y536713D02*
X1283858Y535531D01*
G01X1289173Y497579D02*
X1292520Y494232D01*
G01X1282677Y500256D02*
X1283858Y499075D01*
G01X1272662Y555472D02*
X1272774Y555464D01*
G01X1272773Y546019D02*
X1272662Y546024D01*
G01X1272773Y539721D02*
X1272662Y539724D01*
G01X1272773Y549170D02*
X1272662Y549173D01*
G01X1287185Y570256D02*
X1286201D01*
G01X1286202Y569764D02*
X1291535D01*
G01Y569724D02*
X1287187D01*
G01X1291535Y568386D02*
X1286202D01*
G01X1286201Y567894D02*
X1287185D01*
G01Y565256D02*
X1286201D01*
G01X1286202Y564764D02*
X1291535D01*
G01Y564724D02*
X1287187D01*
G01X1291535Y563386D02*
X1286202D01*
G01X1286201Y562894D02*
X1287185D01*
G01Y560256D02*
X1286201D01*
G01X1286202Y559764D02*
X1291535D01*
G01Y559724D02*
X1287187D01*
G01X1274213Y558780D02*
X1270866D01*
G01X1291535Y558386D02*
X1286202D01*
G01X1286201Y557894D02*
X1287185D01*
G01X1283858Y557618D02*
X1287795D01*
G01X1273720Y556811D02*
X1272815D01*
G01X1273760Y556772D02*
X1272776D01*
G01X1273719Y556614D02*
X1267835D01*
G01Y556575D02*
X1273759D01*
G01X1282677Y556437D02*
X1286614D01*
G01X1273758Y555472D02*
X1267835D01*
G01X1273719Y555433D02*
X1267835D01*
G01X1272776Y555276D02*
X1273760D01*
G01X1272815Y555236D02*
X1273720D01*
G01Y553661D02*
X1272815D01*
G01X1273760Y553622D02*
X1272776D01*
G01X1273719Y553465D02*
X1267835D01*
G01Y553425D02*
X1273759D01*
G01X1273758Y552323D02*
X1267835D01*
G01X1273719Y552283D02*
X1267835D01*
G01X1272776Y552126D02*
X1273760D01*
G01X1272815Y552087D02*
X1273720D01*
G01Y550512D02*
X1272815D01*
G01X1273760Y550472D02*
X1272776D01*
G01X1273719Y550315D02*
X1267835D01*
G01Y550276D02*
X1273759D01*
G01X1272028Y549173D02*
X1271594D01*
G01X1273758D02*
X1267835D01*
G01X1273719Y549134D02*
X1267835D01*
G01X1272776Y548976D02*
X1273760D01*
G01X1272815Y548937D02*
X1273720D01*
G01Y547362D02*
X1272815D01*
G01X1273760Y547323D02*
X1272776D01*
G01X1273719Y547165D02*
X1267835D01*
G01Y547126D02*
X1273759D01*
G01X1272028Y546024D02*
X1271594D01*
G01X1273758D02*
X1267835D01*
G01X1273719Y545984D02*
X1267835D01*
G01X1272776Y545827D02*
X1273760D01*
G01X1272815Y545787D02*
X1273720D01*
G01Y544213D02*
X1272815D01*
G01X1273760Y544173D02*
X1272776D01*
G01X1273719Y544016D02*
X1267835D01*
G01Y543976D02*
X1273759D01*
G01X1273758Y542874D02*
X1267835D01*
G01X1273719Y542835D02*
X1267835D01*
G01X1272776Y542677D02*
X1273760D01*
G01X1272815Y542638D02*
X1273720D01*
G01Y541063D02*
X1272815D01*
G01X1273760Y541024D02*
X1272776D01*
G01X1273719Y540866D02*
X1267835D01*
G01Y540827D02*
X1273759D01*
G01X1272028Y539724D02*
X1271594D01*
G01X1273758D02*
X1267835D01*
G01X1273719Y539685D02*
X1267835D01*
G01X1272776Y539528D02*
X1273760D01*
G01X1272815Y539488D02*
X1273720D01*
G01Y537913D02*
X1272815D01*
G01X1273760Y537874D02*
X1272776D01*
G01X1273719Y537717D02*
X1267835D01*
G01Y537677D02*
X1273759D01*
G01X1286614Y536713D02*
X1282677D01*
G01X1273758Y536575D02*
X1267835D01*
G01X1273719Y536535D02*
X1267835D01*
G01X1272776Y536378D02*
X1273760D01*
G01X1272815Y536339D02*
X1273720D01*
G01X1287795Y535531D02*
X1283858D01*
G01X1287185Y535256D02*
X1286201D01*
G01X1286202Y534764D02*
X1291535D01*
G01Y534724D02*
X1287187D01*
G01X1274213Y534370D02*
X1270866D01*
G01X1291535Y533386D02*
X1286202D01*
G01X1286201Y532894D02*
X1287185D01*
G01Y530256D02*
X1286201D01*
G01X1286202Y529764D02*
X1291535D01*
G01Y529724D02*
X1287187D01*
G01X1291535Y528386D02*
X1286202D01*
G01X1286201Y569959D02*
X1287156Y569961D01*
G01X1287185Y568190D02*
X1286201Y568189D01*
G01Y564959D02*
X1287156Y564961D01*
G01X1287185Y563190D02*
X1286201Y563189D01*
G01Y559959D02*
X1287156Y559961D01*
G01X1287185Y558190D02*
X1286201Y558189D01*
G01Y534959D02*
X1287156Y534961D01*
G01X1287185Y533190D02*
X1286201Y533189D01*
G01Y529959D02*
X1287156Y529961D01*
G01X1286201Y527894D02*
X1287185D01*
G01Y525256D02*
X1286201D01*
G01X1286202Y524764D02*
X1291535D01*
G01Y524724D02*
X1287187D01*
G01X1291535Y523386D02*
X1286202D01*
G01X1286201Y522894D02*
X1287185D01*
G01Y520256D02*
X1286201D01*
G01X1286202Y519764D02*
X1291535D01*
G01Y519724D02*
X1287187D01*
G01X1291535Y518386D02*
X1286202D01*
G01X1286201Y517894D02*
X1287185D01*
G01Y515256D02*
X1286201D01*
G01X1286202Y514764D02*
X1291535D01*
G01Y514724D02*
X1287187D01*
G01X1291535Y513386D02*
X1286202D01*
G01X1286201Y512894D02*
X1287185D01*
G01Y510256D02*
X1286201D01*
G01X1286202Y509764D02*
X1291535D01*
G01Y509724D02*
X1287187D01*
G01X1291535Y508386D02*
X1286202D01*
G01X1286201Y507894D02*
X1287185D01*
G01Y505256D02*
X1286201D01*
G01X1286202Y504764D02*
X1291535D01*
G01Y504724D02*
X1287187D01*
G01X1291535Y503386D02*
X1286202D01*
G01X1286201Y502894D02*
X1287185D01*
G01X1282677Y500256D02*
X1277165D01*
G01X1283858Y499075D02*
X1275984D01*
G01X1289173Y497579D02*
X1274213D01*
G01X1285433Y496713D02*
X1288583D01*
G01X1277953D02*
X1274213D01*
G01Y495335D02*
X1288583D01*
G01X1282874Y493366D02*
X1280512D01*
G01X1282874Y491673D02*
X1280512D01*
G01X1284252Y486988D02*
X1279134D01*
G01X1292520Y486949D02*
X1270866D01*
G01X1285630Y483996D02*
X1277756D01*
G01Y482421D02*
X1285630D01*
G01X1282874Y481043D02*
X1280512D01*
G01Y479075D02*
X1282874D01*
G01X1285039Y477303D02*
X1278346D01*
G01X1290551Y476516D02*
X1272835D01*
G01X1287185Y528190D02*
X1286201Y528189D01*
G01Y524959D02*
X1287156Y524961D01*
G01X1287185Y523190D02*
X1286201Y523189D01*
G01Y519959D02*
X1287156Y519961D01*
G01X1287185Y518190D02*
X1286201Y518189D01*
G01Y514959D02*
X1287156Y514961D01*
G01X1287185Y513190D02*
X1286201Y513189D01*
G01Y509959D02*
X1287156Y509961D01*
G01X1287185Y508190D02*
X1286201Y508189D01*
G01Y504959D02*
X1287156Y504961D01*
G01X1287185Y503190D02*
X1286201Y503189D01*
G01X1287172Y574755D02*
X1287183Y574740D01*
G01X1287148Y574764D02*
X1287172Y574755D01*
G01Y579755D02*
X1287183Y579740D01*
G01X1287148Y579764D02*
X1287172Y579755D01*
G01Y584755D02*
X1287183Y584740D01*
G01X1287148Y584764D02*
X1287172Y584755D01*
G01Y589755D02*
X1287183Y589740D01*
G01X1287148Y589764D02*
X1287172Y589755D01*
G01Y594755D02*
X1287183Y594740D01*
G01X1287148Y594764D02*
X1287172Y594755D01*
G01Y599755D02*
X1287183Y599740D01*
G01X1287148Y599764D02*
X1287172Y599755D01*
G01Y604755D02*
X1287183Y604740D01*
G01X1287148Y604764D02*
X1287172Y604755D01*
G01Y609755D02*
X1287183Y609740D01*
G01X1287148Y609764D02*
X1287172Y609755D01*
G01Y614755D02*
X1287183Y614740D01*
G01X1287148Y614764D02*
X1287172Y614755D01*
G01Y619755D02*
X1287183Y619740D01*
G01X1287148Y619764D02*
X1287172Y619755D01*
G01Y624755D02*
X1287183Y624740D01*
G01X1287148Y624764D02*
X1287172Y624755D01*
G01Y629755D02*
X1287183Y629740D01*
G01X1287148Y629764D02*
X1287172Y629755D01*
G01X1287185Y574731D02*
Y574738D01*
G01X1287186Y574726D02*
X1287185Y574731D01*
G01X1287187Y574724D02*
X1287186Y574726D01*
G01X1287185Y579731D02*
Y579738D01*
G01X1287186Y579726D02*
X1287185Y579731D01*
G01X1287187Y579724D02*
X1287186Y579726D01*
G01X1287185Y584731D02*
Y584738D01*
G01X1287186Y584726D02*
X1287185Y584731D01*
G01X1287187Y584724D02*
X1287186Y584726D01*
G01X1287185Y589731D02*
Y589738D01*
G01X1287186Y589726D02*
X1287185Y589731D01*
G01X1287187Y589724D02*
X1287186Y589726D01*
G01X1287185Y594731D02*
Y594738D01*
G01X1287186Y594726D02*
X1287185Y594731D01*
G01X1287187Y594724D02*
X1287186Y594726D01*
G01X1287185Y599731D02*
Y599738D01*
G01X1287186Y599726D02*
X1287185Y599731D01*
G01X1287187Y599724D02*
X1287186Y599726D01*
G01X1287185Y604731D02*
Y604738D01*
G01X1287186Y604726D02*
X1287185Y604731D01*
G01X1287187Y604724D02*
X1287186Y604726D01*
G01X1287185Y609731D02*
Y609738D01*
G01X1287186Y609726D02*
X1287185Y609731D01*
G01X1287187Y609724D02*
X1287186Y609726D01*
G01X1287185Y614731D02*
Y614738D01*
G01X1287186Y614726D02*
X1287185Y614731D01*
G01X1287187Y614724D02*
X1287186Y614726D01*
G01X1287185Y619731D02*
Y619738D01*
G01X1287186Y619726D02*
X1287185Y619731D01*
G01X1287187Y619724D02*
X1287186Y619726D01*
G01X1287185Y624731D02*
Y624738D01*
G01X1287186Y624726D02*
X1287185Y624731D01*
G01X1287187Y624724D02*
X1287186Y624726D01*
G01X1287185Y629731D02*
Y629738D01*
G01X1287186Y629726D02*
X1287185Y629731D01*
G01X1287187Y629724D02*
X1287186Y629726D01*
G01X1286201Y574771D02*
Y574780D01*
G01X1286202Y574765D02*
X1286201Y574771D01*
G01X1286202Y574764D02*
Y574765D01*
G01X1286201Y579771D02*
Y579780D01*
G01X1286202Y579765D02*
X1286201Y579771D01*
G01X1286202Y579764D02*
Y579765D01*
G01X1286201Y584771D02*
Y584780D01*
G01X1286202Y584765D02*
X1286201Y584771D01*
G01X1286202Y584764D02*
Y584765D01*
G01X1286201Y589771D02*
Y589780D01*
G01X1286202Y589765D02*
X1286201Y589771D01*
G01X1286202Y589764D02*
Y589765D01*
G01X1286201Y594771D02*
Y594780D01*
G01X1286202Y594765D02*
X1286201Y594771D01*
G01X1286202Y594764D02*
Y594765D01*
G01X1286201Y599771D02*
Y599780D01*
G01X1286202Y599765D02*
X1286201Y599771D01*
G01X1286202Y599764D02*
Y599765D01*
G01X1286201Y604771D02*
Y604780D01*
G01X1286202Y604765D02*
X1286201Y604771D01*
G01X1286202Y604764D02*
Y604765D01*
G01X1286201Y609771D02*
Y609780D01*
G01X1286202Y609765D02*
X1286201Y609771D01*
G01X1286202Y609764D02*
Y609765D01*
G01X1286201Y614771D02*
Y614780D01*
G01X1286202Y614765D02*
X1286201Y614771D01*
G01X1286202Y614764D02*
Y614765D01*
G01X1286201Y619771D02*
Y619780D01*
G01X1286202Y619765D02*
X1286201Y619771D01*
G01X1286202Y619764D02*
Y619765D01*
G01X1286201Y624771D02*
Y624780D01*
G01X1286202Y624765D02*
X1286201Y624771D01*
G01X1286202Y624764D02*
Y624765D01*
G01X1286201Y629771D02*
Y629780D01*
G01X1286202Y629765D02*
X1286201Y629771D01*
G01X1286202Y629764D02*
Y629765D01*
G01X1287177Y574907D02*
X1287185Y574881D01*
G01X1287167Y574934D02*
X1287177Y574907D01*
G01X1287156Y574961D02*
X1287167Y574934D01*
G01X1287177Y579907D02*
X1287185Y579881D01*
G01X1287167Y579934D02*
X1287177Y579907D01*
G01X1287156Y579961D02*
X1287167Y579934D01*
G01X1287177Y584907D02*
X1287185Y584881D01*
G01X1287167Y584934D02*
X1287177Y584907D01*
G01X1287156Y584961D02*
X1287167Y584934D01*
G01X1287177Y589907D02*
X1287185Y589881D01*
G01X1287167Y589934D02*
X1287177Y589907D01*
G01X1287156Y589961D02*
X1287167Y589934D01*
G01X1287177Y594907D02*
X1287185Y594881D01*
G01X1287167Y594934D02*
X1287177Y594907D01*
G01X1287156Y594961D02*
X1287167Y594934D01*
G01X1287177Y599907D02*
X1287185Y599881D01*
G01X1287167Y599934D02*
X1287177Y599907D01*
G01X1287156Y599961D02*
X1287167Y599934D01*
G01X1287177Y604907D02*
X1287185Y604881D01*
G01X1287167Y604934D02*
X1287177Y604907D01*
G01X1287156Y604961D02*
X1287167Y604934D01*
G01X1287177Y609907D02*
X1287185Y609881D01*
G01X1287167Y609934D02*
X1287177Y609907D01*
G01X1287156Y609961D02*
X1287167Y609934D01*
G01X1287177Y614907D02*
X1287185Y614881D01*
G01X1287167Y614934D02*
X1287177Y614907D01*
G01X1287156Y614961D02*
X1287167Y614934D01*
G01X1287177Y619907D02*
X1287185Y619881D01*
G01X1287167Y619934D02*
X1287177Y619907D01*
G01X1287156Y619961D02*
X1287167Y619934D01*
G01X1287177Y624907D02*
X1287185Y624881D01*
G01X1287167Y624934D02*
X1287177Y624907D01*
G01X1287156Y624961D02*
X1287167Y624934D01*
G01X1287177Y629907D02*
X1287185Y629881D01*
G01X1287167Y629934D02*
X1287177Y629907D01*
G01X1287156Y629961D02*
X1287167Y629934D01*
G01X1287152Y574862D02*
X1287156Y574961D01*
G01X1287146Y574790D02*
X1287152Y574862D01*
G01X1287148Y574764D02*
X1287146Y574790D01*
G01X1287152Y579862D02*
X1287156Y579961D01*
G01X1287146Y579790D02*
X1287152Y579862D01*
G01X1287148Y579764D02*
X1287146Y579790D01*
G01X1287152Y584862D02*
X1287156Y584961D01*
G01X1287146Y584790D02*
X1287152Y584862D01*
G01X1287148Y584764D02*
X1287146Y584790D01*
G01X1287152Y589862D02*
X1287156Y589961D01*
G01X1287146Y589790D02*
X1287152Y589862D01*
G01X1287148Y589764D02*
X1287146Y589790D01*
G01X1287152Y594862D02*
X1287156Y594961D01*
G01X1287146Y594790D02*
X1287152Y594862D01*
G01X1287148Y594764D02*
X1287146Y594790D01*
G01X1287152Y599862D02*
X1287156Y599961D01*
G01X1287146Y599790D02*
X1287152Y599862D01*
G01X1287148Y599764D02*
X1287146Y599790D01*
G01X1287152Y604862D02*
X1287156Y604961D01*
G01X1287146Y604790D02*
X1287152Y604862D01*
G01X1287148Y604764D02*
X1287146Y604790D01*
G01X1287152Y609862D02*
X1287156Y609961D01*
G01X1287146Y609790D02*
X1287152Y609862D01*
G01X1287148Y609764D02*
X1287146Y609790D01*
G01X1287152Y614862D02*
X1287156Y614961D01*
G01X1287146Y614790D02*
X1287152Y614862D01*
G01X1287148Y614764D02*
X1287146Y614790D01*
G01X1287152Y619862D02*
X1287156Y619961D01*
G01X1287146Y619790D02*
X1287152Y619862D01*
G01X1287148Y619764D02*
X1287146Y619790D01*
G01X1287152Y624862D02*
X1287156Y624961D01*
G01X1287146Y624790D02*
X1287152Y624862D01*
G01X1287148Y624764D02*
X1287146Y624790D01*
G01X1287152Y629862D02*
X1287156Y629961D01*
G01X1287146Y629790D02*
X1287152Y629862D01*
G01X1287148Y629764D02*
X1287146Y629790D01*
G01X1286202Y628384D02*
Y628386D01*
G01X1286201Y628378D02*
X1286202Y628384D01*
G01X1286201Y628370D02*
Y628378D01*
G01X1286202Y623384D02*
Y623386D01*
G01X1286201Y623378D02*
X1286202Y623384D01*
G01X1286201Y623370D02*
Y623378D01*
G01X1286202Y618384D02*
Y618386D01*
G01X1286201Y618378D02*
X1286202Y618384D01*
G01X1286201Y618370D02*
Y618378D01*
G01X1286202Y613384D02*
Y613386D01*
G01X1286201Y613378D02*
X1286202Y613384D01*
G01X1286201Y613370D02*
Y613378D01*
G01X1286202Y608384D02*
Y608386D01*
G01X1286201Y608378D02*
X1286202Y608384D01*
G01X1286201Y608370D02*
Y608378D01*
G01X1286202Y603384D02*
Y603386D01*
G01X1286201Y603378D02*
X1286202Y603384D01*
G01X1286201Y603370D02*
Y603378D01*
G01X1286202Y598384D02*
Y598386D01*
G01X1286201Y598378D02*
X1286202Y598384D01*
G01X1286201Y598370D02*
Y598378D01*
G01X1286202Y593384D02*
Y593386D01*
G01X1286201Y593378D02*
X1286202Y593384D01*
G01X1286201Y593370D02*
Y593378D01*
G01X1286202Y588384D02*
Y588386D01*
G01X1286201Y588378D02*
X1286202Y588384D01*
G01X1286201Y588370D02*
Y588378D01*
G01X1286202Y583384D02*
Y583386D01*
G01X1286201Y583378D02*
X1286202Y583384D01*
G01X1286201Y583370D02*
Y583378D01*
G01X1286202Y578384D02*
Y578386D01*
G01X1286201Y578378D02*
X1286202Y578384D01*
G01X1286201Y578370D02*
Y578378D01*
G01X1286202Y573384D02*
Y573386D01*
G01X1286201Y573378D02*
X1286202Y573384D01*
G01X1286201Y573370D02*
Y573378D01*
G01X1287185Y628378D02*
Y628369D01*
G01X1287186Y628384D02*
X1287185Y628378D01*
G01X1287188Y628386D02*
X1287186Y628384D01*
G01X1287185Y623378D02*
Y623369D01*
G01X1287186Y623384D02*
X1287185Y623378D01*
G01X1287188Y623386D02*
X1287186Y623384D01*
G01X1287168Y574759D02*
X1287148Y574764D01*
G01X1287182Y574744D02*
X1287168Y574759D01*
G01X1287187Y574724D02*
X1287182Y574744D01*
G01X1287168Y579759D02*
X1287148Y579764D01*
G01X1287182Y579744D02*
X1287168Y579759D01*
G01X1287187Y579724D02*
X1287182Y579744D01*
G01X1287168Y584759D02*
X1287148Y584764D01*
G01X1287182Y584744D02*
X1287168Y584759D01*
G01X1287187Y584724D02*
X1287182Y584744D01*
G01X1287168Y589759D02*
X1287148Y589764D01*
G01X1287182Y589744D02*
X1287168Y589759D01*
G01X1287187Y589724D02*
X1287182Y589744D01*
G01X1287168Y594759D02*
X1287148Y594764D01*
G01X1287182Y594744D02*
X1287168Y594759D01*
G01X1287187Y594724D02*
X1287182Y594744D01*
G01X1287168Y599759D02*
X1287148Y599764D01*
G01X1287182Y599744D02*
X1287168Y599759D01*
G01X1287187Y599724D02*
X1287182Y599744D01*
G01X1287168Y604759D02*
X1287148Y604764D01*
G01X1287182Y604744D02*
X1287168Y604759D01*
G01X1287187Y604724D02*
X1287182Y604744D01*
G01X1287168Y609759D02*
X1287148Y609764D01*
G01X1287182Y609744D02*
X1287168Y609759D01*
G01X1287187Y609724D02*
X1287182Y609744D01*
G01X1287168Y614759D02*
X1287148Y614764D01*
G01X1287182Y614744D02*
X1287168Y614759D01*
G01X1287187Y614724D02*
X1287182Y614744D01*
G01X1287168Y619759D02*
X1287148Y619764D01*
G01X1287182Y619744D02*
X1287168Y619759D01*
G01X1287187Y619724D02*
X1287182Y619744D01*
G01X1287168Y624759D02*
X1287148Y624764D01*
G01X1287182Y624744D02*
X1287168Y624759D01*
G01X1287187Y624724D02*
X1287182Y624744D01*
G01X1287168Y629759D02*
X1287148Y629764D01*
G01X1287182Y629744D02*
X1287168Y629759D01*
G01X1287187Y629724D02*
X1287182Y629744D01*
G01X1287185Y618378D02*
Y618369D01*
G01X1287186Y618384D02*
X1287185Y618378D01*
G01X1287188Y618386D02*
X1287186Y618384D01*
G01X1287185Y613378D02*
Y613369D01*
G01X1287186Y613384D02*
X1287185Y613378D01*
G01X1287188Y613386D02*
X1287186Y613384D01*
G01X1287185Y608378D02*
Y608369D01*
G01X1287186Y608384D02*
X1287185Y608378D01*
G01X1287188Y608386D02*
X1287186Y608384D01*
G01X1287185Y603378D02*
Y603369D01*
G01X1287186Y603384D02*
X1287185Y603378D01*
G01X1287188Y603386D02*
X1287186Y603384D01*
G01X1287185Y598378D02*
Y598369D01*
G01X1287186Y598384D02*
X1287185Y598378D01*
G01X1287188Y598386D02*
X1287186Y598384D01*
G01X1287185Y593378D02*
Y593369D01*
G01X1287186Y593384D02*
X1287185Y593378D01*
G01X1287188Y593386D02*
X1287186Y593384D01*
G01X1287185Y588378D02*
Y588369D01*
G01X1287186Y588384D02*
X1287185Y588378D01*
G01X1287188Y588386D02*
X1287186Y588384D01*
G01X1287185Y583378D02*
Y583369D01*
G01X1287186Y583384D02*
X1287185Y583378D01*
G01X1287188Y583386D02*
X1287186Y583384D01*
G01X1287185Y578378D02*
Y578369D01*
G01X1287186Y578384D02*
X1287185Y578378D01*
G01X1287188Y578386D02*
X1287186Y578384D01*
G01X1287185Y573378D02*
Y573369D01*
G01X1287186Y573384D02*
X1287185Y573378D01*
G01X1287188Y573386D02*
X1287186Y573384D01*
G01X1285630Y655256D02*
G03X1285039Y655846I-590J0D01*
G01X1278346D02*
G03X1277756Y655256I0J-590D01*
G01X1280512Y654075D02*
G03Y652106I0J-985D01*
G01X1282874D02*
G03Y654075I0J984D01*
G01X1279134Y646161D02*
G03X1277953Y644980I0J-1181D01*
G01X1285433D02*
G03X1284252Y646161I-1181J0D01*
G01X1283583Y640886D02*
G03I-1890J0D01*
G01X1292520Y654665D02*
G03X1290551Y656634I-1969J0D01*
G01X1272835D02*
G03X1270866Y654665I0J-1969D01*
G01X1284055Y640886D02*
G03I-2362J0D01*
G01X1292520Y638917D02*
X1289173Y635571D01*
G01X1282677Y632894D02*
X1283858Y634075D01*
G01X1279208Y637815D02*
X1280512Y639783D01*
G01X1285184Y645706D02*
X1282874Y641476D01*
G01X1287185Y574738D02*
Y574746D01*
G01Y579738D02*
Y579746D01*
G01Y584738D02*
Y584746D01*
G01Y589738D02*
Y589746D01*
G01Y594738D02*
Y594746D01*
G01Y599738D02*
Y599746D01*
G01Y604738D02*
Y604746D01*
G01Y609738D02*
Y609746D01*
G01Y614738D02*
Y614746D01*
G01Y619738D02*
Y619746D01*
G01Y624738D02*
Y624746D01*
G01Y629738D02*
Y629746D01*
G01X1292520Y638917D02*
Y654665D01*
G01X1291535Y628386D02*
Y629764D01*
G01Y623386D02*
Y624764D01*
G01Y618386D02*
Y619764D01*
G01Y613386D02*
Y614764D01*
G01Y608386D02*
Y609764D01*
G01Y603386D02*
Y604764D01*
G01Y598386D02*
Y599764D01*
G01Y593386D02*
Y594764D01*
G01Y588386D02*
Y589764D01*
G01Y583386D02*
Y584764D01*
G01Y578386D02*
Y579764D01*
G01Y573386D02*
Y574764D01*
G01X1288366D02*
Y573386D01*
G01Y579764D02*
Y578386D01*
G01Y584764D02*
Y583386D01*
G01Y589764D02*
Y588386D01*
G01Y594764D02*
Y593386D01*
G01Y599764D02*
Y598386D01*
G01Y604764D02*
Y603386D01*
G01Y609764D02*
Y608386D01*
G01Y614764D02*
Y613386D01*
G01Y619764D02*
Y618386D01*
G01Y624764D02*
Y623386D01*
G01Y629764D02*
Y628386D01*
G01X1287185Y627894D02*
Y630256D01*
G01Y622894D02*
Y625256D01*
G01Y617894D02*
Y620256D01*
G01Y612894D02*
Y615256D01*
G01Y607894D02*
Y610256D01*
G01Y602894D02*
Y605256D01*
G01Y597894D02*
Y600256D01*
G01Y592894D02*
Y595256D01*
G01Y587894D02*
Y590256D01*
G01Y582894D02*
Y585256D01*
G01Y577894D02*
Y580256D01*
G01Y572894D02*
Y575256D01*
G01X1286201D02*
Y572894D01*
G01Y580256D02*
Y577894D01*
G01Y585256D02*
Y582894D01*
G01Y590256D02*
Y587894D01*
G01Y595256D02*
Y592894D01*
G01Y600256D02*
Y597894D01*
G01Y605256D02*
Y602894D01*
G01Y610256D02*
Y607894D01*
G01Y615256D02*
Y612894D01*
G01Y620256D02*
Y617894D01*
G01Y625256D02*
Y622894D01*
G01Y630256D02*
Y627894D01*
G01X1285630Y649154D02*
Y655256D01*
G01X1285433Y644980D02*
Y636437D01*
G01X1282874Y641476D02*
Y639783D01*
G01X1280512D02*
Y641476D01*
G01X1277953Y636437D02*
Y644980D01*
G01X1277756Y649154D02*
Y655256D01*
G01X1270866Y654665D02*
Y638917D01*
G01X1280512Y641476D02*
X1278202Y645706D01*
G01X1282874Y639783D02*
X1284178Y637815D01*
G01X1275984Y634075D02*
X1277165Y632894D01*
G01X1270866Y638917D02*
X1274213Y635571D01*
G01X1290551Y656634D02*
X1272835D01*
G01X1285039Y655846D02*
X1278346D01*
G01X1282874Y654075D02*
X1280512D01*
G01Y652106D02*
X1282874D01*
G01X1285630Y650728D02*
X1277756D01*
G01Y649154D02*
X1285630D01*
G01X1292520Y646201D02*
X1270866D01*
G01X1279134Y646161D02*
X1284252D01*
G01X1280512Y641476D02*
X1282874D01*
G01X1280512Y639783D02*
X1282874D01*
G01X1274213Y637815D02*
X1288583D01*
G01X1274213Y636437D02*
X1277953D01*
G01X1288583D02*
X1285433D01*
G01X1274213Y635571D02*
X1289173D01*
G01X1275984Y634075D02*
X1283858D01*
G01X1277165Y632894D02*
X1282677D01*
G01X1287185Y630256D02*
X1286201D01*
G01X1286202Y629764D02*
X1291535D01*
G01Y629724D02*
X1287187D01*
G01X1291535Y628386D02*
X1286202D01*
G01X1286201Y627894D02*
X1287185D01*
G01Y625256D02*
X1286201D01*
G01X1286202Y624764D02*
X1291535D01*
G01Y624724D02*
X1287187D01*
G01X1291535Y623386D02*
X1286202D01*
G01X1286201Y622894D02*
X1287185D01*
G01Y620256D02*
X1286201D01*
G01X1286202Y619764D02*
X1291535D01*
G01Y619724D02*
X1287187D01*
G01X1291535Y618386D02*
X1286202D01*
G01X1286201Y617894D02*
X1287185D01*
G01Y615256D02*
X1286201D01*
G01X1286202Y614764D02*
X1291535D01*
G01Y614724D02*
X1287187D01*
G01X1291535Y613386D02*
X1286202D01*
G01X1286201Y612894D02*
X1287185D01*
G01Y610256D02*
X1286201D01*
G01Y629959D02*
X1287156Y629961D01*
G01X1287185Y628190D02*
X1286201Y628189D01*
G01Y624959D02*
X1287156Y624961D01*
G01X1287185Y623190D02*
X1286201Y623189D01*
G01Y619959D02*
X1287156Y619961D01*
G01X1287185Y618190D02*
X1286201Y618189D01*
G01Y614959D02*
X1287156Y614961D01*
G01X1287185Y613190D02*
X1286201Y613189D01*
G01X1286202Y609764D02*
X1291535D01*
G01Y609724D02*
X1287187D01*
G01X1291535Y608386D02*
X1286202D01*
G01X1286201Y607894D02*
X1287185D01*
G01Y605256D02*
X1286201D01*
G01X1286202Y604764D02*
X1291535D01*
G01Y604724D02*
X1287187D01*
G01X1291535Y603386D02*
X1286202D01*
G01X1286201Y602894D02*
X1287185D01*
G01Y600256D02*
X1286201D01*
G01X1286202Y599764D02*
X1291535D01*
G01Y599724D02*
X1287187D01*
G01X1291535Y598386D02*
X1286202D01*
G01X1286201Y597894D02*
X1287185D01*
G01Y595256D02*
X1286201D01*
G01X1286202Y594764D02*
X1291535D01*
G01Y594724D02*
X1287187D01*
G01X1291535Y593386D02*
X1286202D01*
G01X1286201Y592894D02*
X1287185D01*
G01Y590256D02*
X1286201D01*
G01X1286202Y589764D02*
X1291535D01*
G01Y589724D02*
X1287187D01*
G01X1291535Y588386D02*
X1286202D01*
G01X1286201Y587894D02*
X1287185D01*
G01Y585256D02*
X1286201D01*
G01X1286202Y584764D02*
X1291535D01*
G01Y584724D02*
X1287187D01*
G01X1291535Y583386D02*
X1286202D01*
G01X1286201Y582894D02*
X1287185D01*
G01Y580256D02*
X1286201D01*
G01X1286202Y579764D02*
X1291535D01*
G01Y579724D02*
X1287187D01*
G01X1291535Y578386D02*
X1286202D01*
G01X1286201Y577894D02*
X1287185D01*
G01Y575256D02*
X1286201D01*
G01X1286202Y574764D02*
X1291535D01*
G01Y574724D02*
X1287187D01*
G01X1291535Y573386D02*
X1286202D01*
G01X1286201Y572894D02*
X1287185D01*
G01X1286201Y609959D02*
X1287156Y609961D01*
G01X1287185Y608190D02*
X1286201Y608189D01*
G01Y604959D02*
X1287156Y604961D01*
G01X1287185Y603190D02*
X1286201Y603189D01*
G01Y599959D02*
X1287156Y599961D01*
G01X1287185Y598190D02*
X1286201Y598189D01*
G01Y594959D02*
X1287156Y594961D01*
G01X1287185Y593190D02*
X1286201Y593189D01*
G01Y589959D02*
X1287156Y589961D01*
G01X1287185Y588190D02*
X1286201Y588189D01*
G01Y584959D02*
X1287156Y584961D01*
G01X1287185Y583190D02*
X1286201Y583189D01*
G01Y579959D02*
X1287156Y579961D01*
G01X1287185Y578190D02*
X1286201Y578189D01*
G01Y574959D02*
X1287156Y574961D01*
G01X1287185Y573190D02*
X1286201Y573189D01*
G01X1284965Y717468D02*
G03X1318775I16905J-13531D01*
G01X1311851Y730599D02*
G03X1318775Y717468I37663J11469D01*
G01X1311851Y730599D02*
G03X1291890I-9980J-3040D01*
G01X1284965Y717468D02*
G03X1291891Y730599I-30736J24604D01*
G01X1311850D02*
G03X1318776Y717468I37661J11473D01*
G01X1311850Y730599D02*
G03X1291890I-9980J-3040D01*
G01X1284965Y717468D02*
G03X1318776I16906J-13531D01*
G01X1284965D02*
G03X1291890Y730599I-30737J24602D01*
G01X1282795Y945020D02*
G03I-1102J0D01*
G01X1284252Y939744D02*
G03X1285433Y940925I0J1181D01*
G01X1277953D02*
G03X1279134Y939744I1181J0D01*
G01X1283268Y945020D02*
G03I-1575J0D01*
G01X1277756Y930650D02*
G03X1278346Y930059I591J0D01*
G01X1285039D02*
G03X1285630Y930650I0J591D01*
G01X1282874Y931831D02*
G03Y933799I0J984D01*
G01X1280512D02*
G03Y931831I0J-984D01*
G01X1270866Y931240D02*
G03X1272835Y929272I1968J0D01*
G01X1290551D02*
G03X1292520Y931240I1J1968D01*
G01X1282874Y944429D02*
X1285184Y940200D01*
G01X1280512Y946122D02*
X1279208Y948091D01*
G01X1289173Y950335D02*
X1292520Y946988D01*
G01X1282677Y953012D02*
X1283858Y951831D01*
G01X1292520Y931240D02*
Y946988D01*
G01X1289173Y1088327D02*
Y950335D01*
G01X1288583Y1090571D02*
Y948091D01*
G01X1285630Y936752D02*
Y930650D01*
G01X1285433Y949469D02*
Y940925D01*
G01X1283858Y988287D02*
Y951831D01*
G01X1282874Y946122D02*
Y944429D01*
G01X1280512D02*
Y946122D01*
G01X1277953Y940925D02*
Y949469D01*
G01X1277756Y936752D02*
Y930650D01*
G01X1275984Y951831D02*
Y1086831D01*
G01X1274213Y987126D02*
Y948091D01*
G01X1270866Y946988D02*
Y931240D01*
G01X1283858Y951831D02*
X1275984D01*
G01X1289173Y950335D02*
X1274213D01*
G01X1285433Y949469D02*
X1288583D01*
G01X1277953D02*
X1274213D01*
G01Y948091D02*
X1288583D01*
G01X1282874Y946122D02*
X1280512D01*
G01X1282874Y944429D02*
X1280512D01*
G01X1284252Y939744D02*
X1279134D01*
G01X1292520Y939705D02*
X1270866D01*
G01X1278202Y940200D02*
X1280512Y944429D01*
G01X1285630Y936752D02*
X1277756D01*
G01Y935177D02*
X1285630D01*
G01X1282874Y933799D02*
X1280512D01*
G01Y931831D02*
X1282874D01*
G01X1285039Y930059D02*
X1278346D01*
G01X1290551Y929272D02*
X1272835D01*
G01X1284178Y948091D02*
X1282874Y946122D01*
G01X1277165Y953012D02*
X1275984Y951831D01*
G01X1274213Y950335D02*
X1270866Y946988D01*
G01X1273731Y1008191D02*
X1273719Y1008189D01*
G01X1273741Y1008196D02*
X1273731Y1008191D01*
G01Y1005041D02*
X1273719Y1005039D01*
G01X1273741Y1005046D02*
X1273731Y1005041D01*
G01Y1001892D02*
X1273719Y1001890D01*
G01X1273741Y1001896D02*
X1273731Y1001892D01*
G01Y998742D02*
X1273719Y998740D01*
G01X1273741Y998747D02*
X1273731Y998742D01*
G01Y995593D02*
X1273719Y995591D01*
G01X1273741Y995597D02*
X1273731Y995593D01*
G01X1273757Y1008202D02*
X1273760Y1008215D01*
G01X1273751Y1008191D02*
X1273757Y1008202D01*
G01X1273741Y1008183D02*
X1273751Y1008191D01*
G01X1273757Y1001903D02*
X1273760Y1001915D01*
G01X1273751Y1001892D02*
X1273757Y1001903D01*
G01X1273741Y1001884D02*
X1273751Y1001892D01*
G01X1273757Y998754D02*
X1273760Y998766D01*
G01X1273751Y998742D02*
X1273757Y998754D01*
G01X1273741Y998734D02*
X1273751Y998742D01*
G01X1272814Y1009375D02*
Y1009381D01*
G01Y1009371D02*
Y1009375D01*
G01X1272813Y1009370D02*
X1272814Y1009371D01*
G01Y1006225D02*
Y1006231D01*
G01Y1006222D02*
Y1006225D01*
G01X1272813Y1006220D02*
X1272814Y1006222D01*
G01Y1003076D02*
Y1003082D01*
G01Y1003072D02*
Y1003076D01*
G01X1272813Y1003071D02*
X1272814Y1003072D01*
G01Y999926D02*
Y999932D01*
G01Y999922D02*
Y999926D01*
G01X1272813Y999921D02*
X1272814Y999922D01*
G01Y996776D02*
Y996783D01*
G01Y996773D02*
Y996776D01*
G01X1272813Y996772D02*
X1272814Y996773D01*
G01Y993627D02*
Y993633D01*
G01Y993623D02*
Y993627D01*
G01X1272813Y993622D02*
X1272814Y993623D01*
G01Y990477D02*
Y990483D01*
G01Y990474D02*
Y990477D01*
G01X1272813Y990472D02*
X1272814Y990474D01*
G01X1272776Y1009350D02*
Y1009344D01*
G01X1272778Y1009357D02*
X1272776Y1009350D01*
G01X1272781Y1009363D02*
X1272778Y1009357D01*
G01X1272785Y1009368D02*
X1272781Y1009363D01*
G01X1272789Y1009372D02*
X1272785Y1009368D01*
G01X1272795Y1009376D02*
X1272789Y1009372D01*
G01X1272776Y1006201D02*
Y1006194D01*
G01X1272778Y1006207D02*
X1272776Y1006201D01*
G01X1272781Y1006213D02*
X1272778Y1006207D01*
G01X1272785Y1006218D02*
X1272781Y1006213D01*
G01X1272789Y1006223D02*
X1272785Y1006218D01*
G01X1272795Y1006226D02*
X1272789Y1006223D01*
G01X1272776Y1003051D02*
Y1003045D01*
G01X1272778Y1003057D02*
X1272776Y1003051D01*
G01X1272781Y1003063D02*
X1272778Y1003057D01*
G01X1272785Y1003069D02*
X1272781Y1003063D01*
G01X1272789Y1003073D02*
X1272785Y1003069D01*
G01X1272795Y1003077D02*
X1272789Y1003073D01*
G01X1272776Y999902D02*
Y999895D01*
G01X1272778Y999908D02*
X1272776Y999902D01*
G01X1272781Y999914D02*
X1272778Y999908D01*
G01X1272785Y999919D02*
X1272781Y999914D01*
G01X1272789Y999924D02*
X1272785Y999919D01*
G01X1272795Y999927D02*
X1272789Y999924D01*
G01X1272776Y996752D02*
Y996746D01*
G01X1272778Y996758D02*
X1272776Y996752D01*
G01X1272781Y996764D02*
X1272778Y996758D01*
G01X1272785Y996769D02*
X1272781Y996764D01*
G01X1272789Y996774D02*
X1272785Y996769D01*
G01X1272795Y996778D02*
X1272789Y996774D01*
G01X1272776Y993602D02*
Y993596D01*
G01X1272778Y993609D02*
X1272776Y993602D01*
G01X1272781Y993615D02*
X1272778Y993609D01*
G01X1272785Y993620D02*
X1272781Y993615D01*
G01X1272789Y993624D02*
X1272785Y993620D01*
G01X1272795Y993628D02*
X1272789Y993624D01*
G01X1272776Y990453D02*
Y990446D01*
G01X1272778Y990459D02*
X1272776Y990453D01*
G01X1272781Y990465D02*
X1272778Y990459D01*
G01X1272785Y990470D02*
X1272781Y990465D01*
G01X1272789Y990475D02*
X1272785Y990470D01*
G01X1272795Y990478D02*
X1272789Y990475D01*
G01X1273731Y992443D02*
X1273719Y992441D01*
G01X1273741Y992448D02*
X1273731Y992443D01*
G01Y989293D02*
X1273719Y989291D01*
G01X1273741Y989298D02*
X1273731Y989293D01*
G01X1287185Y1046134D02*
Y1046125D01*
G01X1287186Y1046140D02*
X1287185Y1046134D01*
G01X1287188Y1046142D02*
X1287186Y1046140D01*
G01X1287185Y1041134D02*
Y1041125D01*
G01X1287186Y1041140D02*
X1287185Y1041134D01*
G01X1287188Y1041142D02*
X1287186Y1041140D01*
G01X1287185Y1036134D02*
Y1036125D01*
G01X1287186Y1036140D02*
X1287185Y1036134D01*
G01X1287188Y1036142D02*
X1287186Y1036140D01*
G01X1287185Y1031134D02*
Y1031125D01*
G01X1287186Y1031140D02*
X1287185Y1031134D01*
G01X1287188Y1031142D02*
X1287186Y1031140D01*
G01X1287185Y1026134D02*
Y1026125D01*
G01X1287186Y1026140D02*
X1287185Y1026134D01*
G01X1287188Y1026142D02*
X1287186Y1026140D01*
G01X1287185Y1021134D02*
Y1021125D01*
G01X1287186Y1021140D02*
X1287185Y1021134D01*
G01X1287188Y1021142D02*
X1287186Y1021140D01*
G01X1287185Y1016134D02*
Y1016125D01*
G01X1287186Y1016140D02*
X1287185Y1016134D01*
G01X1287188Y1016142D02*
X1287186Y1016140D01*
G01X1272775Y1009337D02*
X1272776Y1009344D01*
G01X1272774Y1009332D02*
X1272775Y1009337D01*
G01X1272773Y1009331D02*
X1272774Y1009332D01*
G01X1272775Y1006187D02*
X1272776Y1006194D01*
G01X1272774Y1006183D02*
X1272775Y1006187D01*
G01X1272773Y1006181D02*
X1272774Y1006183D01*
G01X1272775Y1003037D02*
X1272776Y1003045D01*
G01X1272774Y1003033D02*
X1272775Y1003037D01*
G01X1272773Y1003031D02*
X1272774Y1003033D01*
G01X1272775Y999888D02*
X1272776Y999895D01*
G01X1272774Y999883D02*
X1272775Y999888D01*
G01X1272773Y999882D02*
X1272774Y999883D01*
G01X1272775Y996738D02*
X1272776Y996746D01*
G01X1272774Y996734D02*
X1272775Y996738D01*
G01X1272773Y996732D02*
X1272774Y996734D01*
G01X1272775Y993589D02*
X1272776Y993596D01*
G01X1272774Y993584D02*
X1272775Y993589D01*
G01X1272773Y993583D02*
X1272774Y993584D01*
G01X1272775Y990439D02*
X1272776Y990446D01*
G01X1272774Y990435D02*
X1272775Y990439D01*
G01X1272773Y990433D02*
X1272774Y990435D01*
G01X1273757Y995604D02*
X1273760Y995616D01*
G01X1273751Y995593D02*
X1273757Y995604D01*
G01X1273741Y995585D02*
X1273751Y995593D01*
G01X1273757Y992454D02*
X1273760Y992467D01*
G01X1273751Y992443D02*
X1273757Y992454D01*
G01X1273741Y992435D02*
X1273751Y992443D01*
G01X1273757Y989305D02*
X1273760Y989317D01*
G01X1273751Y989293D02*
X1273757Y989305D01*
G01X1273741Y989285D02*
X1273751Y989293D01*
G01X1272775Y992474D02*
X1272776Y992467D01*
G01X1272774Y992479D02*
X1272775Y992474D01*
G01X1272773Y992477D02*
X1272774Y992479D01*
G01X1273720Y1009375D02*
Y1009381D01*
G01Y1009371D02*
Y1009375D01*
G01X1273719Y1009370D02*
X1273720Y1009371D01*
G01Y1006226D02*
Y1006231D01*
G01Y1006222D02*
Y1006226D01*
G01X1273719Y1006220D02*
X1273720Y1006222D01*
G01Y1003076D02*
Y1003082D01*
G01Y1003072D02*
Y1003076D01*
G01X1273719Y1003071D02*
X1273720Y1003072D01*
G01Y999926D02*
Y999932D01*
G01Y999922D02*
Y999926D01*
G01X1273719Y999921D02*
X1273720Y999922D01*
G01Y996777D02*
Y996783D01*
G01Y996773D02*
Y996777D01*
G01X1273719Y996772D02*
X1273720Y996773D01*
G01Y993627D02*
Y993633D01*
G01Y993623D02*
Y993627D01*
G01X1273719Y993622D02*
X1273720Y993623D01*
G01Y990478D02*
Y990483D01*
G01Y990474D02*
Y990478D01*
G01X1273719Y990472D02*
X1273720Y990474D01*
G01X1287185Y1011134D02*
Y1011125D01*
G01X1287186Y1011140D02*
X1287185Y1011134D01*
G01X1287188Y1011142D02*
X1287186Y1011140D01*
G01X1287185Y986134D02*
Y986125D01*
G01X1287186Y986140D02*
X1287185Y986134D01*
G01X1287188Y986142D02*
X1287186Y986140D01*
G01X1287185Y981134D02*
Y981125D01*
G01X1287186Y981140D02*
X1287185Y981134D01*
G01X1287188Y981142D02*
X1287186Y981140D01*
G01X1287185Y976134D02*
Y976125D01*
G01X1287186Y976140D02*
X1287185Y976134D01*
G01X1287188Y976142D02*
X1287186Y976140D01*
G01X1287185Y971134D02*
Y971125D01*
G01X1287186Y971140D02*
X1287185Y971134D01*
G01X1287188Y971142D02*
X1287186Y971140D01*
G01X1287185Y966134D02*
Y966125D01*
G01X1287186Y966140D02*
X1287185Y966134D01*
G01X1287188Y966142D02*
X1287186Y966140D01*
G01X1287185Y961134D02*
Y961125D01*
G01X1287186Y961140D02*
X1287185Y961134D01*
G01X1287188Y961142D02*
X1287186Y961140D01*
G01X1287185Y956134D02*
Y956125D01*
G01X1287186Y956140D02*
X1287185Y956134D01*
G01X1287188Y956142D02*
X1287186Y956140D01*
G01X1272778Y990453D02*
X1272773Y990433D01*
G01X1272793Y990467D02*
X1272778Y990453D01*
G01X1272813Y990472D02*
X1272793Y990467D01*
G01X1272778Y993602D02*
X1272773Y993583D01*
G01X1272793Y993617D02*
X1272778Y993602D01*
G01X1272813Y993622D02*
X1272793Y993617D01*
G01X1272778Y996752D02*
X1272773Y996732D01*
G01X1272793Y996766D02*
X1272778Y996752D01*
G01X1272813Y996772D02*
X1272793Y996766D01*
G01X1272778Y999902D02*
X1272773Y999882D01*
G01X1272793Y999916D02*
X1272778Y999902D01*
G01X1272813Y999921D02*
X1272793Y999916D01*
G01X1272778Y1003051D02*
X1272773Y1003031D01*
G01X1272793Y1003065D02*
X1272778Y1003051D01*
G01X1272813Y1003071D02*
X1272793Y1003065D01*
G01X1272778Y1006201D02*
X1272773Y1006181D01*
G01X1272793Y1006215D02*
X1272778Y1006201D01*
G01X1272813Y1006220D02*
X1272793Y1006215D01*
G01X1272778Y1009350D02*
X1272773Y1009331D01*
G01X1272793Y1009365D02*
X1272778Y1009350D01*
G01X1272813Y1009370D02*
X1272793Y1009365D01*
G01X1273753Y989311D02*
X1273758Y989331D01*
G01X1273739Y989296D02*
X1273753Y989311D01*
G01X1273719Y989291D02*
X1273739Y989296D01*
G01X1273753Y992461D02*
X1273758Y992480D01*
G01X1273739Y992446D02*
X1273753Y992461D01*
G01X1273719Y992441D02*
X1273739Y992446D01*
G01X1273753Y995610D02*
X1273758Y995630D01*
G01X1273739Y995596D02*
X1273753Y995610D01*
G01X1273719Y995591D02*
X1273739Y995596D01*
G01X1273753Y998760D02*
X1273758Y998780D01*
G01X1273739Y998745D02*
X1273753Y998760D01*
G01X1273719Y998740D02*
X1273739Y998745D01*
G01X1273753Y1001909D02*
X1273758Y1001929D01*
G01X1273739Y1001895D02*
X1273753Y1001909D01*
G01X1273719Y1001890D02*
X1273739Y1001895D01*
G01X1273753Y1005059D02*
X1273758Y1005079D01*
G01X1273739Y1005044D02*
X1273753Y1005059D01*
G01X1273719Y1005039D02*
X1273739Y1005044D01*
G01X1273753Y1008209D02*
X1273758Y1008228D01*
G01X1273739Y1008194D02*
X1273753Y1008209D01*
G01X1273719Y1008189D02*
X1273739Y1008194D01*
G01X1272789Y1009361D02*
X1272813Y1009370D01*
G01X1272778Y1009347D02*
X1272789Y1009361D01*
G01X1272776Y1009340D02*
X1272778Y1009347D01*
G01X1272789Y1006212D02*
X1272813Y1006220D01*
G01X1272778Y1006197D02*
X1272789Y1006212D01*
G01X1272776Y1006191D02*
X1272778Y1006197D01*
G01X1272789Y1003062D02*
X1272813Y1003071D01*
G01X1272778Y1003048D02*
X1272789Y1003062D01*
G01X1272776Y1003041D02*
X1272778Y1003048D01*
G01X1272789Y999913D02*
X1272813Y999921D01*
G01X1272778Y999898D02*
X1272789Y999913D01*
G01X1272776Y999891D02*
X1272778Y999898D01*
G01X1272789Y996763D02*
X1272813Y996772D01*
G01X1272778Y996748D02*
X1272789Y996763D01*
G01X1272776Y996742D02*
X1272778Y996748D01*
G01X1272789Y993613D02*
X1272813Y993622D01*
G01X1272778Y993599D02*
X1272789Y993613D01*
G01X1272776Y993592D02*
X1272778Y993599D01*
G01X1272789Y990464D02*
X1272813Y990472D01*
G01X1272778Y990449D02*
X1272789Y990464D01*
G01X1272776Y990443D02*
X1272778Y990449D01*
G01X1273760Y1009337D02*
Y1009344D01*
G01X1273759Y1009332D02*
X1273760Y1009337D01*
G01X1273759Y1009331D02*
Y1009332D01*
G01X1273760Y1006187D02*
Y1006194D01*
G01X1273759Y1006183D02*
X1273760Y1006187D01*
G01X1273759Y1006181D02*
Y1006183D01*
G01X1273760Y1003038D02*
Y1003045D01*
G01X1273759Y1003033D02*
X1273760Y1003038D01*
G01X1273759Y1003031D02*
Y1003033D01*
G01X1273760Y999888D02*
Y999895D01*
G01X1273759Y999883D02*
X1273760Y999888D01*
G01X1273759Y999882D02*
Y999883D01*
G01X1273760Y996739D02*
Y996746D01*
G01X1273759Y996734D02*
X1273760Y996739D01*
G01X1273759Y996732D02*
Y996734D01*
G01X1273760Y993589D02*
Y993596D01*
G01X1273759Y993584D02*
X1273760Y993589D01*
G01X1273759Y993583D02*
Y993584D01*
G01X1273760Y990439D02*
Y990446D01*
G01X1273759Y990435D02*
X1273760Y990439D01*
G01X1273759Y990433D02*
Y990435D01*
G01X1272775Y998774D02*
X1272776Y998766D01*
G01X1272774Y998778D02*
X1272775Y998774D01*
G01X1272773Y998775D02*
X1272774Y998778D01*
G01X1273759Y1005058D02*
X1273760Y1005065D01*
G01X1273757Y1005051D02*
X1273759Y1005058D01*
G01X1273753Y1005044D02*
X1273757Y1005051D01*
G01X1273748Y1005039D02*
X1273753Y1005044D01*
G01X1273742Y1005034D02*
X1273748Y1005039D01*
G01X1273735Y1005031D02*
X1273742Y1005034D01*
G01X1273728Y1005029D02*
X1273735Y1005031D01*
G01X1273720Y1005028D02*
X1273728Y1005029D01*
G01X1273737Y989283D02*
X1273741Y989285D01*
G01X1273734Y989282D02*
X1273737Y989283D01*
G01X1273731Y989281D02*
X1273734Y989282D01*
G01X1273728Y989281D02*
X1273731D01*
G01X1273724Y989280D02*
X1273728Y989281D01*
G01X1273720Y989280D02*
X1273724D01*
G01X1272798Y990480D02*
X1272795Y990478D01*
G01X1272801Y990481D02*
X1272798Y990480D01*
G01X1272805Y990482D02*
X1272801Y990481D01*
G01X1272808Y990483D02*
X1272805Y990482D01*
G01X1272811Y990483D02*
X1272808D01*
G01X1272815D02*
X1272811D01*
G01X1273737Y992433D02*
X1273741Y992435D01*
G01X1273734Y992432D02*
X1273737Y992433D01*
G01X1273731Y992431D02*
X1273734Y992432D01*
G01X1273728Y992430D02*
X1273731Y992431D01*
G01X1273724Y992430D02*
X1273728D01*
G01X1273720D02*
X1273724D01*
G01X1272798Y993630D02*
X1272795Y993628D01*
G01X1272801Y993631D02*
X1272798Y993630D01*
G01X1272805Y993632D02*
X1272801Y993631D01*
G01X1272808Y993633D02*
X1272805Y993632D01*
G01X1272811Y993633D02*
X1272808D01*
G01X1272815D02*
X1272811D01*
G01X1273737Y995583D02*
X1273741Y995585D01*
G01X1273734Y995581D02*
X1273737Y995583D01*
G01X1273731Y995581D02*
X1273734D01*
G01X1273728Y995580D02*
X1273731Y995581D01*
G01X1273724Y995580D02*
X1273728D01*
G01X1273720Y995579D02*
X1273724Y995580D01*
G01X1272798Y996779D02*
X1272795Y996778D01*
G01X1272801Y996780D02*
X1272798Y996779D01*
G01X1272805Y996781D02*
X1272801Y996780D01*
G01X1272808Y996782D02*
X1272805Y996781D01*
G01X1272811Y996783D02*
X1272808Y996782D01*
G01X1272815Y996783D02*
X1272811D01*
G01X1273737Y998732D02*
X1273741Y998734D01*
G01X1273734Y998731D02*
X1273737Y998732D01*
G01X1273731Y998730D02*
X1273734Y998731D01*
G01X1273728Y998730D02*
X1273731D01*
G01X1273724Y998729D02*
X1273728Y998730D01*
G01X1273720Y998729D02*
X1273724D01*
G01X1272798Y999929D02*
X1272795Y999927D01*
G01X1272801Y999930D02*
X1272798Y999929D01*
G01X1272805Y999931D02*
X1272801Y999930D01*
G01X1272808Y999932D02*
X1272805Y999931D01*
G01X1272811Y999932D02*
X1272808D01*
G01X1272815D02*
X1272811D01*
G01X1273737Y1001882D02*
X1273741Y1001884D01*
G01X1273734Y1001881D02*
X1273737Y1001882D01*
G01X1273731Y1001880D02*
X1273734Y1001881D01*
G01X1273728Y1001879D02*
X1273731Y1001880D01*
G01X1273724Y1001879D02*
X1273728D01*
G01X1273720Y1001878D02*
X1273724Y1001879D01*
G01X1272798Y1003078D02*
X1272795Y1003077D01*
G01X1272801Y1003080D02*
X1272798Y1003078D01*
G01X1272805Y1003081D02*
X1272801Y1003080D01*
G01X1272808Y1003081D02*
X1272805D01*
G01X1272811Y1003082D02*
X1272808Y1003081D01*
G01X1272815Y1003082D02*
X1272811D01*
G01X1272798Y1006228D02*
X1272795Y1006226D01*
G01X1272801Y1006229D02*
X1272798Y1006228D01*
G01X1272805Y1006230D02*
X1272801Y1006229D01*
G01X1272808Y1006231D02*
X1272805Y1006230D01*
G01X1272811Y1006231D02*
X1272808D01*
G01X1272815D02*
X1272811D01*
G01X1273737Y1008181D02*
X1273741Y1008183D01*
G01X1273734Y1008180D02*
X1273737Y1008181D01*
G01X1273731Y1008179D02*
X1273734Y1008180D01*
G01X1273728Y1008178D02*
X1273731Y1008179D01*
G01X1273724Y1008178D02*
X1273728D01*
G01X1273720D02*
X1273724D01*
G01X1272798Y1009378D02*
X1272795Y1009376D01*
G01X1272801Y1009379D02*
X1272798Y1009378D01*
G01X1272805Y1009380D02*
X1272801Y1009379D01*
G01X1272808Y1009381D02*
X1272805Y1009380D01*
G01X1272811Y1009381D02*
X1272808D01*
G01X1272815D02*
X1272811D01*
G01X1273750Y990471D02*
X1273754Y990465D01*
G01X1273746Y990475D02*
X1273750Y990471D01*
G01X1273740Y990479D02*
X1273746Y990475D01*
G01X1273734Y990481D02*
X1273740Y990479D01*
G01X1273727Y990483D02*
X1273734Y990481D01*
G01X1273720Y990483D02*
X1273727D01*
G01X1273750Y993620D02*
X1273754Y993615D01*
G01X1273746Y993625D02*
X1273750Y993620D01*
G01X1273740Y993628D02*
X1273746Y993625D01*
G01X1273734Y993631D02*
X1273740Y993628D01*
G01X1273727Y993633D02*
X1273734Y993631D01*
G01X1273720Y993633D02*
X1273727D01*
G01X1273750Y996770D02*
X1273754Y996765D01*
G01X1273746Y996774D02*
X1273750Y996770D01*
G01X1273740Y996778D02*
X1273746Y996774D01*
G01X1273734Y996781D02*
X1273740Y996778D01*
G01X1273727Y996782D02*
X1273734Y996781D01*
G01X1273720Y996783D02*
X1273727Y996782D01*
G01X1272776Y989310D02*
Y989317D01*
G01X1272779Y989303D02*
X1272776Y989310D01*
G01X1272782Y989296D02*
X1272779Y989303D01*
G01X1272787Y989291D02*
X1272782Y989296D01*
G01X1272793Y989286D02*
X1272787Y989291D01*
G01X1272800Y989283D02*
X1272793Y989286D01*
G01X1272807Y989281D02*
X1272800Y989283D01*
G01X1272815Y989280D02*
X1272807Y989281D01*
G01X1272776Y992459D02*
Y992467D01*
G01X1272779Y992452D02*
X1272776Y992459D01*
G01X1272782Y992446D02*
X1272779Y992452D01*
G01X1272787Y992441D02*
X1272782Y992446D01*
G01X1272793Y992436D02*
X1272787Y992441D01*
G01X1272800Y992432D02*
X1272793Y992436D01*
G01X1272807Y992430D02*
X1272800Y992432D01*
G01X1272815Y992430D02*
X1272807D01*
G01X1287152Y957618D02*
X1287156Y957717D01*
G01X1287146Y957546D02*
X1287152Y957618D01*
G01X1287148Y957520D02*
X1287146Y957546D01*
G01X1287152Y962618D02*
X1287156Y962717D01*
G01X1287146Y962546D02*
X1287152Y962618D01*
G01X1287148Y962520D02*
X1287146Y962546D01*
G01X1287152Y967618D02*
X1287156Y967717D01*
G01X1287146Y967546D02*
X1287152Y967618D01*
G01X1287148Y967520D02*
X1287146Y967546D01*
G01X1287152Y972618D02*
X1287156Y972717D01*
G01X1287146Y972546D02*
X1287152Y972618D01*
G01X1287148Y972520D02*
X1287146Y972546D01*
G01X1287152Y977618D02*
X1287156Y977717D01*
G01X1287146Y977546D02*
X1287152Y977618D01*
G01X1287148Y977520D02*
X1287146Y977546D01*
G01X1287152Y982618D02*
X1287156Y982717D01*
G01X1287146Y982546D02*
X1287152Y982618D01*
G01X1287148Y982520D02*
X1287146Y982546D01*
G01X1287152Y987618D02*
X1287156Y987717D01*
G01X1287146Y987546D02*
X1287152Y987618D01*
G01X1287148Y987520D02*
X1287146Y987546D01*
G01X1287152Y1012618D02*
X1287156Y1012717D01*
G01X1287146Y1012546D02*
X1287152Y1012618D01*
G01X1287148Y1012520D02*
X1287146Y1012546D01*
G01X1287152Y1017618D02*
X1287156Y1017717D01*
G01X1287146Y1017546D02*
X1287152Y1017618D01*
G01X1287148Y1017520D02*
X1287146Y1017546D01*
G01X1287152Y1022618D02*
X1287156Y1022717D01*
G01X1287146Y1022546D02*
X1287152Y1022618D01*
G01X1287148Y1022520D02*
X1287146Y1022546D01*
G01X1287152Y1027618D02*
X1287156Y1027717D01*
G01X1287146Y1027546D02*
X1287152Y1027618D01*
G01X1287148Y1027520D02*
X1287146Y1027546D01*
G01X1287152Y1032618D02*
X1287156Y1032717D01*
G01X1287146Y1032546D02*
X1287152Y1032618D01*
G01X1287148Y1032520D02*
X1287146Y1032546D01*
G01X1287152Y1037618D02*
X1287156Y1037717D01*
G01X1287146Y1037546D02*
X1287152Y1037618D01*
G01X1287148Y1037520D02*
X1287146Y1037546D01*
G01X1287152Y1042618D02*
X1287156Y1042717D01*
G01X1287146Y1042546D02*
X1287152Y1042618D01*
G01X1287148Y1042520D02*
X1287146Y1042546D01*
G01X1272775Y1001923D02*
X1272776Y1001916D01*
G01X1272774Y1001928D02*
X1272775Y1001923D01*
G01Y1001918D02*
X1272774Y1001928D01*
G01X1272816Y1009554D02*
X1272815Y1009567D01*
G01X1272813Y1009541D02*
X1272816Y1009554D01*
G01X1272813Y1009528D02*
Y1009541D01*
G01X1272816Y1006405D02*
X1272815Y1006417D01*
G01X1272813Y1006392D02*
X1272816Y1006405D01*
G01X1272813Y1006378D02*
Y1006392D01*
G01X1272816Y1003255D02*
X1272815Y1003268D01*
G01X1272813Y1003242D02*
X1272816Y1003255D01*
G01X1272813Y1003228D02*
Y1003242D01*
G01X1272816Y1000106D02*
X1272815Y1000118D01*
G01X1272813Y1000093D02*
X1272816Y1000106D01*
G01X1272813Y1000079D02*
Y1000093D01*
G01X1272816Y996956D02*
X1272815Y996969D01*
G01X1272813Y996943D02*
X1272816Y996956D01*
G01X1272813Y996929D02*
Y996943D01*
G01X1272816Y993806D02*
X1272815Y993819D01*
G01X1272813Y993793D02*
X1272816Y993806D01*
G01X1272813Y993780D02*
Y993793D01*
G01X1272816Y990657D02*
X1272815Y990669D01*
G01X1272813Y990644D02*
X1272816Y990657D01*
G01X1272813Y990630D02*
Y990644D01*
G01X1286202Y1046140D02*
Y1046142D01*
G01X1286201Y1046134D02*
X1286202Y1046140D01*
G01X1286201Y1046126D02*
Y1046134D01*
G01X1286202Y1041140D02*
Y1041142D01*
G01X1286201Y1041134D02*
X1286202Y1041140D01*
G01X1286201Y1041126D02*
Y1041134D01*
G01X1286202Y1036140D02*
Y1036142D01*
G01X1286201Y1036134D02*
X1286202Y1036140D01*
G01X1286201Y1036126D02*
Y1036134D01*
G01X1286202Y1031140D02*
Y1031142D01*
G01X1286201Y1031134D02*
X1286202Y1031140D01*
G01X1286201Y1031126D02*
Y1031134D01*
G01X1286202Y1026140D02*
Y1026142D01*
G01X1286201Y1026134D02*
X1286202Y1026140D01*
G01X1286201Y1026126D02*
Y1026134D01*
G01X1286202Y1021140D02*
Y1021142D01*
G01X1286201Y1021134D02*
X1286202Y1021140D01*
G01X1286201Y1021126D02*
Y1021134D01*
G01X1286202Y1016140D02*
Y1016142D01*
G01X1286201Y1016134D02*
X1286202Y1016140D01*
G01X1286201Y1016126D02*
Y1016134D01*
G01X1286202Y1011140D02*
Y1011142D01*
G01X1286201Y1011134D02*
X1286202Y1011140D01*
G01X1286201Y1011126D02*
Y1011134D01*
G01X1286202Y986140D02*
Y986142D01*
G01X1286201Y986134D02*
X1286202Y986140D01*
G01X1286201Y986126D02*
Y986134D01*
G01X1286202Y981140D02*
Y981142D01*
G01X1286201Y981134D02*
X1286202Y981140D01*
G01X1286201Y981126D02*
Y981134D01*
G01X1286202Y976140D02*
Y976142D01*
G01X1286201Y976134D02*
X1286202Y976140D01*
G01X1286201Y976126D02*
Y976134D01*
G01X1286202Y971140D02*
Y971142D01*
G01X1286201Y971134D02*
X1286202Y971140D01*
G01X1286201Y971126D02*
Y971134D01*
G01X1286202Y966140D02*
Y966142D01*
G01X1286201Y966134D02*
X1286202Y966140D01*
G01X1286201Y966126D02*
Y966134D01*
G01X1286202Y961140D02*
Y961142D01*
G01X1286201Y961134D02*
X1286202Y961140D01*
G01X1286201Y961126D02*
Y961134D01*
G01X1286202Y956140D02*
Y956142D01*
G01X1286201Y956134D02*
X1286202Y956140D01*
G01X1286201Y956126D02*
Y956134D01*
G01X1272775Y1008222D02*
X1272776Y1008215D01*
G01X1272774Y1008227D02*
X1272775Y1008222D01*
G01X1272774Y1008219D02*
Y1008227D01*
G01X1272813Y1008017D02*
X1272811Y1008031D01*
G01X1272816Y1008005D02*
X1272813Y1008017D01*
G01X1272815Y1007992D02*
X1272816Y1008005D01*
G01X1272813Y1004868D02*
X1272811Y1004881D01*
G01X1272816Y1004855D02*
X1272813Y1004868D01*
G01X1272815Y1004843D02*
X1272816Y1004855D01*
G01X1272813Y1001718D02*
X1272811Y1001732D01*
G01X1272816Y1001706D02*
X1272813Y1001718D01*
G01X1272815Y1001693D02*
X1272816Y1001706D01*
G01X1272813Y998569D02*
X1272811Y998582D01*
G01X1272816Y998556D02*
X1272813Y998569D01*
G01X1272815Y998543D02*
X1272816Y998556D01*
G01X1272813Y995419D02*
X1272811Y995433D01*
G01X1272816Y995406D02*
X1272813Y995419D01*
G01X1272815Y995394D02*
X1272816Y995406D01*
G01X1272813Y992269D02*
X1272811Y992283D01*
G01X1272816Y992257D02*
X1272813Y992269D01*
G01X1272815Y992244D02*
X1272816Y992257D01*
G01X1272813Y989120D02*
X1272811Y989133D01*
G01X1272816Y989107D02*
X1272813Y989120D01*
G01X1272815Y989094D02*
X1272816Y989107D01*
G01X1273723Y1009541D02*
X1273724Y1009528D01*
G01X1273720Y1009554D02*
X1273723Y1009541D01*
G01X1273720Y1009567D02*
Y1009554D01*
G01X1273723Y1006392D02*
X1273724Y1006378D01*
G01X1273720Y1006405D02*
X1273723Y1006392D01*
G01X1273720Y1006417D02*
Y1006405D01*
G01X1273723Y1003242D02*
X1273724Y1003228D01*
G01X1273720Y1003255D02*
X1273723Y1003242D01*
G01X1273720Y1003268D02*
Y1003255D01*
G01X1273723Y1000093D02*
X1273724Y1000079D01*
G01X1273720Y1000106D02*
X1273723Y1000093D01*
G01X1273720Y1000118D02*
Y1000106D01*
G01X1273723Y996943D02*
X1273724Y996929D01*
G01X1273720Y996956D02*
X1273723Y996943D01*
G01X1273720Y996969D02*
Y996956D01*
G01X1273723Y993793D02*
X1273724Y993780D01*
G01X1273720Y993806D02*
X1273723Y993793D01*
G01X1273720Y993819D02*
Y993806D01*
G01X1273723Y990644D02*
X1273724Y990630D01*
G01X1273720Y990657D02*
X1273723Y990644D01*
G01X1273720Y990669D02*
Y990657D01*
G01X1272775Y995624D02*
X1272776Y995617D01*
G01X1272774Y995628D02*
X1272775Y995624D01*
G01X1272774Y995621D02*
Y995628D01*
G01X1272775Y1005073D02*
X1272776Y1005065D01*
G01X1272774Y1005077D02*
X1272775Y1005073D01*
G01X1272774Y1005070D02*
Y1005077D01*
G01X1273720Y1008005D02*
Y1007992D01*
G01X1273722Y1008017D02*
X1273720Y1008005D01*
G01X1273724Y1008031D02*
X1273722Y1008017D01*
G01X1273720Y1004855D02*
Y1004843D01*
G01X1273722Y1004868D02*
X1273720Y1004855D01*
G01X1273724Y1004881D02*
X1273722Y1004868D01*
G01X1273720Y1001706D02*
Y1001693D01*
G01X1273722Y1001718D02*
X1273720Y1001706D01*
G01X1273724Y1001732D02*
X1273722Y1001718D01*
G01X1273720Y998556D02*
Y998543D01*
G01X1273722Y998569D02*
X1273720Y998556D01*
G01X1273724Y998582D02*
X1273722Y998569D01*
G01X1273720Y995406D02*
Y995394D01*
G01X1273722Y995419D02*
X1273720Y995406D01*
G01X1273724Y995433D02*
X1273722Y995419D01*
G01X1273720Y992257D02*
Y992244D01*
G01X1273722Y992269D02*
X1273720Y992257D01*
G01X1273724Y992283D02*
X1273722Y992269D01*
G01X1273720Y989107D02*
Y989094D01*
G01X1273722Y989120D02*
X1273720Y989107D01*
G01X1273724Y989133D02*
X1273722Y989120D01*
G01X1272775Y989325D02*
X1272776Y989317D01*
G01X1272774Y989329D02*
X1272775Y989325D01*
G01X1272774Y989323D02*
Y989329D01*
G01X1273750Y999920D02*
X1273754Y999914D01*
G01X1273746Y999924D02*
X1273750Y999920D01*
G01X1273740Y999928D02*
X1273746Y999924D01*
G01X1273734Y999930D02*
X1273740Y999928D01*
G01X1273727Y999932D02*
X1273734Y999930D01*
G01X1273720Y999932D02*
X1273727D01*
G01X1273750Y1003069D02*
X1273754Y1003064D01*
G01X1273746Y1003074D02*
X1273750Y1003069D01*
G01X1273740Y1003077D02*
X1273746Y1003074D01*
G01X1273734Y1003080D02*
X1273740Y1003077D01*
G01X1273727Y1003081D02*
X1273734Y1003080D01*
G01X1273720Y1003082D02*
X1273727Y1003081D01*
G01X1273750Y1006219D02*
X1273754Y1006213D01*
G01X1273746Y1006223D02*
X1273750Y1006219D01*
G01X1273740Y1006227D02*
X1273746Y1006223D01*
G01X1273734Y1006230D02*
X1273740Y1006227D01*
G01X1273727Y1006231D02*
X1273734Y1006230D01*
G01X1273720Y1006231D02*
X1273727D01*
G01X1273750Y1009369D02*
X1273754Y1009363D01*
G01X1273746Y1009373D02*
X1273750Y1009369D01*
G01X1273740Y1009376D02*
X1273746Y1009373D01*
G01X1273734Y1009379D02*
X1273740Y1009376D01*
G01X1273727Y1009381D02*
X1273734Y1009379D01*
G01X1273720Y1009381D02*
X1273727D01*
G01X1272776Y995609D02*
Y995616D01*
G01X1272779Y995602D02*
X1272776Y995609D01*
G01X1272782Y995596D02*
X1272779Y995602D01*
G01X1272787Y995590D02*
X1272782Y995596D01*
G01X1272793Y995585D02*
X1272787Y995590D01*
G01X1272800Y995582D02*
X1272793Y995585D01*
G01X1272807Y995580D02*
X1272800Y995582D01*
G01X1272815Y995579D02*
X1272807Y995580D01*
G01X1272776Y998759D02*
Y998766D01*
G01X1272779Y998752D02*
X1272776Y998759D01*
G01X1272782Y998745D02*
X1272779Y998752D01*
G01X1272787Y998740D02*
X1272782Y998745D01*
G01X1272793Y998735D02*
X1272787Y998740D01*
G01X1272800Y998731D02*
X1272793Y998735D01*
G01X1272807Y998730D02*
X1272800Y998731D01*
G01X1272815Y998729D02*
X1272807Y998730D01*
G01X1272776Y1001908D02*
Y1001915D01*
G01X1272779Y1001901D02*
X1272776Y1001908D01*
G01X1272782Y1001895D02*
X1272779Y1001901D01*
G01X1272787Y1001889D02*
X1272782Y1001895D01*
G01X1272793Y1001885D02*
X1272787Y1001889D01*
G01X1272800Y1001881D02*
X1272793Y1001885D01*
G01X1272807Y1001879D02*
X1272800Y1001881D01*
G01X1272815Y1001878D02*
X1272807Y1001879D01*
G01X1272776Y1005058D02*
Y1005065D01*
G01X1272779Y1005051D02*
X1272776Y1005058D01*
G01X1272782Y1005044D02*
X1272779Y1005051D01*
G01X1272787Y1005039D02*
X1272782Y1005044D01*
G01X1272793Y1005034D02*
X1272787Y1005039D01*
G01X1272800Y1005031D02*
X1272793Y1005034D01*
G01X1272807Y1005029D02*
X1272800Y1005031D01*
G01X1272815Y1005028D02*
X1272807Y1005029D01*
G01X1272776Y1008207D02*
Y1008215D01*
G01X1272779Y1008200D02*
X1272776Y1008207D01*
G01X1272782Y1008194D02*
X1272779Y1008200D01*
G01X1272787Y1008189D02*
X1272782Y1008194D01*
G01X1272793Y1008184D02*
X1272787Y1008189D01*
G01X1272800Y1008180D02*
X1272793Y1008184D01*
G01X1272807Y1008178D02*
X1272800Y1008180D01*
G01X1272815Y1008178D02*
X1272807D01*
G01X1273730Y990471D02*
X1273739Y990467D01*
G01X1273719Y990472D02*
X1273730Y990471D01*
G01Y993620D02*
X1273739Y993617D01*
G01X1273719Y993622D02*
X1273730Y993620D01*
G01Y996770D02*
X1273739Y996766D01*
G01X1273719Y996772D02*
X1273730Y996770D01*
G01Y999920D02*
X1273739Y999916D01*
G01X1273719Y999921D02*
X1273730Y999920D01*
G01Y1003069D02*
X1273739Y1003065D01*
G01X1273719Y1003071D02*
X1273730Y1003069D01*
G01Y1006219D02*
X1273739Y1006215D01*
G01X1273719Y1006220D02*
X1273730Y1006219D01*
G01Y1009369D02*
X1273739Y1009365D01*
G01X1273719Y1009370D02*
X1273730Y1009369D01*
G01X1272776Y992470D02*
Y992467D01*
G01X1272777Y992464D02*
X1272776Y992470D01*
G01X1272789Y992449D02*
X1272777Y992464D01*
G01X1272814Y992441D02*
X1272789Y992449D01*
G01X1272776Y995620D02*
Y995616D01*
G01X1272777Y995614D02*
X1272776Y995620D01*
G01X1272789Y995599D02*
X1272777Y995614D01*
G01X1272813Y995591D02*
X1272789Y995599D01*
G01X1272776Y1001919D02*
Y1001915D01*
G01X1272777Y1001913D02*
X1272776Y1001919D01*
G01X1272789Y1001898D02*
X1272777Y1001913D01*
G01X1272813Y1001890D02*
X1272789Y1001898D01*
G01X1272776Y1005069D02*
Y1005065D01*
G01X1272777Y1005063D02*
X1272776Y1005069D01*
G01X1272789Y1005048D02*
X1272777Y1005063D01*
G01X1272813Y1005039D02*
X1272789Y1005048D01*
G01X1272776Y989321D02*
Y989317D01*
G01X1272777Y989315D02*
X1272776Y989321D01*
G01X1272789Y989300D02*
X1272777Y989315D01*
G01X1272813Y989291D02*
X1272789Y989300D01*
G01X1272776Y1008219D02*
Y1008215D01*
G01X1272777Y1008213D02*
X1272776Y1008219D01*
G01X1272789Y1008197D02*
X1272777Y1008213D01*
G01X1272813Y1008189D02*
X1272789Y1008197D01*
G01X1287172Y957511D02*
X1287183Y957496D01*
G01X1287148Y957520D02*
X1287172Y957511D01*
G01Y962511D02*
X1287183Y962496D01*
G01X1287148Y962520D02*
X1287172Y962511D01*
G01Y967511D02*
X1287183Y967496D01*
G01X1287148Y967520D02*
X1287172Y967511D01*
G01Y972511D02*
X1287183Y972496D01*
G01X1287148Y972520D02*
X1287172Y972511D01*
G01Y977511D02*
X1287183Y977496D01*
G01X1287148Y977520D02*
X1287172Y977511D01*
G01Y982511D02*
X1287183Y982496D01*
G01X1287148Y982520D02*
X1287172Y982511D01*
G01Y987511D02*
X1287183Y987496D01*
G01X1287148Y987520D02*
X1287172Y987511D01*
G01X1272776Y998770D02*
Y998766D01*
G01X1272777Y998764D02*
X1272776Y998770D01*
G01X1272787Y998750D02*
X1272777Y998764D01*
G01X1272810Y998740D02*
X1272787Y998750D01*
G01X1273752Y996754D02*
X1273745Y996762D01*
G01X1273757Y996743D02*
X1273752Y996754D01*
G01X1273759Y996732D02*
X1273757Y996743D01*
G01X1273752Y990454D02*
X1273745Y990463D01*
G01X1273757Y990444D02*
X1273752Y990454D01*
G01X1273759Y990433D02*
X1273757Y990444D01*
G01X1273752Y993604D02*
X1273745Y993612D01*
G01X1273757Y993594D02*
X1273752Y993604D01*
G01X1273759Y993583D02*
X1273757Y993594D01*
G01X1273752Y999903D02*
X1273745Y999911D01*
G01X1273757Y999893D02*
X1273752Y999903D01*
G01X1273759Y999882D02*
X1273757Y999893D01*
G01X1273752Y1003053D02*
X1273745Y1003061D01*
G01X1273757Y1003043D02*
X1273752Y1003053D01*
G01X1273759Y1003031D02*
X1273757Y1003043D01*
G01X1273752Y1006202D02*
X1273745Y1006211D01*
G01X1273757Y1006192D02*
X1273752Y1006202D01*
G01X1273759Y1006181D02*
X1273757Y1006192D01*
G01X1273752Y1009352D02*
X1273745Y1009360D01*
G01X1273757Y1009342D02*
X1273752Y1009352D01*
G01X1273759Y1009331D02*
X1273757Y1009342D01*
G01X1287172Y1012511D02*
X1287183Y1012496D01*
G01X1287148Y1012520D02*
X1287172Y1012511D01*
G01Y1017511D02*
X1287183Y1017496D01*
G01X1287148Y1017520D02*
X1287172Y1017511D01*
G01Y1022511D02*
X1287183Y1022496D01*
G01X1287148Y1022520D02*
X1287172Y1022511D01*
G01Y1027511D02*
X1287183Y1027496D01*
G01X1287148Y1027520D02*
X1287172Y1027511D01*
G01Y1032511D02*
X1287183Y1032496D01*
G01X1287148Y1032520D02*
X1287172Y1032511D01*
G01Y1037511D02*
X1287183Y1037496D01*
G01X1287148Y1037520D02*
X1287172Y1037511D01*
G01Y1042511D02*
X1287183Y1042496D01*
G01X1287148Y1042520D02*
X1287172Y1042511D01*
G01Y1047511D02*
X1287183Y1047496D01*
G01X1287148Y1047520D02*
X1287172Y1047511D01*
G01X1273728Y996770D02*
X1273719Y996772D01*
G01X1273737Y996767D02*
X1273728Y996770D01*
G01X1273745Y996762D02*
X1273737Y996767D01*
G01X1273728Y990471D02*
X1273719Y990472D01*
G01X1273737Y990468D02*
X1273728Y990471D01*
G01X1273745Y990463D02*
X1273737Y990468D01*
G01X1273728Y993621D02*
X1273719Y993622D01*
G01X1273737Y993618D02*
X1273728Y993621D01*
G01X1273745Y993612D02*
X1273737Y993618D01*
G01X1273728Y999920D02*
X1273719Y999921D01*
G01X1273737Y999917D02*
X1273728Y999920D01*
G01X1273745Y999911D02*
X1273737Y999917D01*
G01X1273728Y1003070D02*
X1273719Y1003071D01*
G01X1273737Y1003067D02*
X1273728Y1003070D01*
G01X1273745Y1003061D02*
X1273737Y1003067D01*
G01X1273728Y1006219D02*
X1273719Y1006220D01*
G01X1273737Y1006216D02*
X1273728Y1006219D01*
G01X1273745Y1006211D02*
X1273737Y1006216D01*
G01X1273728Y1009369D02*
X1273719Y1009370D01*
G01X1273737Y1009366D02*
X1273728Y1009369D01*
G01X1273745Y1009360D02*
X1273737Y1009366D01*
G01X1272815Y989286D02*
Y989280D01*
G01X1272814Y989290D02*
X1272815Y989286D01*
G01X1272813Y989291D02*
X1272814Y989290D01*
G01X1272815Y992436D02*
Y992430D01*
G01X1272814Y992440D02*
X1272815Y992436D01*
G01X1272813Y992441D02*
X1272814Y992440D01*
G01X1272815Y995585D02*
Y995579D01*
G01X1272814Y995589D02*
X1272815Y995585D01*
G01X1272813Y995591D02*
X1272814Y995589D01*
G01X1272815Y998735D02*
Y998729D01*
G01X1272814Y998739D02*
X1272815Y998735D01*
G01X1272813Y998740D02*
X1272814Y998739D01*
G01X1272815Y1001885D02*
Y1001878D01*
G01X1272814Y1001889D02*
X1272815Y1001885D01*
G01X1272813Y1001890D02*
X1272814Y1001889D01*
G01X1272815Y1005034D02*
Y1005028D01*
G01X1272814Y1005038D02*
X1272815Y1005034D01*
G01X1272813Y1005039D02*
X1272814Y1005038D01*
G01X1272815Y1008184D02*
Y1008178D01*
G01X1272814Y1008188D02*
X1272815Y1008184D01*
G01X1272813Y1008189D02*
X1272814Y1008188D01*
G01X1287185Y957487D02*
Y957494D01*
G01X1287186Y957482D02*
X1287185Y957487D01*
G01X1287187Y957480D02*
X1287186Y957482D01*
G01X1287185Y962487D02*
Y962494D01*
G01X1287186Y962482D02*
X1287185Y962487D01*
G01X1287187Y962480D02*
X1287186Y962482D01*
G01X1287185Y967487D02*
Y967494D01*
G01X1287186Y967482D02*
X1287185Y967487D01*
G01X1287187Y967480D02*
X1287186Y967482D01*
G01X1287185Y972487D02*
Y972494D01*
G01X1287186Y972482D02*
X1287185Y972487D01*
G01X1287187Y972480D02*
X1287186Y972482D01*
G01X1287185Y977487D02*
Y977494D01*
G01X1287186Y977482D02*
X1287185Y977487D01*
G01X1287187Y977480D02*
X1287186Y977482D01*
G01X1287185Y982487D02*
Y982494D01*
G01X1287186Y982482D02*
X1287185Y982487D01*
G01X1287187Y982480D02*
X1287186Y982482D01*
G01X1287185Y987487D02*
Y987494D01*
G01X1287186Y987482D02*
X1287185Y987487D01*
G01X1287187Y987480D02*
X1287186Y987482D01*
G01X1287185Y1012487D02*
Y1012494D01*
G01X1287186Y1012482D02*
X1287185Y1012487D01*
G01X1287187Y1012480D02*
X1287186Y1012482D01*
G01X1287185Y1017487D02*
Y1017494D01*
G01X1287186Y1017482D02*
X1287185Y1017487D01*
G01X1287187Y1017480D02*
X1287186Y1017482D01*
G01X1287185Y1022487D02*
Y1022494D01*
G01X1287186Y1022482D02*
X1287185Y1022487D01*
G01X1287187Y1022480D02*
X1287186Y1022482D01*
G01X1287185Y1027487D02*
Y1027494D01*
G01X1287186Y1027482D02*
X1287185Y1027487D01*
G01X1287187Y1027480D02*
X1287186Y1027482D01*
G01X1287185Y1032487D02*
Y1032494D01*
G01X1287186Y1032482D02*
X1287185Y1032487D01*
G01X1287187Y1032480D02*
X1287186Y1032482D01*
G01X1287185Y1037487D02*
Y1037494D01*
G01X1287186Y1037482D02*
X1287185Y1037487D01*
G01X1287187Y1037480D02*
X1287186Y1037482D01*
G01X1272798Y992443D02*
X1272813Y992441D01*
G01X1272787Y992450D02*
X1272798Y992443D01*
G01X1272775Y992469D02*
X1272787Y992450D01*
G01X1272798Y1001892D02*
X1272813Y1001890D01*
G01X1272787Y1001900D02*
X1272798Y1001892D01*
G01X1272775Y1001918D02*
X1272787Y1001900D01*
G01X1272798Y995593D02*
X1272813Y995591D01*
G01X1272786Y995601D02*
X1272798Y995593D01*
G01X1272774Y995621D02*
X1272786Y995601D01*
G01X1272798Y1005042D02*
X1272813Y1005039D01*
G01X1272786Y1005050D02*
X1272798Y1005042D01*
G01X1272774Y1005070D02*
X1272786Y1005050D01*
G01X1273760Y989325D02*
Y989317D01*
G01X1273759Y989329D02*
X1273760Y989325D01*
G01X1273758Y989331D02*
X1273759Y989329D01*
G01X1273760Y992474D02*
Y992467D01*
G01X1273759Y992479D02*
X1273760Y992474D01*
G01X1273758Y992480D02*
X1273759Y992479D01*
G01X1273760Y995624D02*
Y995616D01*
G01X1273759Y995628D02*
X1273760Y995624D01*
G01X1273758Y995630D02*
X1273759Y995628D01*
G01X1273760Y998774D02*
Y998766D01*
G01X1273759Y998778D02*
X1273760Y998774D01*
G01X1273758Y998780D02*
X1273759Y998778D01*
G01X1273760Y1001923D02*
Y1001915D01*
G01X1273759Y1001928D02*
X1273760Y1001923D01*
G01X1273758Y1001929D02*
X1273759Y1001928D01*
G01X1273760Y1005073D02*
Y1005065D01*
G01X1273759Y1005077D02*
X1273760Y1005073D01*
G01X1273758Y1005079D02*
X1273759Y1005077D01*
G01X1273760Y1008222D02*
Y1008215D01*
G01X1273759Y1008227D02*
X1273760Y1008222D01*
G01X1273758Y1008228D02*
X1273759Y1008227D01*
G01X1272798Y1008192D02*
X1272813Y1008189D01*
G01X1272785Y1008200D02*
X1272798Y1008192D01*
G01X1272774Y1008220D02*
X1272785Y1008200D01*
G01X1272798Y989294D02*
X1272813Y989291D01*
G01X1272785Y989303D02*
X1272798Y989294D01*
G01X1272774Y989323D02*
X1272785Y989303D01*
G01X1273759Y990453D02*
X1273760Y990446D01*
G01X1273757Y990459D02*
X1273759Y990453D01*
G01X1273754Y990465D02*
X1273757Y990459D01*
G01X1273759Y993603D02*
X1273760Y993596D01*
G01X1273757Y993609D02*
X1273759Y993603D01*
G01X1273754Y993615D02*
X1273757Y993609D01*
G01X1273759Y996752D02*
X1273760Y996746D01*
G01X1273757Y996759D02*
X1273759Y996752D01*
G01X1273754Y996765D02*
X1273757Y996759D01*
G01X1273759Y999902D02*
X1273760Y999895D01*
G01X1273757Y999908D02*
X1273759Y999902D01*
G01X1273754Y999914D02*
X1273757Y999908D01*
G01X1273759Y1003052D02*
X1273760Y1003045D01*
G01X1273757Y1003058D02*
X1273759Y1003052D01*
G01X1273754Y1003064D02*
X1273757Y1003058D01*
G01X1273759Y1006201D02*
X1273760Y1006194D01*
G01X1273757Y1006207D02*
X1273759Y1006201D01*
G01X1273754Y1006213D02*
X1273757Y1006207D01*
G01X1273759Y1009351D02*
X1273760Y1009344D01*
G01X1273757Y1009357D02*
X1273759Y1009351D01*
G01X1273754Y1009363D02*
X1273757Y1009357D01*
G01X1273721Y989286D02*
Y989280D01*
G01X1273720Y989290D02*
X1273721Y989286D01*
G01X1273719Y989291D02*
X1273720Y989290D01*
G01X1273721Y992436D02*
Y992430D01*
G01X1273720Y992439D02*
X1273721Y992436D01*
G01X1273719Y992441D02*
X1273720Y992439D01*
G01X1273721Y995585D02*
Y995579D01*
G01X1273720Y995589D02*
X1273721Y995585D01*
G01X1273719Y995591D02*
X1273720Y995589D01*
G01X1273721Y998735D02*
Y998729D01*
G01X1273720Y998739D02*
X1273721Y998735D01*
G01X1273719Y998740D02*
X1273720Y998739D01*
G01X1273721Y1001885D02*
Y1001878D01*
G01X1273720Y1001888D02*
X1273721Y1001885D01*
G01X1273719Y1001890D02*
X1273720Y1001888D01*
G01X1273721Y1008184D02*
Y1008178D01*
G01X1273720Y1008187D02*
X1273721Y1008184D01*
G01X1273719Y1008189D02*
X1273720Y1008187D01*
G01X1286201Y957527D02*
Y957536D01*
G01X1286202Y957521D02*
X1286201Y957527D01*
G01X1286202Y957520D02*
Y957521D01*
G01X1286201Y962527D02*
Y962536D01*
G01X1286202Y962521D02*
X1286201Y962527D01*
G01X1286202Y962520D02*
Y962521D01*
G01X1286201Y967527D02*
Y967536D01*
G01X1286202Y967521D02*
X1286201Y967527D01*
G01X1286202Y967520D02*
Y967521D01*
G01X1286201Y972527D02*
Y972536D01*
G01X1286202Y972521D02*
X1286201Y972527D01*
G01X1286202Y972520D02*
Y972521D01*
G01X1286201Y977527D02*
Y977536D01*
G01X1286202Y977521D02*
X1286201Y977527D01*
G01X1286202Y977520D02*
Y977521D01*
G01X1286201Y982527D02*
Y982536D01*
G01X1286202Y982521D02*
X1286201Y982527D01*
G01X1286202Y982520D02*
Y982521D01*
G01X1286201Y987527D02*
Y987536D01*
G01X1286202Y987521D02*
X1286201Y987527D01*
G01X1286202Y987520D02*
Y987521D01*
G01X1286201Y1012527D02*
Y1012536D01*
G01X1286202Y1012521D02*
X1286201Y1012527D01*
G01X1286202Y1012520D02*
Y1012521D01*
G01X1286201Y1017527D02*
Y1017536D01*
G01X1286202Y1017521D02*
X1286201Y1017527D01*
G01X1286202Y1017520D02*
Y1017521D01*
G01X1286201Y1022527D02*
Y1022536D01*
G01X1286202Y1022521D02*
X1286201Y1022527D01*
G01X1286202Y1022520D02*
Y1022521D01*
G01X1286201Y1027527D02*
Y1027536D01*
G01X1286202Y1027521D02*
X1286201Y1027527D01*
G01X1286202Y1027520D02*
Y1027521D01*
G01X1286201Y1032527D02*
Y1032536D01*
G01X1286202Y1032521D02*
X1286201Y1032527D01*
G01X1286202Y1032520D02*
Y1032521D01*
G01X1286201Y1037527D02*
Y1037536D01*
G01X1286202Y1037521D02*
X1286201Y1037527D01*
G01X1286202Y1037520D02*
Y1037521D01*
G01X1286201Y1042527D02*
Y1042536D01*
G01X1286202Y1042521D02*
X1286201Y1042527D01*
G01X1286202Y1042520D02*
Y1042521D01*
G01X1287177Y957663D02*
X1287185Y957637D01*
G01X1287167Y957690D02*
X1287177Y957663D01*
G01X1287156Y957717D02*
X1287167Y957690D01*
G01X1287177Y962663D02*
X1287185Y962637D01*
G01X1287167Y962690D02*
X1287177Y962663D01*
G01X1287156Y962717D02*
X1287167Y962690D01*
G01X1287177Y967663D02*
X1287185Y967637D01*
G01X1287167Y967690D02*
X1287177Y967663D01*
G01X1287156Y967717D02*
X1287167Y967690D01*
G01X1287177Y972663D02*
X1287185Y972637D01*
G01X1287167Y972690D02*
X1287177Y972663D01*
G01X1287156Y972717D02*
X1287167Y972690D01*
G01X1287177Y977663D02*
X1287185Y977637D01*
G01X1287167Y977690D02*
X1287177Y977663D01*
G01X1287156Y977717D02*
X1287167Y977690D01*
G01X1287177Y982663D02*
X1287185Y982637D01*
G01X1287167Y982690D02*
X1287177Y982663D01*
G01X1287156Y982717D02*
X1287167Y982690D01*
G01X1287177Y987663D02*
X1287185Y987637D01*
G01X1287167Y987690D02*
X1287177Y987663D01*
G01X1287156Y987717D02*
X1287167Y987690D01*
G01X1287177Y1012663D02*
X1287185Y1012637D01*
G01X1287167Y1012690D02*
X1287177Y1012663D01*
G01X1287156Y1012717D02*
X1287167Y1012690D01*
G01X1287177Y1017663D02*
X1287185Y1017637D01*
G01X1287167Y1017690D02*
X1287177Y1017663D01*
G01X1287156Y1017717D02*
X1287167Y1017690D01*
G01X1287177Y1022663D02*
X1287185Y1022637D01*
G01X1287167Y1022690D02*
X1287177Y1022663D01*
G01X1287156Y1022717D02*
X1287167Y1022690D01*
G01X1287177Y1027663D02*
X1287185Y1027637D01*
G01X1287167Y1027690D02*
X1287177Y1027663D01*
G01X1287156Y1027717D02*
X1287167Y1027690D01*
G01X1287177Y1032663D02*
X1287185Y1032637D01*
G01X1287167Y1032690D02*
X1287177Y1032663D01*
G01X1287156Y1032717D02*
X1287167Y1032690D01*
G01X1287177Y1037663D02*
X1287185Y1037637D01*
G01X1287167Y1037690D02*
X1287177Y1037663D01*
G01X1287156Y1037717D02*
X1287167Y1037690D01*
G01X1287177Y1042663D02*
X1287185Y1042637D01*
G01X1287167Y1042690D02*
X1287177Y1042663D01*
G01X1287156Y1042717D02*
X1287167Y1042690D01*
G01X1272793Y998745D02*
X1272813Y998740D01*
G01X1272780Y998757D02*
X1272793Y998745D01*
G01X1272773Y998775D02*
X1272780Y998757D01*
G01X1287168Y957515D02*
X1287148Y957520D01*
G01X1287182Y957500D02*
X1287168Y957515D01*
G01X1287187Y957480D02*
X1287182Y957500D01*
G01X1287168Y962515D02*
X1287148Y962520D01*
G01X1287182Y962500D02*
X1287168Y962515D01*
G01X1287187Y962480D02*
X1287182Y962500D01*
G01X1287168Y967515D02*
X1287148Y967520D01*
G01X1287182Y967500D02*
X1287168Y967515D01*
G01X1287187Y967480D02*
X1287182Y967500D01*
G01X1287168Y972515D02*
X1287148Y972520D01*
G01X1287182Y972500D02*
X1287168Y972515D01*
G01X1287187Y972480D02*
X1287182Y972500D01*
G01X1287168Y977515D02*
X1287148Y977520D01*
G01X1287182Y977500D02*
X1287168Y977515D01*
G01X1287187Y977480D02*
X1287182Y977500D01*
G01X1287168Y982515D02*
X1287148Y982520D01*
G01X1287182Y982500D02*
X1287168Y982515D01*
G01X1287187Y982480D02*
X1287182Y982500D01*
G01X1287168Y987515D02*
X1287148Y987520D01*
G01X1287182Y987500D02*
X1287168Y987515D01*
G01X1287187Y987480D02*
X1287182Y987500D01*
G01X1287168Y1012515D02*
X1287148Y1012520D01*
G01X1287182Y1012500D02*
X1287168Y1012515D01*
G01X1287187Y1012480D02*
X1287182Y1012500D01*
G01X1287168Y1017515D02*
X1287148Y1017520D01*
G01X1287182Y1017500D02*
X1287168Y1017515D01*
G01X1287187Y1017480D02*
X1287182Y1017500D01*
G01X1287168Y1022515D02*
X1287148Y1022520D01*
G01X1287182Y1022500D02*
X1287168Y1022515D01*
G01X1287187Y1022480D02*
X1287182Y1022500D01*
G01X1287168Y1027515D02*
X1287148Y1027520D01*
G01X1287182Y1027500D02*
X1287168Y1027515D01*
G01X1287187Y1027480D02*
X1287182Y1027500D01*
G01X1287168Y1032515D02*
X1287148Y1032520D01*
G01X1287182Y1032500D02*
X1287168Y1032515D01*
G01X1287187Y1032480D02*
X1287182Y1032500D01*
G01X1287168Y1037515D02*
X1287148Y1037520D01*
G01X1287182Y1037500D02*
X1287168Y1037515D01*
G01X1287187Y1037480D02*
X1287182Y1037500D01*
G01X1287168Y1042515D02*
X1287148Y1042520D01*
G01X1287182Y1042500D02*
X1287168Y1042515D01*
G01X1287187Y1042480D02*
X1287182Y1042500D01*
G01X1287168Y1047515D02*
X1287148Y1047520D01*
G01X1287182Y1047500D02*
X1287168Y1047515D01*
G01X1287187Y1047480D02*
X1287182Y1047500D01*
G01X1287185Y1042487D02*
Y1042494D01*
G01X1287186Y1042482D02*
X1287185Y1042487D01*
G01X1287187Y1042480D02*
X1287186Y1042482D01*
G01Y1047482D02*
X1287185Y1047487D01*
G01X1287187Y1047480D02*
X1287186Y1047482D01*
G01X1273719Y1005039D02*
X1273722Y1005028D01*
G01X1286614Y989469D02*
X1287795Y988287D01*
G01X1282677Y989469D02*
X1283858Y988287D01*
G01X1272662Y1008228D02*
X1272774Y1008220D01*
G01X1291535Y1046142D02*
X1286202D01*
G01X1286201Y1045650D02*
X1287185D01*
G01Y1043012D02*
X1286201D01*
G01X1286202Y1042520D02*
X1291535D01*
G01Y1042480D02*
X1287187D01*
G01X1291535Y1041142D02*
X1286202D01*
G01X1286201Y1040650D02*
X1287185D01*
G01Y1038012D02*
X1286201D01*
G01X1286202Y1037520D02*
X1291535D01*
G01Y1037480D02*
X1287187D01*
G01X1291535Y1036142D02*
X1286202D01*
G01X1286201Y1035650D02*
X1287185D01*
G01Y1033012D02*
X1286201D01*
G01X1286202Y1032520D02*
X1291535D01*
G01Y1032480D02*
X1287187D01*
G01X1291535Y1031142D02*
X1286202D01*
G01X1286201Y1030650D02*
X1287185D01*
G01Y1028012D02*
X1286201D01*
G01X1286202Y1027520D02*
X1291535D01*
G01Y1027480D02*
X1287187D01*
G01X1291535Y1026142D02*
X1286202D01*
G01X1286201Y1025650D02*
X1287185D01*
G01Y1023012D02*
X1286201D01*
G01X1286202Y1022520D02*
X1291535D01*
G01Y1022480D02*
X1287187D01*
G01X1291535Y1021142D02*
X1286202D01*
G01X1287185Y1045946D02*
X1286201Y1045945D01*
G01Y1042715D02*
X1287156Y1042717D01*
G01X1287185Y1040946D02*
X1286201Y1040945D01*
G01Y1037715D02*
X1287156Y1037717D01*
G01X1287185Y1035946D02*
X1286201Y1035945D01*
G01Y1032715D02*
X1287156Y1032717D01*
G01X1287185Y1030946D02*
X1286201Y1030945D01*
G01Y1027715D02*
X1287156Y1027717D01*
G01X1287185Y1025946D02*
X1286201Y1025945D01*
G01Y1022715D02*
X1287156Y1022717D01*
G01X1273759Y990435D02*
X1273760Y990446D01*
G01X1273759Y993585D02*
X1273760Y993596D01*
G01X1273759Y996734D02*
X1273760Y996746D01*
G01X1273759Y999884D02*
X1273760Y999895D01*
G01X1273759Y1003033D02*
X1273760Y1003045D01*
G01X1273759Y1006183D02*
X1273760Y1006194D01*
G01X1273759Y1009333D02*
X1273760Y1009344D01*
G01X1287185Y957494D02*
Y957502D01*
G01Y962494D02*
Y962502D01*
G01Y967494D02*
Y967502D01*
G01Y972494D02*
Y972502D01*
G01Y977494D02*
Y977502D01*
G01Y982494D02*
Y982502D01*
G01Y987494D02*
Y987502D01*
G01Y1012494D02*
Y1012502D01*
G01Y1017494D02*
Y1017502D01*
G01Y1022494D02*
Y1022502D01*
G01Y1027494D02*
Y1027502D01*
G01Y1032494D02*
Y1032502D01*
G01Y1037494D02*
Y1037502D01*
G01Y1042494D02*
Y1042502D01*
G01X1291535Y1046142D02*
Y1047520D01*
G01Y1041142D02*
Y1042520D01*
G01Y1036142D02*
Y1037520D01*
G01Y1031142D02*
Y1032520D01*
G01Y1026142D02*
Y1027520D01*
G01Y1021142D02*
Y1022520D01*
G01Y1016142D02*
Y1017520D01*
G01Y1011142D02*
Y1012520D01*
G01Y986142D02*
Y987520D01*
G01Y981142D02*
Y982520D01*
G01Y976142D02*
Y977520D01*
G01Y971142D02*
Y972520D01*
G01Y966142D02*
Y967520D01*
G01Y961142D02*
Y962520D01*
G01Y956142D02*
Y957520D01*
G01X1288366D02*
Y956142D01*
G01Y962520D02*
Y961142D01*
G01Y967520D02*
Y966142D01*
G01Y972520D02*
Y971142D01*
G01Y977520D02*
Y976142D01*
G01Y982520D02*
Y981142D01*
G01Y987520D02*
Y986142D01*
G01Y1012520D02*
Y1011142D01*
G01Y1017520D02*
Y1016142D01*
G01Y1022520D02*
Y1021142D01*
G01Y1027520D02*
Y1026142D01*
G01Y1032520D02*
Y1031142D01*
G01Y1037520D02*
Y1036142D01*
G01Y1042520D02*
Y1041142D01*
G01Y1047520D02*
Y1046142D01*
G01X1287795Y1010374D02*
Y988287D01*
G01X1287185Y1045650D02*
Y1048012D01*
G01Y1040650D02*
Y1043012D01*
G01Y1035650D02*
Y1038012D01*
G01Y1030650D02*
Y1033012D01*
G01Y1025650D02*
Y1028012D01*
G01Y1020650D02*
Y1023012D01*
G01Y1015650D02*
Y1018012D01*
G01Y1010650D02*
Y1013012D01*
G01Y985650D02*
Y988012D01*
G01Y980650D02*
Y983012D01*
G01Y975650D02*
Y978012D01*
G01Y970650D02*
Y973012D01*
G01Y965650D02*
Y968012D01*
G01Y960650D02*
Y963012D01*
G01Y955650D02*
Y958012D01*
G01Y962494D02*
Y962637D01*
G01Y967494D02*
Y967637D01*
G01Y972494D02*
Y972637D01*
G01Y977494D02*
Y977637D01*
G01Y982494D02*
Y982637D01*
G01Y987494D02*
Y987637D01*
G01Y1012494D02*
Y1012637D01*
G01Y1017494D02*
Y1017637D01*
G01Y1022494D02*
Y1022637D01*
G01Y1027494D02*
Y1027637D01*
G01Y1032494D02*
Y1032637D01*
G01Y1037494D02*
Y1037637D01*
G01Y1042494D02*
Y1042637D01*
G01X1286614Y1009193D02*
Y989469D01*
G01X1286201Y958012D02*
Y955650D01*
G01Y963012D02*
Y960650D01*
G01Y968012D02*
Y965650D01*
G01Y973012D02*
Y970650D01*
G01Y978012D02*
Y975650D01*
G01Y983012D02*
Y980650D01*
G01Y988012D02*
Y985650D01*
G01Y1013012D02*
Y1010650D01*
G01Y1018012D02*
Y1015650D01*
G01Y1023012D02*
Y1020650D01*
G01Y1028012D02*
Y1025650D01*
G01Y1033012D02*
Y1030650D01*
G01Y1038012D02*
Y1035650D01*
G01Y1043012D02*
Y1040650D01*
G01Y1048012D02*
Y1045650D01*
G01X1283858Y1086831D02*
Y1010374D01*
G01X1282677Y989469D02*
Y953012D01*
G01Y1085650D02*
Y1009193D01*
G01X1277165Y953012D02*
Y1085650D01*
G01X1274213Y1090571D02*
Y1011535D01*
G01X1273760Y1008031D02*
Y1009528D01*
G01Y1004881D02*
Y1006378D01*
G01Y1001732D02*
Y1003228D01*
G01Y998582D02*
Y1000079D01*
G01Y995433D02*
Y996929D01*
G01Y992283D02*
Y993780D01*
G01Y989133D02*
Y990630D01*
G01X1273720Y989280D02*
Y989133D01*
G01Y990630D02*
Y990483D01*
G01Y995579D02*
Y995432D01*
G01Y992430D02*
Y992283D01*
G01Y993780D02*
Y993633D01*
G01Y998729D02*
Y998582D01*
G01Y1000079D02*
Y999932D01*
G01Y996930D02*
Y996783D01*
G01Y1001878D02*
Y1001731D01*
G01Y1003229D02*
Y1003082D01*
G01Y1008178D02*
Y1008031D01*
G01Y1009528D02*
Y1009381D01*
G01Y1005028D02*
Y1004881D01*
G01Y1006378D02*
Y1006231D01*
G01X1272815Y1008031D02*
Y1008178D01*
G01Y1009381D02*
Y1009528D01*
G01Y1004881D02*
Y1005028D01*
G01Y1006231D02*
Y1006378D01*
G01Y1001731D02*
Y1001878D01*
G01Y1003082D02*
Y1003229D01*
G01Y998582D02*
Y998729D01*
G01Y999932D02*
Y1000079D01*
G01Y996783D02*
Y996930D01*
G01Y995432D02*
Y995579D01*
G01Y992283D02*
Y992430D01*
G01Y993633D02*
Y993780D01*
G01Y989133D02*
Y989280D01*
G01Y990483D02*
Y990630D01*
G01X1272776D02*
Y989134D01*
G01Y993780D02*
Y992283D01*
G01Y1000079D02*
Y998583D01*
G01Y996929D02*
Y995433D01*
G01Y1003228D02*
Y1001732D01*
G01Y1009528D02*
Y1008031D01*
G01Y1006378D02*
Y1004882D01*
G01X1271594Y990472D02*
Y989291D01*
G01Y996772D02*
Y995591D01*
G01Y993622D02*
Y992441D01*
G01Y999921D02*
Y998740D01*
G01Y1003071D02*
Y1001890D01*
G01Y1009370D02*
Y1008189D01*
G01Y1006220D02*
Y1005039D01*
G01X1271260Y1011535D02*
Y987126D01*
G01X1270866D02*
Y1011535D01*
G01X1267835Y1008189D02*
Y1009370D01*
G01Y1005039D02*
Y1006220D01*
G01Y1001890D02*
Y1003071D01*
G01Y998740D02*
Y999921D01*
G01Y995591D02*
Y996772D01*
G01Y992441D02*
Y993622D01*
G01Y989291D02*
Y990472D01*
G01X1273760Y1008215D02*
X1273759Y1008226D01*
G01X1273760Y1005065D02*
X1273759Y1005076D01*
G01X1273760Y1001916D02*
X1273759Y1001926D01*
G01X1273760Y998766D02*
X1273759Y998777D01*
G01X1273760Y995617D02*
X1273759Y995627D01*
G01X1273760Y992467D02*
X1273759Y992478D01*
G01X1273760Y989317D02*
X1273759Y989328D01*
G01X1272773Y998775D02*
X1272662Y998780D01*
G01X1272773Y992477D02*
X1272662Y992480D01*
G01X1272773Y1001926D02*
X1272662Y1001929D01*
G01X1286201Y1020650D02*
X1287185D01*
G01Y1018012D02*
X1286201D01*
G01X1286202Y1017520D02*
X1291535D01*
G01Y1017480D02*
X1287187D01*
G01X1291535Y1016142D02*
X1286202D01*
G01X1286201Y1015650D02*
X1287185D01*
G01Y1013012D02*
X1286201D01*
G01X1286202Y1012520D02*
X1291535D01*
G01Y1012480D02*
X1287187D01*
G01X1274213Y1011535D02*
X1270866D01*
G01X1291535Y1011142D02*
X1286202D01*
G01X1286201Y1010650D02*
X1287185D01*
G01X1283858Y1010374D02*
X1287795D01*
G01X1273720Y1009567D02*
X1272815D01*
G01X1273760Y1009528D02*
X1272776D01*
G01X1273719Y1009370D02*
X1267835D01*
G01Y1009331D02*
X1273759D01*
G01X1282677Y1009193D02*
X1286614D01*
G01X1273758Y1008228D02*
X1267835D01*
G01X1273719Y1008189D02*
X1267835D01*
G01X1272776Y1008031D02*
X1273760D01*
G01X1272815Y1007992D02*
X1273720D01*
G01Y1006417D02*
X1272815D01*
G01X1273760Y1006378D02*
X1272776D01*
G01X1273719Y1006220D02*
X1267835D01*
G01Y1006181D02*
X1273759D01*
G01X1273758Y1005079D02*
X1267835D01*
G01X1273719Y1005039D02*
X1267835D01*
G01X1272776Y1004882D02*
X1273760D01*
G01X1272815Y1004843D02*
X1273720D01*
G01Y1003268D02*
X1272815D01*
G01X1273760Y1003228D02*
X1272776D01*
G01X1273719Y1003071D02*
X1267835D01*
G01Y1003031D02*
X1273759D01*
G01X1272028Y1001929D02*
X1271594D01*
G01X1273758D02*
X1267835D01*
G01X1273719Y1001890D02*
X1267835D01*
G01X1272776Y1001732D02*
X1273760D01*
G01X1272815Y1001693D02*
X1273720D01*
G01Y1000118D02*
X1272815D01*
G01X1273760Y1000079D02*
X1272776D01*
G01X1273719Y999921D02*
X1267835D01*
G01Y999882D02*
X1273759D01*
G01X1272028Y998780D02*
X1271594D01*
G01X1273758D02*
X1267835D01*
G01X1273719Y998740D02*
X1267835D01*
G01X1272776Y998583D02*
X1273760D01*
G01X1272815Y998543D02*
X1273720D01*
G01Y996969D02*
X1272815D01*
G01X1273760Y996929D02*
X1272776D01*
G01X1273719Y996772D02*
X1267835D01*
G01Y996732D02*
X1273759D01*
G01X1273758Y995630D02*
X1267835D01*
G01X1273719Y995591D02*
X1267835D01*
G01X1272776Y995433D02*
X1273760D01*
G01X1272815Y995394D02*
X1273720D01*
G01Y993819D02*
X1272815D01*
G01X1273760Y993780D02*
X1272776D01*
G01X1273719Y993622D02*
X1267835D01*
G01Y993583D02*
X1273759D01*
G01X1272028Y992480D02*
X1271594D01*
G01X1273758D02*
X1267835D01*
G01X1273719Y992441D02*
X1267835D01*
G01X1272776Y992283D02*
X1273760D01*
G01X1272815Y992244D02*
X1273720D01*
G01Y990669D02*
X1272815D01*
G01X1273760Y990630D02*
X1272776D01*
G01X1273719Y990472D02*
X1267835D01*
G01Y990433D02*
X1273759D01*
G01X1286614Y989469D02*
X1282677D01*
G01X1273758Y989331D02*
X1267835D01*
G01X1273719Y989291D02*
X1267835D01*
G01X1272776Y989134D02*
X1273760D01*
G01X1272815Y989094D02*
X1273720D01*
G01X1287795Y988287D02*
X1283858D01*
G01X1287185Y988012D02*
X1286201D01*
G01X1286202Y987520D02*
X1291535D01*
G01Y987480D02*
X1287187D01*
G01X1274213Y987126D02*
X1270866D01*
G01X1291535Y986142D02*
X1286202D01*
G01X1286201Y985650D02*
X1287185D01*
G01Y983012D02*
X1286201D01*
G01X1286202Y982520D02*
X1291535D01*
G01Y982480D02*
X1287187D01*
G01X1291535Y981142D02*
X1286202D01*
G01X1286201Y980650D02*
X1287185D01*
G01Y978012D02*
X1286201D01*
G01X1286202Y977520D02*
X1291535D01*
G01Y977480D02*
X1287187D01*
G01X1291535Y976142D02*
X1286202D01*
G01X1286201Y975650D02*
X1287185D01*
G01Y973012D02*
X1286201D01*
G01X1286202Y972520D02*
X1291535D01*
G01Y972480D02*
X1287187D01*
G01X1291535Y971142D02*
X1286202D01*
G01X1286201Y970650D02*
X1287185D01*
G01Y968012D02*
X1286201D01*
G01X1286202Y967520D02*
X1291535D01*
G01Y967480D02*
X1287187D01*
G01X1291535Y966142D02*
X1286202D01*
G01X1286201Y965650D02*
X1287185D01*
G01Y963012D02*
X1286201D01*
G01X1286202Y962520D02*
X1291535D01*
G01Y962480D02*
X1287187D01*
G01X1291535Y961142D02*
X1286202D01*
G01X1286201Y960650D02*
X1287185D01*
G01Y958012D02*
X1286201D01*
G01X1286202Y957520D02*
X1291535D01*
G01Y957480D02*
X1287187D01*
G01X1291535Y956142D02*
X1286202D01*
G01X1286201Y955650D02*
X1287185D01*
G01X1282677Y953012D02*
X1277165D01*
G01X1287185Y1020946D02*
X1286201Y1020945D01*
G01Y1017715D02*
X1287156Y1017717D01*
G01X1287185Y1015946D02*
X1286201Y1015945D01*
G01Y1012715D02*
X1287156Y1012717D01*
G01X1287185Y1010946D02*
X1286201Y1010945D01*
G01Y987715D02*
X1287156Y987717D01*
G01X1287185Y985946D02*
X1286201Y985945D01*
G01Y982715D02*
X1287156Y982717D01*
G01X1287185Y980946D02*
X1286201Y980945D01*
G01Y977715D02*
X1287156Y977717D01*
G01X1287185Y975946D02*
X1286201Y975945D01*
G01Y972715D02*
X1287156Y972717D01*
G01X1287185Y970946D02*
X1286201Y970945D01*
G01Y967715D02*
X1287156Y967717D01*
G01X1287185Y965946D02*
X1286201Y965945D01*
G01Y962715D02*
X1287156Y962717D01*
G01X1287185Y960946D02*
X1286201Y960945D01*
G01Y957715D02*
X1287156Y957717D01*
G01X1287185Y955946D02*
X1286201Y955945D01*
G01X1286614Y1009193D02*
X1287795Y1010374D01*
G01X1282677Y1009193D02*
X1283858Y1010374D01*
G01X1287185Y1081134D02*
Y1081125D01*
G01X1287186Y1081140D02*
X1287185Y1081134D01*
G01X1287188Y1081142D02*
X1287186Y1081140D01*
G01X1287185Y1076134D02*
Y1076125D01*
G01X1287186Y1076140D02*
X1287185Y1076134D01*
G01X1287188Y1076142D02*
X1287186Y1076140D01*
G01X1287185Y1071134D02*
Y1071125D01*
G01X1287186Y1071140D02*
X1287185Y1071134D01*
G01X1287188Y1071142D02*
X1287186Y1071140D01*
G01X1287185Y1066134D02*
Y1066125D01*
G01X1287186Y1066140D02*
X1287185Y1066134D01*
G01X1287188Y1066142D02*
X1287186Y1066140D01*
G01X1287185Y1061134D02*
Y1061125D01*
G01X1287186Y1061140D02*
X1287185Y1061134D01*
G01X1287188Y1061142D02*
X1287186Y1061140D01*
G01X1287185Y1056134D02*
Y1056125D01*
G01X1287186Y1056140D02*
X1287185Y1056134D01*
G01X1287188Y1056142D02*
X1287186Y1056140D01*
G01X1287185Y1051134D02*
Y1051125D01*
G01X1287186Y1051140D02*
X1287185Y1051134D01*
G01X1287188Y1051142D02*
X1287186Y1051140D01*
G01X1287152Y1047618D02*
X1287156Y1047717D01*
G01X1287146Y1047546D02*
X1287152Y1047618D01*
G01X1287148Y1047520D02*
X1287146Y1047546D01*
G01X1287152Y1052618D02*
X1287156Y1052717D01*
G01X1287146Y1052546D02*
X1287152Y1052618D01*
G01X1287148Y1052520D02*
X1287146Y1052546D01*
G01X1287152Y1057618D02*
X1287156Y1057717D01*
G01X1287146Y1057546D02*
X1287152Y1057618D01*
G01X1287148Y1057520D02*
X1287146Y1057546D01*
G01X1287152Y1062618D02*
X1287156Y1062717D01*
G01X1287146Y1062546D02*
X1287152Y1062618D01*
G01X1287148Y1062520D02*
X1287146Y1062546D01*
G01X1286202Y1081140D02*
Y1081142D01*
G01X1286201Y1081134D02*
X1286202Y1081140D01*
G01X1286201Y1081126D02*
Y1081134D01*
G01X1286202Y1076140D02*
Y1076142D01*
G01X1286201Y1076134D02*
X1286202Y1076140D01*
G01X1286201Y1076126D02*
Y1076134D01*
G01X1286202Y1071140D02*
Y1071142D01*
G01X1286201Y1071134D02*
X1286202Y1071140D01*
G01X1286201Y1071126D02*
Y1071134D01*
G01X1286202Y1066140D02*
Y1066142D01*
G01X1286201Y1066134D02*
X1286202Y1066140D01*
G01X1286201Y1066126D02*
Y1066134D01*
G01X1286202Y1061140D02*
Y1061142D01*
G01X1286201Y1061134D02*
X1286202Y1061140D01*
G01X1286201Y1061126D02*
Y1061134D01*
G01X1286202Y1056140D02*
Y1056142D01*
G01X1286201Y1056134D02*
X1286202Y1056140D01*
G01X1286201Y1056126D02*
Y1056134D01*
G01X1286202Y1051140D02*
Y1051142D01*
G01X1286201Y1051134D02*
X1286202Y1051140D01*
G01X1286201Y1051126D02*
Y1051134D01*
G01X1287152Y1067618D02*
X1287156Y1067717D01*
G01X1287146Y1067546D02*
X1287152Y1067618D01*
G01X1287148Y1067520D02*
X1287146Y1067546D01*
G01X1287152Y1072618D02*
X1287156Y1072717D01*
G01X1287146Y1072546D02*
X1287152Y1072618D01*
G01X1287148Y1072520D02*
X1287146Y1072546D01*
G01X1287152Y1077618D02*
X1287156Y1077717D01*
G01X1287146Y1077546D02*
X1287152Y1077618D01*
G01X1287148Y1077520D02*
X1287146Y1077546D01*
G01X1287152Y1082618D02*
X1287156Y1082717D01*
G01X1287146Y1082546D02*
X1287152Y1082618D01*
G01X1287148Y1082520D02*
X1287146Y1082546D01*
G01X1287172Y1052511D02*
X1287183Y1052496D01*
G01X1287148Y1052520D02*
X1287172Y1052511D01*
G01Y1057511D02*
X1287183Y1057496D01*
G01X1287148Y1057520D02*
X1287172Y1057511D01*
G01Y1062511D02*
X1287183Y1062496D01*
G01X1287148Y1062520D02*
X1287172Y1062511D01*
G01Y1067511D02*
X1287183Y1067496D01*
G01X1287148Y1067520D02*
X1287172Y1067511D01*
G01Y1072511D02*
X1287183Y1072496D01*
G01X1287148Y1072520D02*
X1287172Y1072511D01*
G01Y1077511D02*
X1287183Y1077496D01*
G01X1287148Y1077520D02*
X1287172Y1077511D01*
G01Y1082511D02*
X1287183Y1082496D01*
G01X1287148Y1082520D02*
X1287172Y1082511D01*
G01X1286201Y1047527D02*
Y1047536D01*
G01X1286202Y1047521D02*
X1286201Y1047527D01*
G01X1286202Y1047520D02*
Y1047521D01*
G01X1286201Y1052527D02*
Y1052536D01*
G01X1286202Y1052521D02*
X1286201Y1052527D01*
G01X1286202Y1052520D02*
Y1052521D01*
G01X1286201Y1057527D02*
Y1057536D01*
G01X1286202Y1057521D02*
X1286201Y1057527D01*
G01X1286202Y1057520D02*
Y1057521D01*
G01X1286201Y1062527D02*
Y1062536D01*
G01X1286202Y1062521D02*
X1286201Y1062527D01*
G01X1286202Y1062520D02*
Y1062521D01*
G01X1286201Y1067527D02*
Y1067536D01*
G01X1286202Y1067521D02*
X1286201Y1067527D01*
G01X1286202Y1067520D02*
Y1067521D01*
G01X1286201Y1072527D02*
Y1072536D01*
G01X1286202Y1072521D02*
X1286201Y1072527D01*
G01X1286202Y1072520D02*
Y1072521D01*
G01X1286201Y1077527D02*
Y1077536D01*
G01X1286202Y1077521D02*
X1286201Y1077527D01*
G01X1286202Y1077520D02*
Y1077521D01*
G01X1286201Y1082527D02*
Y1082536D01*
G01X1286202Y1082521D02*
X1286201Y1082527D01*
G01X1286202Y1082520D02*
Y1082521D01*
G01X1287177Y1047663D02*
X1287185Y1047637D01*
G01X1287167Y1047690D02*
X1287177Y1047663D01*
G01X1287156Y1047717D02*
X1287167Y1047690D01*
G01X1287177Y1052663D02*
X1287185Y1052637D01*
G01X1287167Y1052690D02*
X1287177Y1052663D01*
G01X1287156Y1052717D02*
X1287167Y1052690D01*
G01X1287177Y1057663D02*
X1287185Y1057637D01*
G01X1287167Y1057690D02*
X1287177Y1057663D01*
G01X1287156Y1057717D02*
X1287167Y1057690D01*
G01X1287177Y1062663D02*
X1287185Y1062637D01*
G01X1287167Y1062690D02*
X1287177Y1062663D01*
G01X1287156Y1062717D02*
X1287167Y1062690D01*
G01X1287177Y1067663D02*
X1287185Y1067637D01*
G01X1287167Y1067690D02*
X1287177Y1067663D01*
G01X1287156Y1067717D02*
X1287167Y1067690D01*
G01X1287177Y1072663D02*
X1287185Y1072637D01*
G01X1287167Y1072690D02*
X1287177Y1072663D01*
G01X1287156Y1072717D02*
X1287167Y1072690D01*
G01X1287177Y1077663D02*
X1287185Y1077637D01*
G01X1287167Y1077690D02*
X1287177Y1077663D01*
G01X1287156Y1077717D02*
X1287167Y1077690D01*
G01X1287177Y1082663D02*
X1287185Y1082637D01*
G01X1287167Y1082690D02*
X1287177Y1082663D01*
G01X1287156Y1082717D02*
X1287167Y1082690D01*
G01X1287168Y1052515D02*
X1287148Y1052520D01*
G01X1287182Y1052500D02*
X1287168Y1052515D01*
G01X1287187Y1052480D02*
X1287182Y1052500D01*
G01X1287168Y1057515D02*
X1287148Y1057520D01*
G01X1287182Y1057500D02*
X1287168Y1057515D01*
G01X1287187Y1057480D02*
X1287182Y1057500D01*
G01X1287168Y1062515D02*
X1287148Y1062520D01*
G01X1287182Y1062500D02*
X1287168Y1062515D01*
G01X1287187Y1062480D02*
X1287182Y1062500D01*
G01X1287168Y1067515D02*
X1287148Y1067520D01*
G01X1287182Y1067500D02*
X1287168Y1067515D01*
G01X1287187Y1067480D02*
X1287182Y1067500D01*
G01X1287168Y1072515D02*
X1287148Y1072520D01*
G01X1287182Y1072500D02*
X1287168Y1072515D01*
G01X1287187Y1072480D02*
X1287182Y1072500D01*
G01X1287168Y1077515D02*
X1287148Y1077520D01*
G01X1287182Y1077500D02*
X1287168Y1077515D01*
G01X1287187Y1077480D02*
X1287182Y1077500D01*
G01X1287168Y1082515D02*
X1287148Y1082520D01*
G01X1287182Y1082500D02*
X1287168Y1082515D01*
G01X1287187Y1082480D02*
X1287182Y1082500D01*
G01X1287185Y1047487D02*
Y1047494D01*
G01Y1052487D02*
Y1052494D01*
G01X1287186Y1052482D02*
X1287185Y1052487D01*
G01X1287187Y1052480D02*
X1287186Y1052482D01*
G01X1287185Y1057487D02*
Y1057494D01*
G01X1287186Y1057482D02*
X1287185Y1057487D01*
G01X1287187Y1057480D02*
X1287186Y1057482D01*
G01X1287185Y1062487D02*
Y1062494D01*
G01X1287186Y1062482D02*
X1287185Y1062487D01*
G01X1287187Y1062480D02*
X1287186Y1062482D01*
G01X1287185Y1067487D02*
Y1067494D01*
G01X1287186Y1067482D02*
X1287185Y1067487D01*
G01X1287187Y1067480D02*
X1287186Y1067482D01*
G01X1287185Y1072487D02*
Y1072494D01*
G01X1287186Y1072482D02*
X1287185Y1072487D01*
G01X1287187Y1072480D02*
X1287186Y1072482D01*
G01X1287185Y1077487D02*
Y1077494D01*
G01X1287186Y1077482D02*
X1287185Y1077487D01*
G01X1287187Y1077480D02*
X1287186Y1077482D01*
G01X1287185Y1082487D02*
Y1082494D01*
G01X1287186Y1082482D02*
X1287185Y1082487D01*
G01X1287187Y1082480D02*
X1287186Y1082482D01*
G01X1284965Y1170224D02*
G03X1318775I16905J-13531D01*
G01X1284965D02*
G03X1318776I16906J-13531D01*
G01X1285630Y1108012D02*
G03X1285039Y1108602I-590J0D01*
G01X1278346D02*
G03X1277756Y1108012I0J-590D01*
G01X1280512Y1106831D02*
G03Y1104862I0J-985D01*
G01X1282874D02*
G03Y1106831I0J984D01*
G01X1279134Y1098917D02*
G03X1277953Y1097736I0J-1181D01*
G01X1285433D02*
G03X1284252Y1098917I-1181J0D01*
G01X1283583Y1093642D02*
G03I-1890J0D01*
G01X1292520Y1107421D02*
G03X1290551Y1109390I-1969J0D01*
G01X1272835D02*
G03X1270866Y1107421I0J-1969D01*
G01X1284055Y1093642D02*
G03I-2362J0D01*
G01X1280512Y1094232D02*
X1278202Y1098461D01*
G01X1282874Y1092539D02*
X1284178Y1090571D01*
G01X1275984Y1086831D02*
X1277165Y1085650D01*
G01X1270866Y1091673D02*
X1274213Y1088327D01*
G01X1290551Y1109390D02*
X1272835D01*
G01X1285039Y1108602D02*
X1278346D01*
G01X1282874Y1106831D02*
X1280512D01*
G01Y1104862D02*
X1282874D01*
G01X1285630Y1103484D02*
X1277756D01*
G01Y1101909D02*
X1285630D01*
G01X1292520Y1098957D02*
X1270866D01*
G01X1279134Y1098917D02*
X1284252D01*
G01X1280512Y1094232D02*
X1282874D01*
G01X1280512Y1092539D02*
X1282874D01*
G01X1274213Y1090571D02*
X1288583D01*
G01X1274213Y1089193D02*
X1277953D01*
G01X1288583D02*
X1285433D01*
G01X1274213Y1088327D02*
X1289173D01*
G01X1275984Y1086831D02*
X1283858D01*
G01X1277165Y1085650D02*
X1282677D01*
G01X1287185Y1083012D02*
X1286201D01*
G01X1286202Y1082520D02*
X1291535D01*
G01Y1082480D02*
X1287187D01*
G01X1291535Y1081142D02*
X1286202D01*
G01X1286201Y1080650D02*
X1287185D01*
G01Y1078012D02*
X1286201D01*
G01X1286202Y1077520D02*
X1291535D01*
G01Y1077480D02*
X1287187D01*
G01X1291535Y1076142D02*
X1286202D01*
G01X1286201Y1075650D02*
X1287185D01*
G01Y1073012D02*
X1286201D01*
G01X1286202Y1072520D02*
X1291535D01*
G01Y1072480D02*
X1287187D01*
G01X1291535Y1071142D02*
X1286202D01*
G01X1286201Y1070650D02*
X1287185D01*
G01Y1068012D02*
X1286201D01*
G01X1286202Y1067520D02*
X1291535D01*
G01Y1067480D02*
X1287187D01*
G01X1291535Y1066142D02*
X1286202D01*
G01X1286201Y1065650D02*
X1287185D01*
G01Y1063012D02*
X1286201D01*
G01X1286202Y1062520D02*
X1291535D01*
G01Y1062480D02*
X1287187D01*
G01X1291535Y1061142D02*
X1286202D01*
G01X1286201Y1060650D02*
X1287185D01*
G01Y1058012D02*
X1286201D01*
G01X1286202Y1057520D02*
X1291535D01*
G01Y1057480D02*
X1287187D01*
G01X1291535Y1056142D02*
X1286202D01*
G01X1286201Y1055650D02*
X1287185D01*
G01Y1053012D02*
X1286201D01*
G01X1286202Y1052520D02*
X1291535D01*
G01Y1052480D02*
X1287187D01*
G01X1291535Y1051142D02*
X1286202D01*
G01X1286201Y1050650D02*
X1287185D01*
G01Y1048012D02*
X1286201D01*
G01X1286202Y1047520D02*
X1291535D01*
G01Y1047480D02*
X1287187D01*
G01X1286201Y1082715D02*
X1287156Y1082717D01*
G01X1287185Y1080946D02*
X1286201Y1080945D01*
G01Y1077715D02*
X1287156Y1077717D01*
G01X1287185Y1075946D02*
X1286201Y1075945D01*
G01Y1072715D02*
X1287156Y1072717D01*
G01X1287185Y1070946D02*
X1286201Y1070945D01*
G01Y1067715D02*
X1287156Y1067717D01*
G01X1287185Y1065946D02*
X1286201Y1065945D01*
G01Y1062715D02*
X1287156Y1062717D01*
G01X1287185Y1060946D02*
X1286201Y1060945D01*
G01Y1057715D02*
X1287156Y1057717D01*
G01X1287185Y1055946D02*
X1286201Y1055945D01*
G01Y1052715D02*
X1287156Y1052717D01*
G01X1287185Y1050946D02*
X1286201Y1050945D01*
G01Y1047715D02*
X1287156Y1047717D01*
G01X1287185Y1047494D02*
Y1047502D01*
G01Y1052494D02*
Y1052502D01*
G01Y1057494D02*
Y1057502D01*
G01Y1062494D02*
Y1062502D01*
G01Y1067494D02*
Y1067502D01*
G01Y1072494D02*
Y1072502D01*
G01Y1077494D02*
Y1077502D01*
G01Y1082494D02*
Y1082502D01*
G01X1292520Y1091673D02*
Y1107421D01*
G01X1291535Y1081142D02*
Y1082520D01*
G01Y1076142D02*
Y1077520D01*
G01Y1071142D02*
Y1072520D01*
G01Y1066142D02*
Y1067520D01*
G01Y1061142D02*
Y1062520D01*
G01Y1056142D02*
Y1057520D01*
G01Y1051142D02*
Y1052520D01*
G01X1288366D02*
Y1051142D01*
G01Y1057520D02*
Y1056142D01*
G01Y1062520D02*
Y1061142D01*
G01Y1067520D02*
Y1066142D01*
G01Y1072520D02*
Y1071142D01*
G01Y1077520D02*
Y1076142D01*
G01Y1082520D02*
Y1081142D01*
G01X1287185Y1080650D02*
Y1083012D01*
G01Y1075650D02*
Y1078012D01*
G01Y1070650D02*
Y1073012D01*
G01Y1065650D02*
Y1068012D01*
G01Y1060650D02*
Y1063012D01*
G01Y1055650D02*
Y1058012D01*
G01Y1050650D02*
Y1053012D01*
G01Y1047494D02*
Y1047637D01*
G01Y1052494D02*
Y1052637D01*
G01Y1057494D02*
Y1057637D01*
G01Y1062494D02*
Y1062637D01*
G01Y1067494D02*
Y1067637D01*
G01Y1072494D02*
Y1072637D01*
G01Y1077494D02*
Y1077637D01*
G01Y1082494D02*
Y1082637D01*
G01X1286201Y1053012D02*
Y1050650D01*
G01Y1058012D02*
Y1055650D01*
G01Y1063012D02*
Y1060650D01*
G01Y1068012D02*
Y1065650D01*
G01Y1073012D02*
Y1070650D01*
G01Y1078012D02*
Y1075650D01*
G01Y1083012D02*
Y1080650D01*
G01X1285630Y1101909D02*
Y1108012D01*
G01X1285433Y1097736D02*
Y1089193D01*
G01X1282874Y1094232D02*
Y1092539D01*
G01X1280512D02*
Y1094232D01*
G01X1277953Y1089193D02*
Y1097736D01*
G01X1277756Y1101909D02*
Y1108012D01*
G01X1270866Y1107421D02*
Y1091673D01*
G01X1285184Y1098461D02*
X1282874Y1094232D01*
G01X1279208Y1090571D02*
X1280512Y1092539D01*
G01X1292520Y1091673D02*
X1289173Y1088327D01*
G01X1282677Y1085650D02*
X1283858Y1086831D01*
G01X1311851Y1183355D02*
G03X1318775Y1170224I37663J11469D01*
G01X1311851Y1183355D02*
G03X1291890I-9980J-3040D01*
G01X1284965Y1170224D02*
G03X1291890Y1183355I-30737J24602D01*
G01X1311850D02*
G03X1291890I-9980J-3040D01*
G01X1311850D02*
G03X1318776Y1170224I37661J11473D01*
G01X1284965D02*
G03X1291890Y1183355I-30737J24602D01*
G01X1244685Y1515748D02*
Y1509055D01*
G01X1248622Y1519685D02*
G03X1244685Y1515748I0J-3937D01*
G01X1427953Y1519685D02*
X1248622D01*
G01X1314961Y1494280D02*
G03Y1497059I0J1389D01*
G01Y1492575D02*
G03Y1498764I0J3094D01*
G01X1248622Y1519685D02*
G03X1244685Y1515748I0J-3937D01*
G01X1316221Y1491732D02*
G03Y1499606I-1260J3937D01*
G01X1319094Y1491732D02*
G03Y1499606I-4134J3937D01*
G01X1297244Y1526772D02*
X1307874Y1516929D01*
G01D02*
X1297244Y1521654D01*
G01X1331496Y1523622D02*
X1364567D01*
G01X1293701D02*
X1327559D01*
G01X1297244Y1521654D02*
X1293701D01*
G01X1331496Y1520210D02*
X1314961D01*
G01X1427953Y1519685D02*
X1248622D01*
G01X1331496Y1518110D02*
X1364567D01*
G01X1388189Y1516929D02*
X1307874D01*
G01X1293701Y1523622D02*
X1304331Y1510954D01*
G01X1388189Y1512992D02*
X1307874D01*
G01X1331496Y1512598D02*
X1364567D01*
G01X1302951D02*
X1302717D01*
G01X1335433Y1510954D02*
X1346063D01*
G01X1304331D02*
X1327559D01*
G01Y1509843D02*
X1368504D01*
G01X1329429Y1505512D02*
X1333563D01*
G01X1312894D02*
X1317028D01*
G01X1331496Y1505210D02*
X1335433D01*
G01X1319094Y1499606D02*
X1314961D01*
G01X1293701Y1492913D02*
X1304331D01*
G01X1319094Y1491732D02*
X1314961D01*
G01X1322047Y1485827D02*
X1307874D01*
G01X1338583D02*
X1324409D01*
G01X1302717Y1471260D02*
X1391732D01*
G01X1317028Y1469783D02*
X1312894D01*
G01X1333563D02*
X1329429D01*
G01X1317028Y1468996D02*
X1312894D01*
G01X1333563D02*
X1329429D01*
G01X1317028Y1464862D02*
X1312894D01*
G01X1333563D02*
X1329429D01*
G01X1317028Y1448130D02*
X1312894D01*
G01X1333563D02*
X1329429D01*
G01X1317028Y1447343D02*
X1312894D01*
G01X1333563D02*
X1329429D01*
G01X1317028Y1443209D02*
X1312894D01*
G01X1333563D02*
X1329429D01*
G01X1338583Y1485827D02*
Y1512992D01*
G01X1335433Y1523622D02*
Y1505210D01*
G01X1334646Y1485827D02*
Y1512992D01*
G01X1333563Y1443209D02*
Y1471260D01*
G01Y1505512D02*
Y1485827D01*
G01X1331496Y1505210D02*
Y1526772D01*
G01X1329429Y1471260D02*
Y1443209D01*
G01Y1505512D02*
Y1485827D01*
G01X1328346D02*
Y1512992D01*
G01X1327559Y1509843D02*
Y1523622D01*
G01X1324409Y1485827D02*
Y1512992D01*
G01X1322047Y1485827D02*
Y1512992D01*
G01X1318110Y1485827D02*
Y1512992D01*
G01X1317028Y1443209D02*
Y1471260D01*
G01Y1505512D02*
Y1485827D01*
G01X1314961Y1492574D02*
Y1494279D01*
G01Y1510954D02*
Y1526772D01*
G01Y1499606D02*
Y1491732D01*
G01Y1497059D02*
Y1498764D01*
G01X1312894Y1471260D02*
Y1443209D01*
G01Y1505512D02*
Y1485827D01*
G01X1312598Y1523622D02*
Y1471260D01*
G01X1311811Y1485827D02*
Y1512992D01*
G01X1309094Y1523622D02*
Y1471260D01*
G01X1307874Y1516929D02*
Y1485827D01*
G01X1304331Y1510954D02*
Y1471260D01*
G01X1304291Y1511001D02*
Y1471260D01*
G01X1302717Y1512598D02*
Y1471260D01*
G01X1297244Y1526772D02*
Y1521654D01*
G01X1295394Y1519685D02*
Y1521604D01*
G01X1293701Y1526772D02*
Y1492913D01*
G01X1244685Y1515748D02*
Y1509055D01*
G01X1293701Y1526772D02*
X1402362D01*
G01X1356944Y-369410D02*
Y-388347D01*
G01X1396991Y84941D02*
X1396986Y84921D01*
G01X1397006Y84955D02*
X1396991Y84941D01*
G01X1397025Y84961D02*
X1397006Y84955D01*
G01X1396991Y88091D02*
X1396986Y88071D01*
G01X1397006Y88105D02*
X1396991Y88091D01*
G01X1397025Y88110D02*
X1397006Y88105D01*
G01X1396991Y91240D02*
X1396986Y91220D01*
G01X1397006Y91254D02*
X1396991Y91240D01*
G01X1397025Y91260D02*
X1397006Y91254D01*
G01X1397966Y83799D02*
X1397971Y83819D01*
G01X1397951Y83785D02*
X1397966Y83799D01*
G01X1397931Y83780D02*
X1397951Y83785D01*
G01X1397966Y86949D02*
X1397971Y86969D01*
G01X1397951Y86934D02*
X1397966Y86949D01*
G01X1397931Y86929D02*
X1397951Y86934D01*
G01X1397966Y90098D02*
X1397971Y90118D01*
G01X1397951Y90084D02*
X1397966Y90098D01*
G01X1397931Y90079D02*
X1397951Y90084D01*
G01X1397966Y93248D02*
X1397971Y93268D01*
G01X1397951Y93233D02*
X1397966Y93248D01*
G01X1397931Y93228D02*
X1397951Y93233D01*
G01X1397950Y83772D02*
X1397953Y83774D01*
G01X1397947Y83770D02*
X1397950Y83772D01*
G01X1397944Y83770D02*
X1397947D01*
G01X1397940Y83769D02*
X1397944Y83770D01*
G01X1397937Y83769D02*
X1397940D01*
G01X1397933Y83768D02*
X1397937Y83769D01*
G01X1397011Y84968D02*
X1397007Y84967D01*
G01X1397014Y84969D02*
X1397011Y84968D01*
G01X1397017Y84970D02*
X1397014Y84969D01*
G01X1397020Y84971D02*
X1397017Y84970D01*
G01X1397024Y84972D02*
X1397020Y84971D01*
G01X1397028Y84972D02*
X1397024D01*
G01X1397950Y86921D02*
X1397953Y86923D01*
G01X1397947Y86920D02*
X1397950Y86921D01*
G01X1397944Y86919D02*
X1397947Y86920D01*
G01X1397940Y86919D02*
X1397944D01*
G01X1397937Y86918D02*
X1397940Y86919D01*
G01X1397933Y86918D02*
X1397937D01*
G01X1397011Y88118D02*
X1397007Y88116D01*
G01X1397014Y88119D02*
X1397011Y88118D01*
G01X1397017Y88120D02*
X1397014Y88119D01*
G01X1397020Y88121D02*
X1397017Y88120D01*
G01X1397024Y88121D02*
X1397020D01*
G01X1397028D02*
X1397024D01*
G01X1397950Y90071D02*
X1397953Y90073D01*
G01X1397947Y90070D02*
X1397950Y90071D01*
G01X1397944Y90069D02*
X1397947Y90070D01*
G01X1397940Y90068D02*
X1397944Y90069D01*
G01X1397937Y90068D02*
X1397940D01*
G01X1397933Y90067D02*
X1397937Y90068D01*
G01X1397011Y91267D02*
X1397007Y91266D01*
G01X1397014Y91269D02*
X1397011Y91267D01*
G01X1397017Y91270D02*
X1397014Y91269D01*
G01X1397020Y91270D02*
X1397017D01*
G01X1397024Y91271D02*
X1397020Y91270D01*
G01X1397028Y91271D02*
X1397024D01*
G01X1397950Y93220D02*
X1397953Y93222D01*
G01X1397947Y93219D02*
X1397950Y93220D01*
G01X1397944Y93219D02*
X1397947D01*
G01X1397940Y93218D02*
X1397944Y93219D01*
G01X1397937Y93217D02*
X1397940Y93218D01*
G01X1397933Y93217D02*
X1397937D01*
G01X1397963Y84959D02*
X1397967Y84954D01*
G01X1397958Y84963D02*
X1397963Y84959D01*
G01X1397952Y84967D02*
X1397958Y84963D01*
G01X1397946Y84970D02*
X1397952Y84967D01*
G01X1397940Y84971D02*
X1397946Y84970D01*
G01X1397933Y84972D02*
X1397940Y84971D01*
G01X1397963Y88109D02*
X1397967Y88103D01*
G01X1397958Y88113D02*
X1397963Y88109D01*
G01X1397952Y88117D02*
X1397958Y88113D01*
G01X1397946Y88119D02*
X1397952Y88117D01*
G01X1397940Y88121D02*
X1397946Y88119D01*
G01X1397933Y88121D02*
X1397940D01*
G01X1397963Y91258D02*
X1397967Y91253D01*
G01X1397958Y91263D02*
X1397963Y91258D01*
G01X1397952Y91266D02*
X1397958Y91263D01*
G01X1397946Y91269D02*
X1397952Y91266D01*
G01X1397940Y91270D02*
X1397946Y91269D01*
G01X1397933Y91271D02*
X1397940Y91270D01*
G01X1396989Y83798D02*
X1396988Y83805D01*
G01X1396991Y83791D02*
X1396989Y83798D01*
G01X1396995Y83785D02*
X1396991Y83791D01*
G01X1397000Y83779D02*
X1396995Y83785D01*
G01X1397006Y83774D02*
X1397000Y83779D01*
G01X1397013Y83771D02*
X1397006Y83774D01*
G01X1397020Y83769D02*
X1397013Y83771D01*
G01X1397028Y83768D02*
X1397020Y83769D01*
G01X1396989Y86948D02*
X1396988Y86955D01*
G01X1396991Y86941D02*
X1396989Y86948D01*
G01X1396995Y86934D02*
X1396991Y86941D01*
G01X1397000Y86929D02*
X1396995Y86934D01*
G01X1397006Y86924D02*
X1397000Y86929D01*
G01X1397013Y86920D02*
X1397006Y86924D01*
G01X1397020Y86919D02*
X1397013Y86920D01*
G01X1397028Y86918D02*
X1397020Y86919D01*
G01X1396989Y90097D02*
X1396988Y90104D01*
G01X1396991Y90090D02*
X1396989Y90097D01*
G01X1396995Y90084D02*
X1396991Y90090D01*
G01X1397000Y90078D02*
X1396995Y90084D01*
G01X1397006Y90074D02*
X1397000Y90078D01*
G01X1397013Y90070D02*
X1397006Y90074D01*
G01X1397020Y90068D02*
X1397013Y90070D01*
G01X1397028Y90067D02*
X1397020Y90068D01*
G01X1396989Y93247D02*
X1396988Y93254D01*
G01X1396991Y93240D02*
X1396989Y93247D01*
G01X1396995Y93233D02*
X1396991Y93240D01*
G01X1397000Y93228D02*
X1396995Y93233D01*
G01X1397006Y93223D02*
X1397000Y93228D01*
G01X1397013Y93220D02*
X1397006Y93223D01*
G01X1397020Y93218D02*
X1397013Y93220D01*
G01X1397028Y93217D02*
X1397020Y93218D01*
G01X1397942Y84959D02*
X1397952Y84955D01*
G01X1397931Y84961D02*
X1397942Y84959D01*
G01Y88109D02*
X1397952Y88105D01*
G01X1397931Y88110D02*
X1397942Y88109D01*
G01Y91258D02*
X1397952Y91254D01*
G01X1397931Y91260D02*
X1397942Y91258D01*
G01X1396988Y86959D02*
Y86955D01*
G01X1396990Y86952D02*
X1396988Y86959D01*
G01X1397002Y86937D02*
X1396990Y86952D01*
G01X1397026Y86929D02*
X1397002Y86937D01*
G01X1396988Y90108D02*
Y90104D01*
G01X1396990Y90102D02*
X1396988Y90108D01*
G01X1397001Y90087D02*
X1396990Y90102D01*
G01X1397026Y90079D02*
X1397001Y90087D01*
G01X1396988Y83809D02*
Y83806D01*
G01X1396990Y83803D02*
X1396988Y83809D01*
G01X1397001Y83788D02*
X1396990Y83803D01*
G01X1397026Y83780D02*
X1397001Y83788D01*
G01X1411385Y51999D02*
X1411396Y51984D01*
G01X1411361Y52008D02*
X1411385Y51999D01*
G01Y56999D02*
X1411396Y56984D01*
G01X1411361Y57008D02*
X1411385Y56999D01*
G01Y61999D02*
X1411396Y61984D01*
G01X1411361Y62008D02*
X1411385Y61999D01*
G01Y66999D02*
X1411396Y66984D01*
G01X1411361Y67008D02*
X1411385Y66999D01*
G01Y71999D02*
X1411396Y71984D01*
G01X1411361Y72008D02*
X1411385Y71999D01*
G01Y76999D02*
X1411396Y76984D01*
G01X1411361Y77008D02*
X1411385Y76999D01*
G01Y81999D02*
X1411396Y81984D01*
G01X1411361Y82008D02*
X1411385Y81999D01*
G01X1396988Y93258D02*
Y93254D01*
G01X1396990Y93252D02*
X1396988Y93258D01*
G01X1397000Y93238D02*
X1396990Y93252D01*
G01X1397023Y93228D02*
X1397000Y93238D01*
G01X1397941Y84959D02*
X1397931Y84961D01*
G01X1397950Y84956D02*
X1397941Y84959D01*
G01X1397957Y84951D02*
X1397950Y84956D01*
G01X1397941Y91259D02*
X1397931Y91260D01*
G01X1397950Y91256D02*
X1397941Y91259D01*
G01X1397957Y91250D02*
X1397950Y91256D01*
G01X1397941Y88109D02*
X1397931Y88110D01*
G01X1397950Y88106D02*
X1397941Y88109D01*
G01X1397957Y88100D02*
X1397950Y88106D01*
G01X1397027Y83774D02*
X1397028Y83768D01*
G01X1397026Y83778D02*
X1397027Y83774D01*
G01X1397025Y83780D02*
X1397026Y83778D01*
G01X1397027Y86924D02*
X1397028Y86918D01*
G01X1397026Y86928D02*
X1397027Y86924D01*
G01X1397025Y86929D02*
X1397026Y86928D01*
G01X1397027Y90074D02*
X1397028Y90067D01*
G01X1397026Y90078D02*
X1397027Y90074D01*
G01X1397025Y90079D02*
X1397026Y90078D01*
G01X1397027Y93223D02*
X1397028Y93217D01*
G01X1397026Y93227D02*
X1397027Y93223D01*
G01X1397025Y93228D02*
X1397026Y93227D01*
G01X1411398Y51975D02*
Y51982D01*
G01X1411399Y51970D02*
X1411398Y51975D01*
G01X1411400Y51969D02*
X1411399Y51970D01*
G01X1411398Y56975D02*
Y56982D01*
G01X1411399Y56970D02*
X1411398Y56975D01*
G01X1411400Y56969D02*
X1411399Y56970D01*
G01X1411398Y61975D02*
Y61982D01*
G01X1411399Y61970D02*
X1411398Y61975D01*
G01X1411400Y61969D02*
X1411399Y61970D01*
G01X1411398Y66975D02*
Y66982D01*
G01X1411399Y66970D02*
X1411398Y66975D01*
G01X1411400Y66969D02*
X1411399Y66970D01*
G01X1411398Y71975D02*
Y71982D01*
G01X1411399Y71970D02*
X1411398Y71975D01*
G01X1411400Y71969D02*
X1411399Y71970D01*
G01X1411398Y76975D02*
Y76982D01*
G01X1411399Y76970D02*
X1411398Y76975D01*
G01X1411400Y76969D02*
X1411399Y76970D01*
G01X1411398Y81975D02*
Y81982D01*
G01X1411399Y81970D02*
X1411398Y81975D01*
G01X1411400Y81969D02*
X1411399Y81970D01*
G01X1397011Y86931D02*
X1397025Y86929D01*
G01X1397000Y86939D02*
X1397011Y86931D01*
G01X1396987Y86957D02*
X1397000Y86939D01*
G01X1397011Y90081D02*
X1397025Y90079D01*
G01X1396998Y90089D02*
X1397011Y90081D01*
G01X1396987Y90109D02*
X1396998Y90089D01*
G01X1397972Y83813D02*
Y83805D01*
G01Y83817D02*
Y83813D01*
G01X1397971Y83819D02*
X1397972Y83817D01*
G01Y86963D02*
Y86955D01*
G01Y86967D02*
Y86963D01*
G01X1397971Y86969D02*
X1397972Y86967D01*
G01Y90112D02*
Y90104D01*
G01Y90117D02*
Y90112D01*
G01X1397971Y90118D02*
X1397972Y90117D01*
G01Y93262D02*
Y93254D01*
G01Y93266D02*
Y93262D01*
G01X1397971Y93268D02*
X1397972Y93266D01*
G01X1397010Y83782D02*
X1397025Y83780D01*
G01X1396997Y83791D02*
X1397010Y83782D01*
G01X1396987Y83811D02*
X1396997Y83791D01*
G01X1397972Y84941D02*
Y84935D01*
G01X1397970Y84948D02*
X1397972Y84941D01*
G01X1397967Y84954D02*
X1397970Y84948D01*
G01X1397972Y88091D02*
Y88084D01*
G01X1397970Y88097D02*
X1397972Y88091D01*
G01X1397967Y88103D02*
X1397970Y88097D01*
G01X1397972Y91241D02*
Y91234D01*
G01X1397970Y91247D02*
X1397972Y91241D01*
G01X1397967Y91253D02*
X1397970Y91247D01*
G01X1397933Y83774D02*
X1397934Y83768D01*
G01X1397932Y83778D02*
X1397933Y83774D01*
G01X1397931Y83780D02*
X1397932Y83778D01*
G01X1397933Y86924D02*
X1397934Y86918D01*
G01X1397932Y86928D02*
X1397933Y86924D01*
G01X1397931Y86929D02*
X1397932Y86928D01*
G01X1397933Y90074D02*
X1397934Y90067D01*
G01X1397932Y90077D02*
X1397933Y90074D01*
G01X1397931Y90079D02*
X1397932Y90077D01*
G01X1397933Y93223D02*
X1397934Y93217D01*
G01X1397932Y93227D02*
X1397933Y93223D01*
G01X1397931Y93228D02*
X1397932Y93227D01*
G01X1410413Y52015D02*
Y52024D01*
G01X1410414Y52009D02*
X1410413Y52015D01*
G01X1410415Y52008D02*
X1410414Y52009D01*
G01X1410413Y57015D02*
Y57024D01*
G01X1410414Y57009D02*
X1410413Y57015D01*
G01X1410415Y57008D02*
X1410414Y57009D01*
G01X1410413Y62015D02*
Y62024D01*
G01X1410414Y62009D02*
X1410413Y62015D01*
G01X1410415Y62008D02*
X1410414Y62009D01*
G01X1410413Y67015D02*
Y67024D01*
G01X1410414Y67009D02*
X1410413Y67015D01*
G01X1410415Y67008D02*
X1410414Y67009D01*
G01X1410413Y72015D02*
Y72024D01*
G01X1410414Y72009D02*
X1410413Y72015D01*
G01X1410415Y72008D02*
X1410414Y72009D01*
G01X1410413Y77015D02*
Y77024D01*
G01X1410414Y77009D02*
X1410413Y77015D01*
G01X1410415Y77008D02*
X1410414Y77009D01*
G01X1410413Y82015D02*
Y82024D01*
G01X1410414Y82009D02*
X1410413Y82015D01*
G01X1410415Y82008D02*
X1410414Y82009D01*
G01X1411390Y52152D02*
X1411398Y52125D01*
G01X1411380Y52178D02*
X1411390Y52152D01*
G01X1411369Y52205D02*
X1411380Y52178D01*
G01X1411390Y57152D02*
X1411398Y57125D01*
G01X1411380Y57178D02*
X1411390Y57152D01*
G01X1411369Y57205D02*
X1411380Y57178D01*
G01X1411390Y62152D02*
X1411398Y62125D01*
G01X1411380Y62178D02*
X1411390Y62152D01*
G01X1411369Y62205D02*
X1411380Y62178D01*
G01X1411390Y67152D02*
X1411398Y67125D01*
G01X1411380Y67178D02*
X1411390Y67152D01*
G01X1411369Y67205D02*
X1411380Y67178D01*
G01X1411390Y72152D02*
X1411398Y72125D01*
G01X1411380Y72178D02*
X1411390Y72152D01*
G01X1411369Y72205D02*
X1411380Y72178D01*
G01X1411390Y77152D02*
X1411398Y77125D01*
G01X1411380Y77178D02*
X1411390Y77152D01*
G01X1411369Y77205D02*
X1411380Y77178D01*
G01X1411390Y82152D02*
X1411398Y82125D01*
G01X1411380Y82178D02*
X1411390Y82152D01*
G01X1411369Y82205D02*
X1411380Y82178D01*
G01X1397006Y93233D02*
X1397025Y93228D01*
G01X1396993Y93246D02*
X1397006Y93233D01*
G01X1396986Y93263D02*
X1396993Y93246D01*
G01X1411380Y52003D02*
X1411361Y52008D01*
G01X1411395Y51988D02*
X1411380Y52003D01*
G01X1411400Y51969D02*
X1411395Y51988D01*
G01X1411380Y57003D02*
X1411361Y57008D01*
G01X1411395Y56988D02*
X1411380Y57003D01*
G01X1411400Y56969D02*
X1411395Y56988D01*
G01X1411380Y62003D02*
X1411361Y62008D01*
G01X1411395Y61988D02*
X1411380Y62003D01*
G01X1411400Y61969D02*
X1411395Y61988D01*
G01X1411380Y67003D02*
X1411361Y67008D01*
G01X1411395Y66988D02*
X1411380Y67003D01*
G01X1411400Y66969D02*
X1411395Y66988D01*
G01X1411380Y72003D02*
X1411361Y72008D01*
G01X1411395Y71988D02*
X1411380Y72003D01*
G01X1411400Y71969D02*
X1411395Y71988D01*
G01X1411380Y77003D02*
X1411361Y77008D01*
G01X1411395Y76988D02*
X1411380Y77003D01*
G01X1411400Y76969D02*
X1411395Y76988D01*
G01X1411380Y82003D02*
X1411361Y82008D01*
G01X1411395Y81988D02*
X1411380Y82003D01*
G01X1411400Y81969D02*
X1411395Y81988D01*
G01X1397965Y91242D02*
X1397957Y91250D01*
G01X1397970Y91231D02*
X1397965Y91242D01*
G01X1397971Y91220D02*
X1397970Y91231D01*
G01X1397965Y84943D02*
X1397957Y84951D01*
G01X1397970Y84932D02*
X1397965Y84943D01*
G01X1397971Y84921D02*
X1397970Y84932D01*
G01X1397965Y88092D02*
X1397957Y88100D01*
G01X1397970Y88082D02*
X1397965Y88092D01*
G01X1397971Y88071D02*
X1397970Y88082D01*
G01X1411365Y52106D02*
X1411369Y52205D01*
G01X1411359Y52034D02*
X1411365Y52106D01*
G01X1411361Y52008D02*
X1411359Y52034D01*
G01X1411365Y57106D02*
X1411369Y57205D01*
G01X1411359Y57034D02*
X1411365Y57106D01*
G01X1411361Y57008D02*
X1411359Y57034D01*
G01X1411365Y62106D02*
X1411369Y62205D01*
G01X1411359Y62034D02*
X1411365Y62106D01*
G01X1411361Y62008D02*
X1411359Y62034D01*
G01X1411365Y67106D02*
X1411369Y67205D01*
G01X1411359Y67034D02*
X1411365Y67106D01*
G01X1411361Y67008D02*
X1411359Y67034D01*
G01X1411365Y72106D02*
X1411369Y72205D01*
G01X1411359Y72034D02*
X1411365Y72106D01*
G01X1411361Y72008D02*
X1411359Y72034D01*
G01X1411365Y77106D02*
X1411369Y77205D01*
G01X1411359Y77034D02*
X1411365Y77106D01*
G01X1411361Y77008D02*
X1411359Y77034D01*
G01X1411365Y82106D02*
X1411369Y82205D01*
G01X1411359Y82034D02*
X1411365Y82106D01*
G01X1411361Y82008D02*
X1411359Y82034D01*
G01X1397028Y91444D02*
Y91457D01*
G01X1397025Y91431D02*
X1397028Y91444D01*
G01X1397025Y91417D02*
Y91431D01*
G01X1397028Y88294D02*
Y88307D01*
G01X1397025Y88281D02*
X1397028Y88294D01*
G01X1397025Y88268D02*
Y88281D01*
G01X1397028Y85145D02*
Y85157D01*
G01X1397025Y85132D02*
X1397028Y85145D01*
G01X1397025Y85118D02*
Y85132D01*
G01X1410414Y80628D02*
X1410415Y80630D01*
G01X1410413Y80622D02*
X1410414Y80628D01*
G01X1410413Y80614D02*
Y80622D01*
G01X1410414Y75628D02*
X1410415Y75630D01*
G01X1410413Y75622D02*
X1410414Y75628D01*
G01X1410413Y75614D02*
Y75622D01*
G01X1410414Y70628D02*
X1410415Y70630D01*
G01X1410413Y70622D02*
X1410414Y70628D01*
G01X1410413Y70614D02*
Y70622D01*
G01X1410414Y65628D02*
X1410415Y65630D01*
G01X1410413Y65622D02*
X1410414Y65628D01*
G01X1410413Y65614D02*
Y65622D01*
G01X1410414Y60628D02*
X1410415Y60630D01*
G01X1410413Y60622D02*
X1410414Y60628D01*
G01X1410413Y60614D02*
Y60622D01*
G01X1410414Y55628D02*
X1410415Y55630D01*
G01X1410413Y55622D02*
X1410414Y55628D01*
G01X1410413Y55614D02*
Y55622D01*
G01X1410414Y50628D02*
X1410415Y50630D01*
G01X1410413Y50622D02*
X1410414Y50628D01*
G01X1410413Y50614D02*
Y50622D01*
G01X1397025Y93057D02*
X1397024Y93070D01*
G01X1397028Y93044D02*
X1397025Y93057D01*
G01X1397028Y93031D02*
Y93044D01*
G01X1397025Y89907D02*
X1397024Y89921D01*
G01X1397028Y89894D02*
X1397025Y89907D01*
G01X1397028Y89882D02*
Y89894D01*
G01X1397025Y86757D02*
X1397024Y86771D01*
G01X1397028Y86745D02*
X1397025Y86757D01*
G01X1397028Y86732D02*
Y86745D01*
G01X1397025Y83608D02*
X1397024Y83622D01*
G01X1397028Y83595D02*
X1397025Y83608D01*
G01X1397028Y83583D02*
Y83595D01*
G01X1397935Y91431D02*
X1397937Y91417D01*
G01X1397932Y91444D02*
X1397935Y91431D01*
G01X1397933Y91457D02*
X1397932Y91444D01*
G01X1397935Y88281D02*
X1397937Y88268D01*
G01X1397932Y88294D02*
X1397935Y88281D01*
G01X1397933Y88307D02*
X1397932Y88294D01*
G01X1397935Y85132D02*
X1397937Y85118D01*
G01X1397932Y85145D02*
X1397935Y85132D01*
G01X1397933Y85157D02*
X1397932Y85145D01*
G01X1396988Y90112D02*
Y90105D01*
G01X1396987Y90117D02*
X1396988Y90112D01*
G01X1396987Y90109D02*
Y90117D01*
G01X1397932Y93044D02*
X1397933Y93031D01*
G01X1397935Y93057D02*
X1397932Y93044D01*
G01X1397936Y93070D02*
X1397935Y93057D01*
G01X1397932Y89894D02*
X1397933Y89882D01*
G01X1397935Y89907D02*
X1397932Y89894D01*
G01X1397936Y89921D02*
X1397935Y89907D01*
G01X1397932Y86745D02*
X1397933Y86732D01*
G01X1397935Y86757D02*
X1397932Y86745D01*
G01X1397936Y86771D02*
X1397935Y86757D01*
G01X1397932Y83595D02*
X1397933Y83583D01*
G01X1397935Y83608D02*
X1397932Y83595D01*
G01X1397936Y83622D02*
X1397935Y83608D01*
G01X1396988Y83813D02*
Y83806D01*
G01X1396987Y83817D02*
X1396988Y83813D01*
G01X1396987Y83811D02*
Y83817D01*
G01X1397001Y91251D02*
X1397025Y91260D01*
G01X1396990Y91237D02*
X1397001Y91251D01*
G01X1396988Y91230D02*
X1396990Y91237D01*
G01X1397001Y88102D02*
X1397025Y88110D01*
G01X1396990Y88087D02*
X1397001Y88102D01*
G01X1396988Y88080D02*
X1396990Y88087D01*
G01X1397001Y84952D02*
X1397025Y84961D01*
G01X1396990Y84937D02*
X1397001Y84952D01*
G01X1396988Y84931D02*
X1396990Y84937D01*
G01X1397972Y91227D02*
Y91234D01*
G01Y91222D02*
Y91227D01*
G01X1397971Y91220D02*
X1397972Y91222D01*
G01Y88077D02*
Y88084D01*
G01Y88072D02*
Y88077D01*
G01X1397971Y88071D02*
X1397972Y88072D01*
G01Y84928D02*
Y84935D01*
G01Y84923D02*
Y84928D01*
G01X1397971Y84921D02*
X1397972Y84923D01*
G01X1396988Y93262D02*
Y93254D01*
G01X1396987Y93266D02*
X1396988Y93262D01*
G01X1396986Y93263D02*
X1396987Y93266D01*
G01X1396988Y86963D02*
Y86955D01*
G01X1396987Y86967D02*
X1396988Y86963D01*
G01X1396986Y86965D02*
X1396987Y86967D01*
G01X1397933Y91265D02*
Y91271D01*
G01X1397932Y91261D02*
X1397933Y91265D01*
G01X1397931Y91260D02*
X1397932Y91261D01*
G01X1397933Y88115D02*
Y88121D01*
G01X1397932Y88111D02*
X1397933Y88115D01*
G01X1397931Y88110D02*
X1397932Y88111D01*
G01X1397933Y84966D02*
Y84972D01*
G01X1397932Y84962D02*
X1397933Y84966D01*
G01X1397931Y84961D02*
X1397932Y84962D01*
G01X1411398Y80622D02*
Y80613D01*
G01X1411399Y80628D02*
X1411398Y80622D01*
G01X1411400Y80630D02*
X1411399Y80628D01*
G01X1411398Y75622D02*
Y75613D01*
G01X1411399Y75628D02*
X1411398Y75622D01*
G01X1411400Y75630D02*
X1411399Y75628D01*
G01X1411398Y70622D02*
Y70613D01*
G01X1411399Y70628D02*
X1411398Y70622D01*
G01X1411400Y70630D02*
X1411399Y70628D01*
G01X1411398Y65622D02*
Y65613D01*
G01X1411399Y65628D02*
X1411398Y65622D01*
G01X1411400Y65630D02*
X1411399Y65628D01*
G01X1411398Y60622D02*
Y60613D01*
G01X1411399Y60628D02*
X1411398Y60622D01*
G01X1411400Y60630D02*
X1411399Y60628D01*
G01X1411398Y55622D02*
Y55613D01*
G01X1411399Y55628D02*
X1411398Y55622D01*
G01X1411400Y55630D02*
X1411399Y55628D01*
G01X1411398Y50622D02*
Y50613D01*
G01X1411399Y50628D02*
X1411398Y50622D01*
G01X1411400Y50630D02*
X1411399Y50628D01*
G01X1396988Y91226D02*
Y91234D01*
G01X1396987Y91222D02*
X1396988Y91226D01*
G01X1396986Y91220D02*
X1396987Y91222D01*
G01X1396988Y88077D02*
Y88084D01*
G01X1396987Y88072D02*
X1396988Y88077D01*
G01X1396986Y88071D02*
X1396987Y88072D01*
G01X1396988Y84927D02*
Y84935D01*
G01X1396987Y84923D02*
X1396988Y84927D01*
G01X1396986Y84921D02*
X1396987Y84923D01*
G01X1397970Y93242D02*
X1397972Y93254D01*
G01X1397963Y93230D02*
X1397970Y93242D01*
G01X1397953Y93222D02*
X1397963Y93230D01*
G01X1397970Y90092D02*
X1397972Y90104D01*
G01X1397963Y90081D02*
X1397970Y90092D01*
G01X1397953Y90073D02*
X1397963Y90081D01*
G01X1397970Y86943D02*
X1397972Y86955D01*
G01X1397963Y86931D02*
X1397970Y86943D01*
G01X1397953Y86923D02*
X1397963Y86931D01*
G01X1397970Y83793D02*
X1397972Y83805D01*
G01X1397963Y83781D02*
X1397970Y83793D01*
G01X1397953Y83774D02*
X1397963Y83781D01*
G01X1397027Y91265D02*
Y91271D01*
G01Y91261D02*
Y91265D01*
G01X1397025Y91260D02*
X1397027Y91261D01*
G01Y88115D02*
Y88121D01*
G01Y88111D02*
Y88115D01*
G01X1397025Y88110D02*
X1397027Y88111D01*
G01Y84965D02*
Y84972D01*
G01Y84962D02*
Y84965D01*
G01X1397025Y84961D02*
X1397027Y84962D01*
G01X1396989Y91240D02*
X1396988Y91234D01*
G01X1396991Y91246D02*
X1396989Y91240D01*
G01X1396993Y91252D02*
X1396991Y91246D01*
G01X1396997Y91257D02*
X1396993Y91252D01*
G01X1397002Y91262D02*
X1396997Y91257D01*
G01X1397007Y91266D02*
X1397002Y91262D01*
G01X1396989Y88091D02*
X1396988Y88084D01*
G01X1396991Y88097D02*
X1396989Y88091D01*
G01X1396993Y88103D02*
X1396991Y88097D01*
G01X1396997Y88108D02*
X1396993Y88103D01*
G01X1397002Y88113D02*
X1396997Y88108D01*
G01X1397007Y88116D02*
X1397002Y88113D01*
G01X1396989Y84941D02*
X1396988Y84935D01*
G01X1396991Y84947D02*
X1396989Y84941D01*
G01X1396993Y84953D02*
X1396991Y84947D01*
G01X1396997Y84958D02*
X1396993Y84953D01*
G01X1397002Y84963D02*
X1396997Y84958D01*
G01X1397007Y84967D02*
X1397002Y84963D01*
G01X1397944Y93230D02*
X1397931Y93228D01*
G01X1397954Y93235D02*
X1397944Y93230D01*
G01Y90081D02*
X1397931Y90079D01*
G01X1397954Y90085D02*
X1397944Y90081D01*
G01Y86931D02*
X1397931Y86929D01*
G01X1397954Y86936D02*
X1397944Y86931D01*
G01Y83781D02*
X1397931Y83780D01*
G01X1397954Y83786D02*
X1397944Y83781D01*
G01X1401969Y25138D02*
G03X1402559Y24547I590J-1D01*
G01X1409252D02*
G03X1409843Y25138I0J591D01*
G01X1407087Y26319D02*
G03Y28287I0J984D01*
G01X1404724D02*
G03Y26319I0J-984D01*
G01X1407008Y39508D02*
G03I-1102J0D01*
G01X1408465Y34232D02*
G03X1409646Y35413I0J1181D01*
G01X1402165D02*
G03X1403346Y34232I1181J0D01*
G01X1407480Y39508D02*
G03I-1574J0D01*
G01X1395079Y25728D02*
G03X1397047Y23760I1968J0D01*
G01X1414764D02*
G03X1416732Y25728I0J1968D01*
G01X1401378Y47500D02*
X1400197Y46319D01*
G01X1398425Y44823D02*
X1395079Y41476D01*
G01X1408390Y42579D02*
X1407087Y40610D01*
G01X1402414Y34688D02*
X1404724Y38917D01*
G01X1397972Y84923D02*
Y84935D01*
G01Y88073D02*
Y88084D01*
G01Y91222D02*
Y91234D01*
G01X1411398Y51982D02*
Y51991D01*
G01Y56982D02*
Y56991D01*
G01Y61982D02*
Y61991D01*
G01Y66982D02*
Y66991D01*
G01Y71982D02*
Y71991D01*
G01Y76982D02*
Y76991D01*
G01Y81982D02*
Y81991D01*
G01X1416732Y25728D02*
Y41476D01*
G01X1415748Y80630D02*
Y82008D01*
G01Y75630D02*
Y77008D01*
G01Y70630D02*
Y72008D01*
G01Y65630D02*
Y67008D01*
G01Y60630D02*
Y62008D01*
G01Y55630D02*
Y57008D01*
G01Y50630D02*
Y52008D01*
G01X1413386Y182815D02*
Y44823D01*
G01X1412795Y185059D02*
Y42579D01*
G01X1412579Y52008D02*
Y50630D01*
G01Y57008D02*
Y55630D01*
G01Y62008D02*
Y60630D01*
G01Y67008D02*
Y65630D01*
G01Y72008D02*
Y70630D01*
G01Y77008D02*
Y75630D01*
G01Y82008D02*
Y80630D01*
G01X1412008Y104862D02*
Y82776D01*
G01X1411398Y51982D02*
Y52125D01*
G01Y56982D02*
Y57125D01*
G01Y61982D02*
Y62125D01*
G01Y66982D02*
Y67125D01*
G01Y71982D02*
Y72125D01*
G01Y76982D02*
Y77125D01*
G01Y81982D02*
Y82125D01*
G01Y80138D02*
Y82500D01*
G01Y75138D02*
Y77500D01*
G01Y70138D02*
Y72500D01*
G01Y65138D02*
Y67500D01*
G01Y60138D02*
Y62500D01*
G01Y55138D02*
Y57500D01*
G01Y50138D02*
Y52500D01*
G01X1410827Y103681D02*
Y83957D01*
G01X1410413Y52500D02*
Y50138D01*
G01Y57500D02*
Y55138D01*
G01Y62500D02*
Y60138D01*
G01Y67500D02*
Y65138D01*
G01Y72500D02*
Y70138D01*
G01Y77500D02*
Y75138D01*
G01Y82500D02*
Y80138D01*
G01X1409843Y31240D02*
Y25138D01*
G01X1409646Y43957D02*
Y35413D01*
G01X1408071Y82776D02*
Y46319D01*
G01X1407087Y40610D02*
Y38917D01*
G01X1406890Y83957D02*
Y47500D01*
G01X1404724Y38917D02*
Y40610D01*
G01X1402165Y35413D02*
Y43957D01*
G01X1401969Y31240D02*
Y25138D01*
G01X1401378Y47500D02*
Y180138D01*
G01X1400197Y46319D02*
Y181319D01*
G01X1398425Y81614D02*
Y42579D01*
G01X1397972Y93070D02*
Y94567D01*
G01Y89921D02*
Y91417D01*
G01Y86771D02*
Y88268D01*
G01Y83622D02*
Y85118D01*
G01X1397933Y86918D02*
Y86771D01*
G01Y83768D02*
Y83621D01*
G01Y85119D02*
Y84972D01*
G01Y90067D02*
Y89920D01*
G01Y91418D02*
Y91271D01*
G01Y88268D02*
Y88121D01*
G01Y93217D02*
Y93070D01*
G01X1397028D02*
Y93217D01*
G01Y89920D02*
Y90067D01*
G01Y91271D02*
Y91418D01*
G01Y88121D02*
Y88268D01*
G01Y86771D02*
Y86918D01*
G01Y83621D02*
Y83768D01*
G01Y84972D02*
Y85119D01*
G01X1396988Y85118D02*
Y83622D01*
G01Y91417D02*
Y89921D01*
G01Y88268D02*
Y86772D01*
G01Y94567D02*
Y93071D01*
G01X1395807Y88110D02*
Y86929D01*
G01Y84961D02*
Y83780D01*
G01Y91260D02*
Y90079D01*
G01Y94409D02*
Y93228D01*
G01X1395472Y106024D02*
Y81614D01*
G01X1395079D02*
Y106024D01*
G01Y41476D02*
Y25728D01*
G01X1392047Y93228D02*
Y94409D01*
G01Y90079D02*
Y91260D01*
G01Y86929D02*
Y88110D01*
G01Y83780D02*
Y84961D01*
G01X1397972Y93254D02*
Y93265D01*
G01Y90105D02*
Y90115D01*
G01Y86955D02*
Y86966D01*
G01Y83806D02*
Y83816D01*
G01X1407087Y38917D02*
X1409397Y34688D01*
G01X1404724Y40610D02*
X1403421Y42579D01*
G01X1410827Y83957D02*
X1412008Y82776D01*
G01X1406890Y83957D02*
X1408071Y82776D01*
G01X1416732Y41476D02*
X1413386Y44823D01*
G01X1406890Y47500D02*
X1408071Y46319D01*
G01X1396986Y93263D02*
X1396875Y93268D01*
G01X1396986Y86965D02*
X1396875Y86969D01*
G01X1396241Y93268D02*
X1395807D01*
G01X1397971D02*
X1392047D01*
G01X1397931Y93228D02*
X1392047D01*
G01X1396988Y93071D02*
X1397972D01*
G01X1397028Y93031D02*
X1397933D01*
G01Y91457D02*
X1397028D01*
G01X1397972Y91417D02*
X1396988D01*
G01X1397931Y91260D02*
X1392047D01*
G01Y91220D02*
X1397971D01*
G01Y90118D02*
X1392047D01*
G01X1397931Y90079D02*
X1392047D01*
G01X1396988Y89921D02*
X1397972D01*
G01X1397028Y89882D02*
X1397933D01*
G01Y88307D02*
X1397028D01*
G01X1397972Y88268D02*
X1396988D01*
G01X1397931Y88110D02*
X1392047D01*
G01Y88071D02*
X1397971D01*
G01X1396241Y86969D02*
X1395807D01*
G01X1397971D02*
X1392047D01*
G01X1397931Y86929D02*
X1392047D01*
G01X1396988Y86772D02*
X1397972D01*
G01X1397028Y86732D02*
X1397933D01*
G01Y85157D02*
X1397028D01*
G01X1397972Y85118D02*
X1396988D01*
G01X1397931Y84961D02*
X1392047D01*
G01Y84921D02*
X1397971D01*
G01X1410827Y83957D02*
X1406890D01*
G01X1397971Y83819D02*
X1392047D01*
G01X1397931Y83780D02*
X1392047D01*
G01X1396988Y83622D02*
X1397972D01*
G01X1397028Y83583D02*
X1397933D01*
G01X1412008Y82776D02*
X1408071D01*
G01X1411398Y82500D02*
X1410413D01*
G01X1410415Y82008D02*
X1415748D01*
G01Y81969D02*
X1411400D01*
G01X1398425Y81614D02*
X1395079D01*
G01X1415748Y80630D02*
X1410415D01*
G01X1410413Y80138D02*
X1411398D01*
G01Y77500D02*
X1410413D01*
G01X1410415Y77008D02*
X1415748D01*
G01Y76969D02*
X1411400D01*
G01X1415748Y75630D02*
X1410415D01*
G01X1410413Y75138D02*
X1411398D01*
G01Y72500D02*
X1410413D01*
G01X1410415Y72008D02*
X1415748D01*
G01Y71969D02*
X1411400D01*
G01X1415748Y70630D02*
X1410415D01*
G01X1410413Y70138D02*
X1411398D01*
G01Y67500D02*
X1410413D01*
G01X1410415Y67008D02*
X1415748D01*
G01Y66969D02*
X1411400D01*
G01X1415748Y65630D02*
X1410415D01*
G01X1410413Y65138D02*
X1411398D01*
G01Y62500D02*
X1410413D01*
G01X1410415Y62008D02*
X1415748D01*
G01Y61969D02*
X1411400D01*
G01X1415748Y60630D02*
X1410415D01*
G01X1410413Y60138D02*
X1411398D01*
G01Y57500D02*
X1410413D01*
G01X1410415Y57008D02*
X1415748D01*
G01Y56969D02*
X1411400D01*
G01X1415748Y55630D02*
X1410415D01*
G01X1410413Y55138D02*
X1411398D01*
G01Y52500D02*
X1410413D01*
G01X1410415Y52008D02*
X1415748D01*
G01Y51969D02*
X1411400D01*
G01X1415748Y50630D02*
X1410415D01*
G01X1410413Y50138D02*
X1411398D01*
G01X1406890Y47500D02*
X1401378D01*
G01X1408071Y46319D02*
X1400197D01*
G01X1413386Y44823D02*
X1398425D01*
G01X1409646Y43957D02*
X1412795D01*
G01X1402165D02*
X1398425D01*
G01Y42579D02*
X1412795D01*
G01X1407087Y40610D02*
X1404724D01*
G01X1407087Y38917D02*
X1404724D01*
G01X1410413Y82204D02*
X1411369Y82205D01*
G01X1411398Y80434D02*
X1410413Y80433D01*
G01Y77204D02*
X1411369Y77205D01*
G01X1411398Y75434D02*
X1410413Y75433D01*
G01Y72204D02*
X1411369Y72205D01*
G01X1411398Y70434D02*
X1410413Y70433D01*
G01Y67204D02*
X1411369Y67205D01*
G01X1411398Y65434D02*
X1410413Y65433D01*
G01Y62204D02*
X1411369Y62205D01*
G01X1411398Y60434D02*
X1410413Y60433D01*
G01Y57204D02*
X1411369Y57205D01*
G01X1411398Y55434D02*
X1410413Y55433D01*
G01Y52204D02*
X1411369Y52205D01*
G01X1411398Y50434D02*
X1410413Y50433D01*
G01X1408465Y34232D02*
X1403346D01*
G01X1416732Y34193D02*
X1395079D01*
G01X1409843Y31240D02*
X1401969D01*
G01Y29665D02*
X1409843D01*
G01X1407087Y28287D02*
X1404724D01*
G01Y26319D02*
X1407087D01*
G01X1409252Y24547D02*
X1402559D01*
G01X1414764Y23760D02*
X1397047D01*
G01X1396991Y94390D02*
X1396986Y94370D01*
G01X1397006Y94404D02*
X1396991Y94390D01*
G01X1397025Y94409D02*
X1397006Y94404D01*
G01X1396991Y97539D02*
X1396986Y97520D01*
G01X1397006Y97554D02*
X1396991Y97539D01*
G01X1397025Y97559D02*
X1397006Y97554D01*
G01X1396991Y100689D02*
X1396986Y100669D01*
G01X1397006Y100703D02*
X1396991Y100689D01*
G01X1397025Y100709D02*
X1397006Y100703D01*
G01X1396991Y103839D02*
X1396986Y103819D01*
G01X1397006Y103853D02*
X1396991Y103839D01*
G01X1397025Y103858D02*
X1397006Y103853D01*
G01X1397966Y96398D02*
X1397971Y96417D01*
G01X1397951Y96383D02*
X1397966Y96398D01*
G01X1397931Y96378D02*
X1397951Y96383D01*
G01X1397966Y99547D02*
X1397971Y99567D01*
G01X1397951Y99533D02*
X1397966Y99547D01*
G01X1397931Y99528D02*
X1397951Y99533D01*
G01X1397966Y102697D02*
X1397971Y102717D01*
G01X1397951Y102682D02*
X1397966Y102697D01*
G01X1397931Y102677D02*
X1397951Y102682D01*
G01X1397972Y99546D02*
Y99553D01*
G01X1397969Y99539D02*
X1397972Y99546D01*
G01X1397966Y99533D02*
X1397969Y99539D01*
G01X1397961Y99527D02*
X1397966Y99533D01*
G01X1397955Y99522D02*
X1397961Y99527D01*
G01X1397948Y99519D02*
X1397955Y99522D01*
G01X1397941Y99517D02*
X1397948Y99519D01*
G01X1397933Y99516D02*
X1397941Y99517D01*
G01X1397011Y94417D02*
X1397007Y94415D01*
G01X1397014Y94418D02*
X1397011Y94417D01*
G01X1397017Y94419D02*
X1397014Y94418D01*
G01X1397020Y94420D02*
X1397017Y94419D01*
G01X1397024Y94420D02*
X1397020D01*
G01X1397028D02*
X1397024D01*
G01X1397950Y96370D02*
X1397953Y96372D01*
G01X1397947Y96369D02*
X1397950Y96370D01*
G01X1397944Y96368D02*
X1397947Y96369D01*
G01X1397940Y96367D02*
X1397944Y96368D01*
G01X1397937Y96367D02*
X1397940D01*
G01X1397933D02*
X1397937D01*
G01X1397011Y97567D02*
X1397007Y97565D01*
G01X1397014Y97568D02*
X1397011Y97567D01*
G01X1397017Y97569D02*
X1397014Y97568D01*
G01X1397020Y97570D02*
X1397017Y97569D01*
G01X1397024Y97570D02*
X1397020D01*
G01X1397028D02*
X1397024D01*
G01X1397011Y100716D02*
X1397007Y100715D01*
G01X1397014Y100717D02*
X1397011Y100716D01*
G01X1397017Y100719D02*
X1397014Y100717D01*
G01X1397020Y100719D02*
X1397017D01*
G01X1397024Y100720D02*
X1397020Y100719D01*
G01X1397028Y100720D02*
X1397024D01*
G01X1397950Y102669D02*
X1397953Y102671D01*
G01X1397947Y102668D02*
X1397950Y102669D01*
G01X1397944Y102667D02*
X1397947Y102668D01*
G01X1397940Y102667D02*
X1397944D01*
G01X1397937Y102666D02*
X1397940Y102667D01*
G01X1397933Y102666D02*
X1397937D01*
G01X1397011Y103866D02*
X1397007Y103864D01*
G01X1397014Y103867D02*
X1397011Y103866D01*
G01X1397017Y103868D02*
X1397014Y103867D01*
G01X1397020Y103869D02*
X1397017Y103868D01*
G01X1397024Y103869D02*
X1397020D01*
G01X1397028D02*
X1397024D01*
G01X1397963Y94408D02*
X1397967Y94402D01*
G01X1397958Y94412D02*
X1397963Y94408D01*
G01X1397952Y94416D02*
X1397958Y94412D01*
G01X1397946Y94419D02*
X1397952Y94416D01*
G01X1397940Y94420D02*
X1397946Y94419D01*
G01X1397933Y94420D02*
X1397940D01*
G01X1397963Y97557D02*
X1397967Y97552D01*
G01X1397958Y97562D02*
X1397963Y97557D01*
G01X1397952Y97565D02*
X1397958Y97562D01*
G01X1397946Y97568D02*
X1397952Y97565D01*
G01X1397940Y97570D02*
X1397946Y97568D01*
G01X1397933Y97570D02*
X1397940D01*
G01X1397963Y100707D02*
X1397967Y100702D01*
G01X1397958Y100711D02*
X1397963Y100707D01*
G01X1397952Y100715D02*
X1397958Y100711D01*
G01X1397946Y100718D02*
X1397952Y100715D01*
G01X1397940Y100719D02*
X1397946Y100718D01*
G01X1397933Y100720D02*
X1397940Y100719D01*
G01X1397963Y103857D02*
X1397967Y103851D01*
G01X1397958Y103861D02*
X1397963Y103857D01*
G01X1397952Y103865D02*
X1397958Y103861D01*
G01X1397946Y103867D02*
X1397952Y103865D01*
G01X1397940Y103869D02*
X1397946Y103867D01*
G01X1397933Y103869D02*
X1397940D01*
G01X1396989Y96396D02*
X1396988Y96404D01*
G01X1396991Y96389D02*
X1396989Y96396D01*
G01X1396995Y96383D02*
X1396991Y96389D01*
G01X1397000Y96378D02*
X1396995Y96383D01*
G01X1397006Y96373D02*
X1397000Y96378D01*
G01X1397013Y96369D02*
X1397006Y96373D01*
G01X1397020Y96367D02*
X1397013Y96369D01*
G01X1397028Y96367D02*
X1397020D01*
G01X1396989Y99546D02*
X1396988Y99553D01*
G01X1396991Y99539D02*
X1396989Y99546D01*
G01X1396995Y99533D02*
X1396991Y99539D01*
G01X1397000Y99527D02*
X1396995Y99533D01*
G01X1397006Y99522D02*
X1397000Y99527D01*
G01X1397013Y99519D02*
X1397006Y99522D01*
G01X1397020Y99517D02*
X1397013Y99519D01*
G01X1397028Y99516D02*
X1397020Y99517D01*
G01X1396989Y102696D02*
X1396988Y102703D01*
G01X1396991Y102689D02*
X1396989Y102696D01*
G01X1396995Y102682D02*
X1396991Y102689D01*
G01X1397000Y102677D02*
X1396995Y102682D01*
G01X1397006Y102672D02*
X1397000Y102677D01*
G01X1397013Y102669D02*
X1397006Y102672D01*
G01X1397020Y102667D02*
X1397013Y102669D01*
G01X1397028Y102666D02*
X1397020Y102667D01*
G01X1397942Y94408D02*
X1397952Y94404D01*
G01X1397931Y94409D02*
X1397942Y94408D01*
G01Y97557D02*
X1397952Y97554D01*
G01X1397931Y97559D02*
X1397942Y97557D01*
G01Y100707D02*
X1397952Y100703D01*
G01X1397931Y100709D02*
X1397942Y100707D01*
G01Y103857D02*
X1397952Y103853D01*
G01X1397931Y103858D02*
X1397942Y103857D01*
G01X1396988Y96407D02*
Y96404D01*
G01X1396990Y96401D02*
X1396988Y96407D01*
G01X1397001Y96386D02*
X1396990Y96401D01*
G01X1397026Y96378D02*
X1397001Y96386D01*
G01X1396988Y99557D02*
Y99553D01*
G01X1396990Y99551D02*
X1396988Y99557D01*
G01X1397001Y99536D02*
X1396990Y99551D01*
G01X1397026Y99528D02*
X1397001Y99536D01*
G01X1396988Y102707D02*
Y102703D01*
G01X1396990Y102701D02*
X1396988Y102707D01*
G01X1397001Y102685D02*
X1396990Y102701D01*
G01X1397026Y102677D02*
X1397001Y102685D01*
G01X1411385Y106999D02*
X1411396Y106984D01*
G01X1411361Y107008D02*
X1411385Y106999D01*
G01Y111999D02*
X1411396Y111984D01*
G01X1411361Y112008D02*
X1411385Y111999D01*
G01Y116999D02*
X1411396Y116984D01*
G01X1411361Y117008D02*
X1411385Y116999D01*
G01Y121999D02*
X1411396Y121984D01*
G01X1411361Y122008D02*
X1411385Y121999D01*
G01Y126999D02*
X1411396Y126984D01*
G01X1411361Y127008D02*
X1411385Y126999D01*
G01Y131999D02*
X1411396Y131984D01*
G01X1411361Y132008D02*
X1411385Y131999D01*
G01Y136999D02*
X1411396Y136984D01*
G01X1411361Y137008D02*
X1411385Y136999D01*
G01Y141999D02*
X1411396Y141984D01*
G01X1411361Y142008D02*
X1411385Y141999D01*
G01Y146999D02*
X1411396Y146984D01*
G01X1411361Y147008D02*
X1411385Y146999D01*
G01Y151999D02*
X1411396Y151984D01*
G01X1411361Y152008D02*
X1411385Y151999D01*
G01Y156999D02*
X1411396Y156984D01*
G01X1411361Y157008D02*
X1411385Y156999D01*
G01Y161999D02*
X1411396Y161984D01*
G01X1411361Y162008D02*
X1411385Y161999D01*
G01Y166999D02*
X1411396Y166984D01*
G01X1411361Y167008D02*
X1411385Y166999D01*
G01Y171999D02*
X1411396Y171984D01*
G01X1411361Y172008D02*
X1411385Y171999D01*
G01Y176999D02*
X1411396Y176984D01*
G01X1411361Y177008D02*
X1411385Y176999D01*
G01X1397941Y94408D02*
X1397931Y94409D01*
G01X1397950Y94405D02*
X1397941Y94408D01*
G01X1397957Y94400D02*
X1397950Y94405D01*
G01X1397941Y97558D02*
X1397931Y97559D01*
G01X1397950Y97555D02*
X1397941Y97558D01*
G01X1397957Y97549D02*
X1397950Y97555D01*
G01X1397941Y100707D02*
X1397931Y100709D01*
G01X1397950Y100704D02*
X1397941Y100707D01*
G01X1397957Y100699D02*
X1397950Y100704D01*
G01X1397941Y103857D02*
X1397931Y103858D01*
G01X1397950Y103854D02*
X1397941Y103857D01*
G01X1397957Y103848D02*
X1397950Y103854D01*
G01X1397027Y96373D02*
X1397028Y96367D01*
G01X1397026Y96377D02*
X1397027Y96373D01*
G01X1397025Y96378D02*
X1397026Y96377D01*
G01X1397027Y99522D02*
X1397028Y99516D01*
G01X1397026Y99526D02*
X1397027Y99522D01*
G01X1397025Y99528D02*
X1397026Y99526D01*
G01X1397027Y102672D02*
X1397028Y102666D01*
G01X1397026Y102676D02*
X1397027Y102672D01*
G01X1397025Y102677D02*
X1397026Y102676D01*
G01X1411398Y106975D02*
Y106982D01*
G01X1411399Y106970D02*
X1411398Y106975D01*
G01X1411400Y106969D02*
X1411399Y106970D01*
G01X1411398Y111975D02*
Y111982D01*
G01X1411399Y111970D02*
X1411398Y111975D01*
G01X1411400Y111969D02*
X1411399Y111970D01*
G01X1411398Y116975D02*
Y116982D01*
G01X1411399Y116970D02*
X1411398Y116975D01*
G01X1411400Y116969D02*
X1411399Y116970D01*
G01X1411398Y121975D02*
Y121982D01*
G01X1411399Y121970D02*
X1411398Y121975D01*
G01X1411400Y121969D02*
X1411399Y121970D01*
G01X1411398Y126975D02*
Y126982D01*
G01X1411399Y126970D02*
X1411398Y126975D01*
G01X1411400Y126969D02*
X1411399Y126970D01*
G01X1411398Y131975D02*
Y131982D01*
G01X1411399Y131970D02*
X1411398Y131975D01*
G01X1411400Y131969D02*
X1411399Y131970D01*
G01X1411398Y136975D02*
Y136982D01*
G01X1411399Y136970D02*
X1411398Y136975D01*
G01X1411400Y136969D02*
X1411399Y136970D01*
G01X1411398Y141975D02*
Y141982D01*
G01X1411399Y141970D02*
X1411398Y141975D01*
G01X1411400Y141969D02*
X1411399Y141970D01*
G01X1411398Y146975D02*
Y146982D01*
G01X1411399Y146970D02*
X1411398Y146975D01*
G01X1411400Y146969D02*
X1411399Y146970D01*
G01X1411398Y151975D02*
Y151982D01*
G01X1411399Y151970D02*
X1411398Y151975D01*
G01X1411400Y151969D02*
X1411399Y151970D01*
G01X1411398Y156975D02*
Y156982D01*
G01X1411399Y156970D02*
X1411398Y156975D01*
G01X1411400Y156969D02*
X1411399Y156970D01*
G01X1411398Y161975D02*
Y161982D01*
G01X1411399Y161970D02*
X1411398Y161975D01*
G01X1411400Y161969D02*
X1411399Y161970D01*
G01X1411398Y166975D02*
Y166982D01*
G01X1411399Y166970D02*
X1411398Y166975D01*
G01X1411400Y166969D02*
X1411399Y166970D01*
G01X1411398Y171975D02*
Y171982D01*
G01X1411399Y171970D02*
X1411398Y171975D01*
G01X1411400Y171969D02*
X1411399Y171970D01*
G01X1411398Y176975D02*
Y176982D01*
G01X1411399Y176970D02*
X1411398Y176975D01*
G01X1411400Y176969D02*
X1411399Y176970D01*
G01X1397011Y96380D02*
X1397025Y96378D01*
G01X1396999Y96388D02*
X1397011Y96380D01*
G01X1396987Y96406D02*
X1396999Y96388D01*
G01X1397011Y99530D02*
X1397025Y99528D01*
G01X1396998Y99538D02*
X1397011Y99530D01*
G01X1396987Y99558D02*
X1396998Y99538D01*
G01X1397972Y96411D02*
Y96404D01*
G01Y96416D02*
Y96411D01*
G01X1397971Y96417D02*
X1397972Y96416D01*
G01Y99561D02*
Y99553D01*
G01Y99565D02*
Y99561D01*
G01X1397971Y99567D02*
X1397972Y99565D01*
G01Y102711D02*
Y102703D01*
G01Y102715D02*
Y102711D01*
G01X1397971Y102717D02*
X1397972Y102715D01*
G01X1397011Y102680D02*
X1397025Y102677D01*
G01X1396998Y102688D02*
X1397011Y102680D01*
G01X1396987Y102708D02*
X1396998Y102688D01*
G01X1397972Y94390D02*
Y94383D01*
G01X1397970Y94396D02*
X1397972Y94390D01*
G01X1397967Y94402D02*
X1397970Y94396D01*
G01X1397972Y97540D02*
Y97533D01*
G01X1397970Y97546D02*
X1397972Y97540D01*
G01X1397967Y97552D02*
X1397970Y97546D01*
G01X1397972Y100689D02*
Y100683D01*
G01X1397970Y100696D02*
X1397972Y100689D01*
G01X1397967Y100702D02*
X1397970Y100696D01*
G01X1397972Y103839D02*
Y103832D01*
G01X1397970Y103845D02*
X1397972Y103839D01*
G01X1397967Y103851D02*
X1397970Y103845D01*
G01X1397933Y96373D02*
X1397934Y96367D01*
G01X1397932Y96376D02*
X1397933Y96373D01*
G01X1397931Y96378D02*
X1397932Y96376D01*
G01X1397933Y102672D02*
X1397934Y102666D01*
G01X1397932Y102676D02*
X1397933Y102672D01*
G01X1397931Y102677D02*
X1397932Y102676D01*
G01X1410413Y107015D02*
Y107024D01*
G01X1410414Y107009D02*
X1410413Y107015D01*
G01X1410415Y107008D02*
X1410414Y107009D01*
G01X1410413Y112015D02*
Y112024D01*
G01X1410414Y112009D02*
X1410413Y112015D01*
G01X1410415Y112008D02*
X1410414Y112009D01*
G01X1410413Y117015D02*
Y117024D01*
G01X1410414Y117009D02*
X1410413Y117015D01*
G01X1410415Y117008D02*
X1410414Y117009D01*
G01X1410413Y122015D02*
Y122024D01*
G01X1410414Y122009D02*
X1410413Y122015D01*
G01X1410415Y122008D02*
X1410414Y122009D01*
G01X1410413Y127015D02*
Y127024D01*
G01X1410414Y127009D02*
X1410413Y127015D01*
G01X1410415Y127008D02*
X1410414Y127009D01*
G01X1410413Y132015D02*
Y132024D01*
G01X1410414Y132009D02*
X1410413Y132015D01*
G01X1410415Y132008D02*
X1410414Y132009D01*
G01X1410413Y137015D02*
Y137024D01*
G01X1410414Y137009D02*
X1410413Y137015D01*
G01X1410415Y137008D02*
X1410414Y137009D01*
G01X1410413Y142015D02*
Y142024D01*
G01X1410414Y142009D02*
X1410413Y142015D01*
G01X1410415Y142008D02*
X1410414Y142009D01*
G01X1410413Y147015D02*
Y147024D01*
G01X1410414Y147009D02*
X1410413Y147015D01*
G01X1410415Y147008D02*
X1410414Y147009D01*
G01X1410413Y152015D02*
Y152024D01*
G01X1410414Y152009D02*
X1410413Y152015D01*
G01X1410415Y152008D02*
X1410414Y152009D01*
G01X1410413Y157015D02*
Y157024D01*
G01X1410414Y157009D02*
X1410413Y157015D01*
G01X1410415Y157008D02*
X1410414Y157009D01*
G01X1410413Y162015D02*
Y162024D01*
G01X1410414Y162009D02*
X1410413Y162015D01*
G01X1410415Y162008D02*
X1410414Y162009D01*
G01X1410413Y167015D02*
Y167024D01*
G01X1410414Y167009D02*
X1410413Y167015D01*
G01X1410415Y167008D02*
X1410414Y167009D01*
G01X1410413Y172015D02*
Y172024D01*
G01X1410414Y172009D02*
X1410413Y172015D01*
G01X1410415Y172008D02*
X1410414Y172009D01*
G01X1410413Y177015D02*
Y177024D01*
G01X1410414Y177009D02*
X1410413Y177015D01*
G01X1410415Y177008D02*
X1410414Y177009D01*
G01X1411390Y107152D02*
X1411398Y107125D01*
G01X1411380Y107178D02*
X1411390Y107152D01*
G01X1411369Y107205D02*
X1411380Y107178D01*
G01X1411390Y112152D02*
X1411398Y112125D01*
G01X1411380Y112178D02*
X1411390Y112152D01*
G01X1411369Y112205D02*
X1411380Y112178D01*
G01X1411390Y117152D02*
X1411398Y117125D01*
G01X1411380Y117178D02*
X1411390Y117152D01*
G01X1411369Y117205D02*
X1411380Y117178D01*
G01X1411390Y122152D02*
X1411398Y122125D01*
G01X1411380Y122178D02*
X1411390Y122152D01*
G01X1411369Y122205D02*
X1411380Y122178D01*
G01X1411390Y127152D02*
X1411398Y127125D01*
G01X1411380Y127178D02*
X1411390Y127152D01*
G01X1411369Y127205D02*
X1411380Y127178D01*
G01X1411390Y132152D02*
X1411398Y132125D01*
G01X1411380Y132178D02*
X1411390Y132152D01*
G01X1411369Y132205D02*
X1411380Y132178D01*
G01X1411390Y137152D02*
X1411398Y137125D01*
G01X1411380Y137178D02*
X1411390Y137152D01*
G01X1411369Y137205D02*
X1411380Y137178D01*
G01X1411390Y142152D02*
X1411398Y142125D01*
G01X1411380Y142178D02*
X1411390Y142152D01*
G01X1411369Y142205D02*
X1411380Y142178D01*
G01X1411390Y147152D02*
X1411398Y147125D01*
G01X1411380Y147178D02*
X1411390Y147152D01*
G01X1411369Y147205D02*
X1411380Y147178D01*
G01X1411390Y152152D02*
X1411398Y152125D01*
G01X1411380Y152178D02*
X1411390Y152152D01*
G01X1411369Y152205D02*
X1411380Y152178D01*
G01X1411390Y157152D02*
X1411398Y157125D01*
G01X1411380Y157178D02*
X1411390Y157152D01*
G01X1411369Y157205D02*
X1411380Y157178D01*
G01X1411390Y162152D02*
X1411398Y162125D01*
G01X1411380Y162178D02*
X1411390Y162152D01*
G01X1411369Y162205D02*
X1411380Y162178D01*
G01X1411390Y167152D02*
X1411398Y167125D01*
G01X1411380Y167178D02*
X1411390Y167152D01*
G01X1411369Y167205D02*
X1411380Y167178D01*
G01X1411390Y172152D02*
X1411398Y172125D01*
G01X1411380Y172178D02*
X1411390Y172152D01*
G01X1411369Y172205D02*
X1411380Y172178D01*
G01X1411390Y177152D02*
X1411398Y177125D01*
G01X1411380Y177178D02*
X1411390Y177152D01*
G01X1411369Y177205D02*
X1411380Y177178D01*
G01Y107003D02*
X1411361Y107008D01*
G01X1411395Y106988D02*
X1411380Y107003D01*
G01X1411400Y106969D02*
X1411395Y106988D01*
G01X1411380Y112003D02*
X1411361Y112008D01*
G01X1411395Y111988D02*
X1411380Y112003D01*
G01X1411400Y111969D02*
X1411395Y111988D01*
G01X1411380Y117003D02*
X1411361Y117008D01*
G01X1411395Y116988D02*
X1411380Y117003D01*
G01X1411400Y116969D02*
X1411395Y116988D01*
G01X1411380Y122003D02*
X1411361Y122008D01*
G01X1411395Y121988D02*
X1411380Y122003D01*
G01X1411400Y121969D02*
X1411395Y121988D01*
G01X1411380Y127003D02*
X1411361Y127008D01*
G01X1411395Y126988D02*
X1411380Y127003D01*
G01X1411400Y126969D02*
X1411395Y126988D01*
G01X1411380Y132003D02*
X1411361Y132008D01*
G01X1411395Y131988D02*
X1411380Y132003D01*
G01X1411400Y131969D02*
X1411395Y131988D01*
G01X1411380Y137003D02*
X1411361Y137008D01*
G01X1411395Y136988D02*
X1411380Y137003D01*
G01X1411400Y136969D02*
X1411395Y136988D01*
G01X1411380Y142003D02*
X1411361Y142008D01*
G01X1411395Y141988D02*
X1411380Y142003D01*
G01X1411400Y141969D02*
X1411395Y141988D01*
G01X1411380Y147003D02*
X1411361Y147008D01*
G01X1411395Y146988D02*
X1411380Y147003D01*
G01X1411400Y146969D02*
X1411395Y146988D01*
G01X1411380Y152003D02*
X1411361Y152008D01*
G01X1411395Y151988D02*
X1411380Y152003D01*
G01X1411400Y151969D02*
X1411395Y151988D01*
G01X1411380Y157003D02*
X1411361Y157008D01*
G01X1411395Y156988D02*
X1411380Y157003D01*
G01X1411400Y156969D02*
X1411395Y156988D01*
G01X1411380Y162003D02*
X1411361Y162008D01*
G01X1411395Y161988D02*
X1411380Y162003D01*
G01X1411400Y161969D02*
X1411395Y161988D01*
G01X1411380Y167003D02*
X1411361Y167008D01*
G01X1411395Y166988D02*
X1411380Y167003D01*
G01X1411400Y166969D02*
X1411395Y166988D01*
G01X1411380Y172003D02*
X1411361Y172008D01*
G01X1411395Y171988D02*
X1411380Y172003D01*
G01X1411400Y171969D02*
X1411395Y171988D01*
G01X1411380Y177003D02*
X1411361Y177008D01*
G01X1411395Y176988D02*
X1411380Y177003D01*
G01X1411400Y176969D02*
X1411395Y176988D01*
G01X1397965Y94391D02*
X1397957Y94400D01*
G01X1397970Y94381D02*
X1397965Y94391D01*
G01X1397971Y94370D02*
X1397970Y94381D01*
G01X1397965Y97541D02*
X1397957Y97549D01*
G01X1397970Y97531D02*
X1397965Y97541D01*
G01X1397971Y97520D02*
X1397970Y97531D01*
G01X1397965Y100691D02*
X1397957Y100699D01*
G01X1397970Y100680D02*
X1397965Y100691D01*
G01X1397971Y100669D02*
X1397970Y100680D01*
G01X1397965Y103840D02*
X1397957Y103848D01*
G01X1397970Y103830D02*
X1397965Y103840D01*
G01X1397971Y103819D02*
X1397970Y103830D01*
G01X1411365Y107106D02*
X1411369Y107205D01*
G01X1411359Y107034D02*
X1411365Y107106D01*
G01X1411361Y107008D02*
X1411359Y107034D01*
G01X1411365Y112106D02*
X1411369Y112205D01*
G01X1411359Y112034D02*
X1411365Y112106D01*
G01X1411361Y112008D02*
X1411359Y112034D01*
G01X1411365Y117106D02*
X1411369Y117205D01*
G01X1411359Y117034D02*
X1411365Y117106D01*
G01X1411361Y117008D02*
X1411359Y117034D01*
G01X1411365Y122106D02*
X1411369Y122205D01*
G01X1411359Y122034D02*
X1411365Y122106D01*
G01X1411361Y122008D02*
X1411359Y122034D01*
G01X1411365Y127106D02*
X1411369Y127205D01*
G01X1411359Y127034D02*
X1411365Y127106D01*
G01X1411361Y127008D02*
X1411359Y127034D01*
G01X1411365Y132106D02*
X1411369Y132205D01*
G01X1411359Y132034D02*
X1411365Y132106D01*
G01X1411361Y132008D02*
X1411359Y132034D01*
G01X1411365Y137106D02*
X1411369Y137205D01*
G01X1411359Y137034D02*
X1411365Y137106D01*
G01X1411361Y137008D02*
X1411359Y137034D01*
G01X1411365Y142106D02*
X1411369Y142205D01*
G01X1411359Y142034D02*
X1411365Y142106D01*
G01X1411361Y142008D02*
X1411359Y142034D01*
G01X1411365Y147106D02*
X1411369Y147205D01*
G01X1411359Y147034D02*
X1411365Y147106D01*
G01X1411361Y147008D02*
X1411359Y147034D01*
G01X1411365Y152106D02*
X1411369Y152205D01*
G01X1411359Y152034D02*
X1411365Y152106D01*
G01X1411361Y152008D02*
X1411359Y152034D01*
G01X1411365Y157106D02*
X1411369Y157205D01*
G01X1411359Y157034D02*
X1411365Y157106D01*
G01X1411361Y157008D02*
X1411359Y157034D01*
G01X1411365Y162106D02*
X1411369Y162205D01*
G01X1411359Y162034D02*
X1411365Y162106D01*
G01X1411361Y162008D02*
X1411359Y162034D01*
G01X1411365Y167106D02*
X1411369Y167205D01*
G01X1411359Y167034D02*
X1411365Y167106D01*
G01X1411361Y167008D02*
X1411359Y167034D01*
G01X1411365Y172106D02*
X1411369Y172205D01*
G01X1411359Y172034D02*
X1411365Y172106D01*
G01X1411361Y172008D02*
X1411359Y172034D01*
G01X1411365Y177106D02*
X1411369Y177205D01*
G01X1411359Y177034D02*
X1411365Y177106D01*
G01X1411361Y177008D02*
X1411359Y177034D01*
G01X1396988Y96411D02*
Y96404D01*
G01X1396987Y96416D02*
X1396988Y96411D01*
G01X1396987Y96406D02*
Y96416D01*
G01X1397028Y104043D02*
Y104055D01*
G01X1397025Y104030D02*
X1397028Y104043D01*
G01X1397025Y104016D02*
Y104030D01*
G01X1397028Y100893D02*
Y100906D01*
G01X1397025Y100880D02*
X1397028Y100893D01*
G01X1397025Y100866D02*
Y100880D01*
G01X1397028Y97743D02*
Y97756D01*
G01X1397025Y97730D02*
X1397028Y97743D01*
G01X1397025Y97717D02*
Y97730D01*
G01X1397028Y94594D02*
Y94606D01*
G01X1397025Y94581D02*
X1397028Y94594D01*
G01X1397025Y94567D02*
Y94581D01*
G01X1410414Y175628D02*
X1410415Y175630D01*
G01X1410413Y175622D02*
X1410414Y175628D01*
G01X1410413Y175614D02*
Y175622D01*
G01X1410414Y170628D02*
X1410415Y170630D01*
G01X1410413Y170622D02*
X1410414Y170628D01*
G01X1410413Y170614D02*
Y170622D01*
G01X1410414Y165628D02*
X1410415Y165630D01*
G01X1410413Y165622D02*
X1410414Y165628D01*
G01X1410413Y165614D02*
Y165622D01*
G01X1410414Y160628D02*
X1410415Y160630D01*
G01X1410413Y160622D02*
X1410414Y160628D01*
G01X1410413Y160614D02*
Y160622D01*
G01X1410414Y155628D02*
X1410415Y155630D01*
G01X1410413Y155622D02*
X1410414Y155628D01*
G01X1410413Y155614D02*
Y155622D01*
G01X1410414Y150628D02*
X1410415Y150630D01*
G01X1410413Y150622D02*
X1410414Y150628D01*
G01X1410413Y150614D02*
Y150622D01*
G01X1410414Y145628D02*
X1410415Y145630D01*
G01X1410413Y145622D02*
X1410414Y145628D01*
G01X1410413Y145614D02*
Y145622D01*
G01X1410414Y140628D02*
X1410415Y140630D01*
G01X1410413Y140622D02*
X1410414Y140628D01*
G01X1410413Y140614D02*
Y140622D01*
G01X1410414Y135628D02*
X1410415Y135630D01*
G01X1410413Y135622D02*
X1410414Y135628D01*
G01X1410413Y135614D02*
Y135622D01*
G01X1410414Y130628D02*
X1410415Y130630D01*
G01X1410413Y130622D02*
X1410414Y130628D01*
G01X1410413Y130614D02*
Y130622D01*
G01X1410414Y125628D02*
X1410415Y125630D01*
G01X1410413Y125622D02*
X1410414Y125628D01*
G01X1410413Y125614D02*
Y125622D01*
G01X1410414Y120628D02*
X1410415Y120630D01*
G01X1410413Y120622D02*
X1410414Y120628D01*
G01X1410413Y120614D02*
Y120622D01*
G01X1410414Y115628D02*
X1410415Y115630D01*
G01X1410413Y115622D02*
X1410414Y115628D01*
G01X1410413Y115614D02*
Y115622D01*
G01X1410414Y110628D02*
X1410415Y110630D01*
G01X1410413Y110622D02*
X1410414Y110628D01*
G01X1410413Y110614D02*
Y110622D01*
G01X1410414Y105628D02*
X1410415Y105630D01*
G01X1410413Y105622D02*
X1410414Y105628D01*
G01X1410413Y105614D02*
Y105622D01*
G01X1396988Y102711D02*
Y102703D01*
G01X1396987Y102715D02*
X1396988Y102711D01*
G01X1396987Y102707D02*
Y102715D01*
G01X1397025Y102506D02*
X1397024Y102519D01*
G01X1397028Y102493D02*
X1397025Y102506D01*
G01X1397028Y102480D02*
Y102493D01*
G01X1397025Y99356D02*
X1397024Y99370D01*
G01X1397028Y99343D02*
X1397025Y99356D01*
G01X1397028Y99331D02*
Y99343D01*
G01X1397025Y96206D02*
X1397024Y96220D01*
G01X1397028Y96194D02*
X1397025Y96206D01*
G01X1397028Y96181D02*
Y96194D01*
G01X1397935Y104030D02*
X1397937Y104016D01*
G01X1397932Y104043D02*
X1397935Y104030D01*
G01X1397933Y104055D02*
X1397932Y104043D01*
G01X1397935Y100880D02*
X1397937Y100866D01*
G01X1397932Y100893D02*
X1397935Y100880D01*
G01X1397933Y100906D02*
X1397932Y100893D01*
G01X1397935Y97730D02*
X1397937Y97717D01*
G01X1397932Y97743D02*
X1397935Y97730D01*
G01X1397933Y97756D02*
X1397932Y97743D01*
G01X1397935Y94581D02*
X1397937Y94567D01*
G01X1397932Y94594D02*
X1397935Y94581D01*
G01X1397933Y94606D02*
X1397932Y94594D01*
G01X1396988Y99561D02*
Y99554D01*
G01X1396987Y99565D02*
X1396988Y99561D01*
G01X1396987Y99558D02*
Y99565D01*
G01X1397932Y102493D02*
X1397933Y102480D01*
G01X1397935Y102506D02*
X1397932Y102493D01*
G01X1397936Y102519D02*
X1397935Y102506D01*
G01X1397932Y99343D02*
X1397933Y99331D01*
G01X1397935Y99356D02*
X1397932Y99343D01*
G01X1397936Y99370D02*
X1397935Y99356D01*
G01X1397932Y96194D02*
X1397933Y96181D01*
G01X1397935Y96206D02*
X1397932Y96194D01*
G01X1397936Y96220D02*
X1397935Y96206D01*
G01X1397001Y103850D02*
X1397025Y103858D01*
G01X1396990Y103835D02*
X1397001Y103850D01*
G01X1396988Y103828D02*
X1396990Y103835D01*
G01X1397001Y100700D02*
X1397025Y100709D01*
G01X1396990Y100685D02*
X1397001Y100700D01*
G01X1396988Y100679D02*
X1396990Y100685D01*
G01X1397001Y97550D02*
X1397025Y97559D01*
G01X1396990Y97536D02*
X1397001Y97550D01*
G01X1396988Y97529D02*
X1396990Y97536D01*
G01X1397001Y94401D02*
X1397025Y94409D01*
G01X1396990Y94386D02*
X1397001Y94401D01*
G01X1396988Y94380D02*
X1396990Y94386D01*
G01X1397972Y103825D02*
Y103832D01*
G01Y103820D02*
Y103825D01*
G01X1397971Y103819D02*
X1397972Y103820D01*
G01Y100676D02*
Y100683D01*
G01Y100671D02*
Y100676D01*
G01X1397971Y100669D02*
X1397972Y100671D01*
G01Y97526D02*
Y97533D01*
G01Y97521D02*
Y97526D01*
G01X1397971Y97520D02*
X1397972Y97521D01*
G01Y94376D02*
Y94383D01*
G01Y94372D02*
Y94376D01*
G01X1397971Y94370D02*
X1397972Y94372D01*
G01X1397933Y103863D02*
Y103869D01*
G01X1397932Y103859D02*
X1397933Y103863D01*
G01X1397931Y103858D02*
X1397932Y103859D01*
G01X1397933Y100714D02*
Y100720D01*
G01X1397932Y100710D02*
X1397933Y100714D01*
G01X1397931Y100709D02*
X1397932Y100710D01*
G01X1397933Y97564D02*
Y97570D01*
G01X1397932Y97560D02*
X1397933Y97564D01*
G01X1397931Y97559D02*
X1397932Y97560D01*
G01X1397933Y94415D02*
Y94420D01*
G01X1397932Y94411D02*
X1397933Y94415D01*
G01X1397931Y94409D02*
X1397932Y94411D01*
G01X1411398Y175622D02*
Y175613D01*
G01X1411399Y175628D02*
X1411398Y175622D01*
G01X1411400Y175630D02*
X1411399Y175628D01*
G01X1411398Y170622D02*
Y170613D01*
G01X1411399Y170628D02*
X1411398Y170622D01*
G01X1411400Y170630D02*
X1411399Y170628D01*
G01X1411398Y165622D02*
Y165613D01*
G01X1411399Y165628D02*
X1411398Y165622D01*
G01X1411400Y165630D02*
X1411399Y165628D01*
G01X1411398Y160622D02*
Y160613D01*
G01X1411399Y160628D02*
X1411398Y160622D01*
G01X1411400Y160630D02*
X1411399Y160628D01*
G01X1411398Y155622D02*
Y155613D01*
G01X1411399Y155628D02*
X1411398Y155622D01*
G01X1411400Y155630D02*
X1411399Y155628D01*
G01X1411398Y150622D02*
Y150613D01*
G01X1411399Y150628D02*
X1411398Y150622D01*
G01X1411400Y150630D02*
X1411399Y150628D01*
G01X1411398Y145622D02*
Y145613D01*
G01X1411399Y145628D02*
X1411398Y145622D01*
G01X1411400Y145630D02*
X1411399Y145628D01*
G01X1411398Y140622D02*
Y140613D01*
G01X1411399Y140628D02*
X1411398Y140622D01*
G01X1411400Y140630D02*
X1411399Y140628D01*
G01X1411398Y135622D02*
Y135613D01*
G01X1411399Y135628D02*
X1411398Y135622D01*
G01X1411400Y135630D02*
X1411399Y135628D01*
G01X1411398Y130622D02*
Y130613D01*
G01X1411399Y130628D02*
X1411398Y130622D01*
G01X1411400Y130630D02*
X1411399Y130628D01*
G01X1411398Y125622D02*
Y125613D01*
G01X1411399Y125628D02*
X1411398Y125622D01*
G01X1411400Y125630D02*
X1411399Y125628D01*
G01X1411398Y120622D02*
Y120613D01*
G01X1411399Y120628D02*
X1411398Y120622D01*
G01X1411400Y120630D02*
X1411399Y120628D01*
G01X1411398Y115622D02*
Y115613D01*
G01X1411399Y115628D02*
X1411398Y115622D01*
G01X1411400Y115630D02*
X1411399Y115628D01*
G01X1411398Y110622D02*
Y110613D01*
G01X1411399Y110628D02*
X1411398Y110622D01*
G01X1411400Y110630D02*
X1411399Y110628D01*
G01X1411398Y105622D02*
Y105613D01*
G01X1411399Y105628D02*
X1411398Y105622D01*
G01X1411400Y105630D02*
X1411399Y105628D01*
G01X1396988Y103825D02*
Y103832D01*
G01X1396987Y103820D02*
X1396988Y103825D01*
G01X1396986Y103819D02*
X1396987Y103820D01*
G01X1396988Y100675D02*
Y100683D01*
G01X1396987Y100671D02*
X1396988Y100675D01*
G01X1396986Y100669D02*
X1396987Y100671D01*
G01X1396988Y97526D02*
Y97533D01*
G01X1396987Y97521D02*
X1396988Y97526D01*
G01X1396986Y97520D02*
X1396987Y97521D01*
G01X1396988Y94376D02*
Y94383D01*
G01X1396987Y94372D02*
X1396988Y94376D01*
G01X1396986Y94370D02*
X1396987Y94372D01*
G01X1397970Y102691D02*
X1397972Y102703D01*
G01X1397963Y102679D02*
X1397970Y102691D01*
G01X1397953Y102671D02*
X1397963Y102679D01*
G01X1397970Y96391D02*
X1397972Y96404D01*
G01X1397963Y96380D02*
X1397970Y96391D01*
G01X1397953Y96372D02*
X1397963Y96380D01*
G01X1397027Y103863D02*
Y103869D01*
G01Y103859D02*
Y103863D01*
G01X1397025Y103858D02*
X1397027Y103859D01*
G01Y100713D02*
Y100720D01*
G01Y100710D02*
Y100713D01*
G01X1397025Y100709D02*
X1397027Y100710D01*
G01Y97564D02*
Y97570D01*
G01Y97560D02*
Y97564D01*
G01X1397025Y97559D02*
X1397027Y97560D01*
G01Y94414D02*
Y94420D01*
G01Y94411D02*
Y94414D01*
G01X1397025Y94409D02*
X1397027Y94411D01*
G01X1396989Y103839D02*
X1396988Y103832D01*
G01X1396991Y103845D02*
X1396989Y103839D01*
G01X1396993Y103851D02*
X1396991Y103845D01*
G01X1396997Y103856D02*
X1396993Y103851D01*
G01X1397002Y103861D02*
X1396997Y103856D01*
G01X1397007Y103864D02*
X1397002Y103861D01*
G01X1396989Y100689D02*
X1396988Y100683D01*
G01X1396991Y100695D02*
X1396989Y100689D01*
G01X1396993Y100701D02*
X1396991Y100695D01*
G01X1396997Y100706D02*
X1396993Y100701D01*
G01X1397002Y100711D02*
X1396997Y100706D01*
G01X1397007Y100715D02*
X1397002Y100711D01*
G01X1396989Y97539D02*
X1396988Y97533D01*
G01X1396991Y97546D02*
X1396989Y97539D01*
G01X1396993Y97552D02*
X1396991Y97546D01*
G01X1396997Y97557D02*
X1396993Y97552D01*
G01X1397002Y97561D02*
X1396997Y97557D01*
G01X1397007Y97565D02*
X1397002Y97561D01*
G01X1396989Y94390D02*
X1396988Y94383D01*
G01X1396991Y94396D02*
X1396989Y94390D01*
G01X1396993Y94402D02*
X1396991Y94396D01*
G01X1396997Y94407D02*
X1396993Y94402D01*
G01X1397002Y94412D02*
X1396997Y94407D01*
G01X1397007Y94415D02*
X1397002Y94412D01*
G01X1397944Y102679D02*
X1397931Y102677D01*
G01X1397954Y102684D02*
X1397944Y102679D01*
G01Y99530D02*
X1397931Y99528D01*
G01X1397954Y99534D02*
X1397944Y99530D01*
G01Y96380D02*
X1397931Y96378D01*
G01X1397954Y96385D02*
X1397944Y96380D01*
G01X1407795Y188130D02*
G03I-1889J0D01*
G01X1408268D02*
G03I-2362J0D01*
G01X1410827Y103681D02*
X1412008Y104862D01*
G01X1406890Y103681D02*
X1408071Y104862D01*
G01X1416732Y186161D02*
X1413386Y182815D01*
G01X1406890Y180138D02*
X1408071Y181319D01*
G01X1403421Y185059D02*
X1404724Y187028D01*
G01X1409397Y192950D02*
X1407087Y188720D01*
G01X1397972Y94372D02*
Y94383D01*
G01Y97522D02*
Y97533D01*
G01Y100671D02*
Y100683D01*
G01Y103821D02*
Y103832D01*
G01X1411398Y106982D02*
Y106991D01*
G01Y111982D02*
Y111991D01*
G01Y116982D02*
Y116991D01*
G01Y121982D02*
Y121991D01*
G01Y126982D02*
Y126991D01*
G01Y131982D02*
Y131991D01*
G01Y136982D02*
Y136991D01*
G01Y141982D02*
Y141991D01*
G01Y146982D02*
Y146991D01*
G01Y151982D02*
Y151991D01*
G01Y156982D02*
Y156991D01*
G01Y161982D02*
Y161991D01*
G01Y166982D02*
Y166991D01*
G01Y171982D02*
Y171991D01*
G01Y176982D02*
Y176991D01*
G01X1416732Y186161D02*
Y201909D01*
G01X1415748Y175630D02*
Y177008D01*
G01Y170630D02*
Y172008D01*
G01Y165630D02*
Y167008D01*
G01Y160630D02*
Y162008D01*
G01Y155630D02*
Y157008D01*
G01Y150630D02*
Y152008D01*
G01Y145630D02*
Y147008D01*
G01Y140630D02*
Y142008D01*
G01Y135630D02*
Y137008D01*
G01Y130630D02*
Y132008D01*
G01Y125630D02*
Y127008D01*
G01Y120630D02*
Y122008D01*
G01Y115630D02*
Y117008D01*
G01Y110630D02*
Y112008D01*
G01Y105630D02*
Y107008D01*
G01X1412579D02*
Y105630D01*
G01Y112008D02*
Y110630D01*
G01Y117008D02*
Y115630D01*
G01Y122008D02*
Y120630D01*
G01Y127008D02*
Y125630D01*
G01Y132008D02*
Y130630D01*
G01Y137008D02*
Y135630D01*
G01Y142008D02*
Y140630D01*
G01Y147008D02*
Y145630D01*
G01Y152008D02*
Y150630D01*
G01Y157008D02*
Y155630D01*
G01Y162008D02*
Y160630D01*
G01Y167008D02*
Y165630D01*
G01Y172008D02*
Y170630D01*
G01Y177008D02*
Y175630D01*
G01X1411398Y106982D02*
Y107125D01*
G01Y111982D02*
Y112125D01*
G01Y116982D02*
Y117125D01*
G01Y121982D02*
Y122125D01*
G01Y126982D02*
Y127125D01*
G01Y131982D02*
Y132125D01*
G01Y136982D02*
Y137125D01*
G01Y141982D02*
Y142125D01*
G01Y146982D02*
Y147125D01*
G01Y151982D02*
Y152125D01*
G01Y156982D02*
Y157125D01*
G01Y161982D02*
Y162125D01*
G01Y166982D02*
Y167125D01*
G01Y171982D02*
Y172125D01*
G01Y176982D02*
Y177125D01*
G01Y175138D02*
Y177500D01*
G01Y170138D02*
Y172500D01*
G01Y165138D02*
Y167500D01*
G01Y160138D02*
Y162500D01*
G01Y155138D02*
Y157500D01*
G01Y150138D02*
Y152500D01*
G01Y145138D02*
Y147500D01*
G01Y140138D02*
Y142500D01*
G01Y135138D02*
Y137500D01*
G01Y130138D02*
Y132500D01*
G01Y125138D02*
Y127500D01*
G01Y120138D02*
Y122500D01*
G01Y115138D02*
Y117500D01*
G01Y110138D02*
Y112500D01*
G01Y105138D02*
Y107500D01*
G01X1410413D02*
Y105138D01*
G01Y112500D02*
Y110138D01*
G01Y117500D02*
Y115138D01*
G01Y122500D02*
Y120138D01*
G01Y127500D02*
Y125138D01*
G01Y132500D02*
Y130138D01*
G01Y137500D02*
Y135138D01*
G01Y142500D02*
Y140138D01*
G01Y147500D02*
Y145138D01*
G01Y152500D02*
Y150138D01*
G01Y157500D02*
Y155138D01*
G01Y162500D02*
Y160138D01*
G01Y167500D02*
Y165138D01*
G01Y172500D02*
Y170138D01*
G01Y177500D02*
Y175138D01*
G01X1409646Y192224D02*
Y183681D01*
G01X1408071Y181319D02*
Y104862D01*
G01X1407087Y188720D02*
Y187028D01*
G01X1406890Y180138D02*
Y103681D01*
G01X1404724Y187028D02*
Y188720D01*
G01X1402165Y183681D02*
Y192224D01*
G01X1398425Y185059D02*
Y106024D01*
G01X1397972Y102519D02*
Y104016D01*
G01Y99370D02*
Y100866D01*
G01Y96220D02*
Y97717D01*
G01X1397933Y96367D02*
Y96220D01*
G01Y94567D02*
Y94420D01*
G01Y99516D02*
Y99369D01*
G01Y100867D02*
Y100720D01*
G01Y97717D02*
Y97570D01*
G01Y102666D02*
Y102519D01*
G01Y104016D02*
Y103869D01*
G01X1397028Y102519D02*
Y102666D01*
G01Y103869D02*
Y104016D01*
G01Y99369D02*
Y99516D01*
G01Y100720D02*
Y100867D01*
G01Y97570D02*
Y97717D01*
G01Y96220D02*
Y96367D01*
G01Y94420D02*
Y94567D01*
G01X1396988Y100866D02*
Y99370D01*
G01Y97717D02*
Y96220D01*
G01Y104016D02*
Y102520D01*
G01X1395807Y97559D02*
Y96378D01*
G01Y100709D02*
Y99528D01*
G01Y103858D02*
Y102677D01*
G01X1395079Y201909D02*
Y186161D01*
G01X1392047Y102677D02*
Y103858D01*
G01Y99528D02*
Y100709D01*
G01Y96378D02*
Y97559D01*
G01X1397972Y102703D02*
Y102714D01*
G01Y99554D02*
Y99564D01*
G01Y96404D02*
Y96415D01*
G01X1411398Y141978D02*
Y141981D01*
G01Y136978D02*
Y136981D01*
G01Y131978D02*
Y131981D01*
G01Y126978D02*
Y126981D01*
G01Y121978D02*
Y121981D01*
G01X1397931Y99528D02*
X1397935Y99516D01*
G01X1404724Y188720D02*
X1402414Y192950D01*
G01X1407087Y187028D02*
X1408390Y185059D01*
G01X1400197Y181319D02*
X1401378Y180138D01*
G01X1395079Y186161D02*
X1398425Y182815D01*
G01X1396875Y102717D02*
X1396987Y102708D01*
G01X1404724Y187028D02*
X1407087D01*
G01X1398425Y185059D02*
X1412795D01*
G01X1398425Y183681D02*
X1402165D01*
G01X1412795D02*
X1409646D01*
G01X1398425Y182815D02*
X1413386D01*
G01X1400197Y181319D02*
X1408071D01*
G01X1401378Y180138D02*
X1406890D01*
G01X1411398Y177500D02*
X1410413D01*
G01X1410415Y177008D02*
X1415748D01*
G01Y176969D02*
X1411400D01*
G01X1415748Y175630D02*
X1410415D01*
G01X1410413Y175138D02*
X1411398D01*
G01Y172500D02*
X1410413D01*
G01X1410415Y172008D02*
X1415748D01*
G01Y171969D02*
X1411400D01*
G01X1415748Y170630D02*
X1410415D01*
G01X1410413Y170138D02*
X1411398D01*
G01Y167500D02*
X1410413D01*
G01X1410415Y167008D02*
X1415748D01*
G01Y166969D02*
X1411400D01*
G01X1415748Y165630D02*
X1410415D01*
G01X1410413Y165138D02*
X1411398D01*
G01Y162500D02*
X1410413D01*
G01X1410415Y162008D02*
X1415748D01*
G01Y161969D02*
X1411400D01*
G01X1415748Y160630D02*
X1410415D01*
G01X1410413Y160138D02*
X1411398D01*
G01Y157500D02*
X1410413D01*
G01X1410415Y157008D02*
X1415748D01*
G01Y156969D02*
X1411400D01*
G01X1415748Y155630D02*
X1410415D01*
G01X1410413Y155138D02*
X1411398D01*
G01Y152500D02*
X1410413D01*
G01X1410415Y152008D02*
X1415748D01*
G01Y151969D02*
X1411400D01*
G01X1415748Y150630D02*
X1410415D01*
G01X1410413Y150138D02*
X1411398D01*
G01Y147500D02*
X1410413D01*
G01X1410415Y147008D02*
X1415748D01*
G01Y146969D02*
X1411400D01*
G01X1415748Y145630D02*
X1410415D01*
G01X1410413Y145138D02*
X1411398D01*
G01Y142500D02*
X1410413D01*
G01X1410415Y142008D02*
X1415748D01*
G01Y141969D02*
X1411400D01*
G01X1415748Y140630D02*
X1410415D01*
G01X1410413Y140138D02*
X1411398D01*
G01Y137500D02*
X1410413D01*
G01X1410415Y137008D02*
X1415748D01*
G01Y136969D02*
X1411400D01*
G01X1415748Y135630D02*
X1410415D01*
G01X1410413Y135138D02*
X1411398D01*
G01Y132500D02*
X1410413D01*
G01X1410415Y132008D02*
X1415748D01*
G01Y131969D02*
X1411400D01*
G01X1415748Y130630D02*
X1410415D01*
G01X1410413Y130138D02*
X1411398D01*
G01Y127500D02*
X1410413D01*
G01X1410415Y127008D02*
X1415748D01*
G01Y126969D02*
X1411400D01*
G01X1415748Y125630D02*
X1410415D01*
G01X1410413Y125138D02*
X1411398D01*
G01Y122500D02*
X1410413D01*
G01X1410415Y122008D02*
X1415748D01*
G01Y121969D02*
X1411400D01*
G01X1415748Y120630D02*
X1410415D01*
G01X1410413Y120138D02*
X1411398D01*
G01Y117500D02*
X1410413D01*
G01Y177204D02*
X1411369Y177205D01*
G01X1411398Y175434D02*
X1410413Y175433D01*
G01Y172204D02*
X1411369Y172205D01*
G01X1411398Y170434D02*
X1410413Y170433D01*
G01Y167204D02*
X1411369Y167205D01*
G01X1411398Y165434D02*
X1410413Y165433D01*
G01Y162204D02*
X1411369Y162205D01*
G01X1411398Y160434D02*
X1410413Y160433D01*
G01Y157204D02*
X1411369Y157205D01*
G01X1411398Y155434D02*
X1410413Y155433D01*
G01Y152204D02*
X1411369Y152205D01*
G01X1411398Y150434D02*
X1410413Y150433D01*
G01Y147204D02*
X1411369Y147205D01*
G01X1411398Y145434D02*
X1410413Y145433D01*
G01Y142204D02*
X1411369Y142205D01*
G01X1411398Y140434D02*
X1410413Y140433D01*
G01Y137204D02*
X1411369Y137205D01*
G01X1411398Y135434D02*
X1410413Y135433D01*
G01Y132204D02*
X1411369Y132205D01*
G01X1411398Y130434D02*
X1410413Y130433D01*
G01Y127204D02*
X1411369Y127205D01*
G01X1411398Y125434D02*
X1410413Y125433D01*
G01Y122204D02*
X1411369Y122205D01*
G01X1411398Y120434D02*
X1410413Y120433D01*
G01X1396986Y96414D02*
X1396875Y96417D01*
G01X1410415Y117008D02*
X1415748D01*
G01Y116969D02*
X1411400D01*
G01X1415748Y115630D02*
X1410415D01*
G01X1410413Y115138D02*
X1411398D01*
G01Y112500D02*
X1410413D01*
G01X1410415Y112008D02*
X1415748D01*
G01Y111969D02*
X1411400D01*
G01X1415748Y110630D02*
X1410415D01*
G01X1410413Y110138D02*
X1411398D01*
G01Y107500D02*
X1410413D01*
G01X1410415Y107008D02*
X1415748D01*
G01Y106969D02*
X1411400D01*
G01X1398425Y106024D02*
X1395079D01*
G01X1415748Y105630D02*
X1410415D01*
G01X1410413Y105138D02*
X1411398D01*
G01X1408071Y104862D02*
X1412008D01*
G01X1397933Y104055D02*
X1397028D01*
G01X1397972Y104016D02*
X1396988D01*
G01X1397931Y103858D02*
X1392047D01*
G01Y103819D02*
X1397971D01*
G01X1406890Y103681D02*
X1410827D01*
G01X1397971Y102717D02*
X1392047D01*
G01X1397931Y102677D02*
X1392047D01*
G01X1396988Y102520D02*
X1397972D01*
G01X1397028Y102480D02*
X1397933D01*
G01Y100906D02*
X1397028D01*
G01X1397972Y100866D02*
X1396988D01*
G01X1397931Y100709D02*
X1392047D01*
G01Y100669D02*
X1397971D01*
G01Y99567D02*
X1392047D01*
G01X1397931Y99528D02*
X1392047D01*
G01X1396988Y99370D02*
X1397972D01*
G01X1397028Y99331D02*
X1397933D01*
G01Y97756D02*
X1397028D01*
G01X1397972Y97717D02*
X1396988D01*
G01X1397931Y97559D02*
X1392047D01*
G01Y97520D02*
X1397971D01*
G01X1396241Y96417D02*
X1395807D01*
G01X1397971D02*
X1392047D01*
G01X1397931Y96378D02*
X1392047D01*
G01X1396988Y96220D02*
X1397972D01*
G01X1397028Y96181D02*
X1397933D01*
G01Y94606D02*
X1397028D01*
G01X1397972Y94567D02*
X1396988D01*
G01X1397931Y94409D02*
X1392047D01*
G01Y94370D02*
X1397971D01*
G01X1410413Y117204D02*
X1411369Y117205D01*
G01X1411398Y115434D02*
X1410413Y115433D01*
G01Y112204D02*
X1411369Y112205D01*
G01X1411398Y110434D02*
X1410413Y110433D01*
G01Y107204D02*
X1411369Y107205D01*
G01X1411398Y105434D02*
X1410413Y105433D01*
G01X1365945Y260630D02*
G03X1367126I590J0D01*
G01Y254331D02*
G03X1365945I-591J0D01*
G01X1363976D02*
G03X1362795I-591J0D01*
G01Y260630D02*
G03X1363976I591J0D01*
G01X1365945D02*
G03X1367126I590J0D01*
G01Y254331D02*
G03X1365945I-591J0D01*
G01X1363976D02*
G03X1362795I-591J0D01*
G01Y260630D02*
G03X1363976I591J0D01*
G01X1409843Y202500D02*
G03X1409252Y203091I-591J0D01*
G01X1402559D02*
G03X1401969Y202500I1J-591D01*
G01X1404724Y201319D02*
G03Y199350I0J-985D01*
G01X1407087D02*
G03Y201319I0J984D01*
G01X1403346Y193406D02*
G03X1402165Y192224I0J-1181D01*
G01X1409646D02*
G03X1408465Y193406I-1181J1D01*
G01X1416732Y201909D02*
G03X1414764Y203878I-1968J1D01*
G01X1397047D02*
G03X1395079Y201909I0J-1968D01*
G01X1409843Y196398D02*
Y202500D01*
G01X1401969Y196398D02*
Y202500D01*
G01X1367913Y254331D02*
Y260630D01*
G01Y254331D02*
Y260630D01*
G01X1362008Y254331D02*
Y260630D01*
G01D02*
Y254331D01*
G01X1365945Y260630D02*
X1363976D01*
G01X1362795D02*
X1362008D01*
G01X1365945D02*
X1363976D01*
G01X1362795D02*
X1362008D01*
G01X1367913D02*
X1367126D01*
G01X1367913D02*
X1367126D01*
G01X1367913Y259646D02*
X1362008D01*
G01Y259449D02*
X1367913D01*
G01X1362008Y255512D02*
X1367913D01*
G01Y255315D02*
X1362008D01*
G01X1367126Y254331D02*
X1367913D01*
G01X1367126D02*
X1367913D01*
G01X1363976D02*
X1365945D01*
G01X1362008D02*
X1362795D01*
G01X1363976D02*
X1365945D01*
G01X1362008D02*
X1362795D01*
G01X1414764Y203878D02*
X1397047D01*
G01X1409252Y203091D02*
X1402559D01*
G01X1407087Y201319D02*
X1404724D01*
G01Y199350D02*
X1407087D01*
G01X1409843Y197972D02*
X1401969D01*
G01Y196398D02*
X1409843D01*
G01X1416732Y193445D02*
X1395079D01*
G01X1403346Y193406D02*
X1408465D01*
G01X1404724Y188720D02*
X1407087D01*
G01X1396991Y537697D02*
X1396986Y537677D01*
G01X1397006Y537711D02*
X1396991Y537697D01*
G01X1397025Y537717D02*
X1397006Y537711D01*
G01X1396991Y540846D02*
X1396986Y540827D01*
G01X1397006Y540861D02*
X1396991Y540846D01*
G01X1397025Y540866D02*
X1397006Y540861D01*
G01X1396991Y543996D02*
X1396986Y543976D01*
G01X1397006Y544010D02*
X1396991Y543996D01*
G01X1397025Y544016D02*
X1397006Y544010D01*
G01X1396991Y547146D02*
X1396986Y547126D01*
G01X1397006Y547160D02*
X1396991Y547146D01*
G01X1397025Y547165D02*
X1397006Y547160D01*
G01X1397966Y536555D02*
X1397971Y536575D01*
G01X1397951Y536541D02*
X1397966Y536555D01*
G01X1397931Y536535D02*
X1397951Y536541D01*
G01X1397966Y539705D02*
X1397971Y539724D01*
G01X1397951Y539690D02*
X1397966Y539705D01*
G01X1397931Y539685D02*
X1397951Y539690D01*
G01X1397966Y542854D02*
X1397971Y542874D01*
G01X1397951Y542840D02*
X1397966Y542854D01*
G01X1397931Y542835D02*
X1397951Y542840D01*
G01X1397966Y546004D02*
X1397971Y546024D01*
G01X1397951Y545989D02*
X1397966Y546004D01*
G01X1397931Y545984D02*
X1397951Y545989D01*
G01X1397966Y549154D02*
X1397971Y549173D01*
G01X1397951Y549139D02*
X1397966Y549154D01*
G01X1397931Y549134D02*
X1397951Y549139D01*
G01X1396991Y550295D02*
X1396986Y550276D01*
G01X1397006Y550309D02*
X1396991Y550295D01*
G01X1397025Y550315D02*
X1397006Y550309D01*
G01X1396991Y553445D02*
X1396986Y553425D01*
G01X1397006Y553459D02*
X1396991Y553445D01*
G01X1397025Y553465D02*
X1397006Y553459D01*
G01X1396991Y556594D02*
X1396986Y556575D01*
G01X1397006Y556609D02*
X1396991Y556594D01*
G01X1397025Y556614D02*
X1397006Y556609D01*
G01X1397966Y552303D02*
X1397971Y552323D01*
G01X1397951Y552289D02*
X1397966Y552303D01*
G01X1397931Y552283D02*
X1397951Y552289D01*
G01X1397966Y555453D02*
X1397971Y555472D01*
G01X1397951Y555438D02*
X1397966Y555453D01*
G01X1397931Y555433D02*
X1397951Y555438D01*
G01X1397972Y552302D02*
Y552309D01*
G01X1397969Y552295D02*
X1397972Y552302D01*
G01X1397966Y552289D02*
X1397969Y552295D01*
G01X1397961Y552283D02*
X1397966Y552289D01*
G01X1397955Y552278D02*
X1397961Y552283D01*
G01X1397948Y552275D02*
X1397955Y552278D01*
G01X1397941Y552273D02*
X1397948Y552275D01*
G01X1397933Y552272D02*
X1397941Y552273D01*
G01X1397950Y536528D02*
X1397953Y536530D01*
G01X1397947Y536526D02*
X1397950Y536528D01*
G01X1397944Y536526D02*
X1397947D01*
G01X1397940Y536525D02*
X1397944Y536526D01*
G01X1397937Y536524D02*
X1397940Y536525D01*
G01X1397933Y536524D02*
X1397937D01*
G01X1397011Y537724D02*
X1397007Y537722D01*
G01X1397014Y537725D02*
X1397011Y537724D01*
G01X1397017Y537726D02*
X1397014Y537725D01*
G01X1397020Y537727D02*
X1397017Y537726D01*
G01X1397024Y537728D02*
X1397020Y537727D01*
G01X1397028Y537728D02*
X1397024D01*
G01X1397950Y539677D02*
X1397953Y539679D01*
G01X1397947Y539676D02*
X1397950Y539677D01*
G01X1397944Y539675D02*
X1397947Y539676D01*
G01X1397940Y539674D02*
X1397944Y539675D01*
G01X1397937Y539674D02*
X1397940D01*
G01X1397933D02*
X1397937D01*
G01X1397011Y540874D02*
X1397007Y540872D01*
G01X1397014Y540875D02*
X1397011Y540874D01*
G01X1397017Y540876D02*
X1397014Y540875D01*
G01X1397020Y540877D02*
X1397017Y540876D01*
G01X1397024Y540877D02*
X1397020D01*
G01X1397028D02*
X1397024D01*
G01X1397950Y542827D02*
X1397953Y542829D01*
G01X1397947Y542826D02*
X1397950Y542827D01*
G01X1397944Y542825D02*
X1397947Y542826D01*
G01X1397940Y542824D02*
X1397944Y542825D01*
G01X1397937Y542824D02*
X1397940D01*
G01X1397933Y542823D02*
X1397937Y542824D01*
G01X1397011Y544023D02*
X1397007Y544022D01*
G01X1397014Y544024D02*
X1397011Y544023D01*
G01X1397017Y544026D02*
X1397014Y544024D01*
G01X1397020Y544026D02*
X1397017D01*
G01X1397024Y544027D02*
X1397020Y544026D01*
G01X1397028Y544027D02*
X1397024D01*
G01X1397950Y545976D02*
X1397953Y545978D01*
G01X1397947Y545975D02*
X1397950Y545976D01*
G01X1397944Y545974D02*
X1397947Y545975D01*
G01X1397940Y545974D02*
X1397944D01*
G01X1397937Y545973D02*
X1397940Y545974D01*
G01X1397933Y545973D02*
X1397937D01*
G01X1397011Y547173D02*
X1397007Y547171D01*
G01X1397014Y547174D02*
X1397011Y547173D01*
G01X1397017Y547175D02*
X1397014Y547174D01*
G01X1397020Y547176D02*
X1397017Y547175D01*
G01X1397024Y547176D02*
X1397020D01*
G01X1397028D02*
X1397024D01*
G01X1397950Y549126D02*
X1397953Y549128D01*
G01X1397947Y549125D02*
X1397950Y549126D01*
G01X1397944Y549124D02*
X1397947Y549125D01*
G01X1397940Y549123D02*
X1397944Y549124D01*
G01X1397937Y549123D02*
X1397940D01*
G01X1397933Y549122D02*
X1397937Y549123D01*
G01X1397011Y550322D02*
X1397007Y550321D01*
G01X1397014Y550324D02*
X1397011Y550322D01*
G01X1397017Y550325D02*
X1397014Y550324D01*
G01X1397020Y550326D02*
X1397017Y550325D01*
G01X1397024Y550326D02*
X1397020D01*
G01X1397028D02*
X1397024D01*
G01X1397011Y553472D02*
X1397007Y553470D01*
G01X1397014Y553473D02*
X1397011Y553472D01*
G01X1397017Y553474D02*
X1397014Y553473D01*
G01X1397020Y553475D02*
X1397017Y553474D01*
G01X1397024Y553476D02*
X1397020Y553475D01*
G01X1397028Y553476D02*
X1397024D01*
G01X1397950Y555425D02*
X1397953Y555427D01*
G01X1397947Y555424D02*
X1397950Y555425D01*
G01X1397944Y555423D02*
X1397947Y555424D01*
G01X1397940Y555422D02*
X1397944Y555423D01*
G01X1397937Y555422D02*
X1397940D01*
G01X1397933D02*
X1397937D01*
G01X1397011Y556622D02*
X1397007Y556620D01*
G01X1397014Y556623D02*
X1397011Y556622D01*
G01X1397017Y556624D02*
X1397014Y556623D01*
G01X1397020Y556625D02*
X1397017Y556624D01*
G01X1397024Y556625D02*
X1397020D01*
G01X1397028D02*
X1397024D01*
G01X1397963Y537715D02*
X1397967Y537709D01*
G01X1397958Y537719D02*
X1397963Y537715D01*
G01X1397952Y537723D02*
X1397958Y537719D01*
G01X1397946Y537726D02*
X1397952Y537723D01*
G01X1397940Y537727D02*
X1397946Y537726D01*
G01X1397933Y537728D02*
X1397940Y537727D01*
G01X1397963Y540865D02*
X1397967Y540859D01*
G01X1397958Y540869D02*
X1397963Y540865D01*
G01X1397952Y540872D02*
X1397958Y540869D01*
G01X1397946Y540875D02*
X1397952Y540872D01*
G01X1397940Y540877D02*
X1397946Y540875D01*
G01X1397933Y540877D02*
X1397940D01*
G01X1397963Y544014D02*
X1397967Y544009D01*
G01X1397958Y544019D02*
X1397963Y544014D01*
G01X1397952Y544022D02*
X1397958Y544019D01*
G01X1397946Y544025D02*
X1397952Y544022D01*
G01X1397940Y544026D02*
X1397946Y544025D01*
G01X1397933Y544027D02*
X1397940Y544026D01*
G01X1397963Y547164D02*
X1397967Y547158D01*
G01X1397958Y547168D02*
X1397963Y547164D01*
G01X1397952Y547172D02*
X1397958Y547168D01*
G01X1397946Y547174D02*
X1397952Y547172D01*
G01X1397940Y547176D02*
X1397946Y547174D01*
G01X1397933Y547176D02*
X1397940D01*
G01X1397963Y550313D02*
X1397967Y550308D01*
G01X1397958Y550318D02*
X1397963Y550313D01*
G01X1397952Y550321D02*
X1397958Y550318D01*
G01X1397946Y550324D02*
X1397952Y550321D01*
G01X1397940Y550326D02*
X1397946Y550324D01*
G01X1397933Y550326D02*
X1397940D01*
G01X1397963Y553463D02*
X1397967Y553457D01*
G01X1397958Y553467D02*
X1397963Y553463D01*
G01X1397952Y553471D02*
X1397958Y553467D01*
G01X1397946Y553474D02*
X1397952Y553471D01*
G01X1397940Y553475D02*
X1397946Y553474D01*
G01X1397933Y553476D02*
X1397940Y553475D01*
G01X1397963Y556613D02*
X1397967Y556607D01*
G01X1397958Y556617D02*
X1397963Y556613D01*
G01X1397952Y556620D02*
X1397958Y556617D01*
G01X1397946Y556623D02*
X1397952Y556620D01*
G01X1397940Y556625D02*
X1397946Y556623D01*
G01X1397933Y556625D02*
X1397940D01*
G01X1396989Y536554D02*
X1396988Y536561D01*
G01X1396991Y536547D02*
X1396989Y536554D01*
G01X1396995Y536541D02*
X1396991Y536547D01*
G01X1397000Y536535D02*
X1396995Y536541D01*
G01X1397006Y536530D02*
X1397000Y536535D01*
G01X1397013Y536527D02*
X1397006Y536530D01*
G01X1397020Y536525D02*
X1397013Y536527D01*
G01X1397028Y536524D02*
X1397020Y536525D01*
G01X1396989Y539704D02*
X1396988Y539711D01*
G01X1396991Y539696D02*
X1396989Y539704D01*
G01X1396995Y539690D02*
X1396991Y539696D01*
G01X1397000Y539685D02*
X1396995Y539690D01*
G01X1397006Y539680D02*
X1397000Y539685D01*
G01X1397013Y539676D02*
X1397006Y539680D01*
G01X1397020Y539674D02*
X1397013Y539676D01*
G01X1397028Y539674D02*
X1397020D01*
G01X1396989Y542853D02*
X1396988Y542860D01*
G01X1396991Y542846D02*
X1396989Y542853D01*
G01X1396995Y542840D02*
X1396991Y542846D01*
G01X1397000Y542834D02*
X1396995Y542840D01*
G01X1397006Y542830D02*
X1397000Y542834D01*
G01X1397013Y542826D02*
X1397006Y542830D01*
G01X1397020Y542824D02*
X1397013Y542826D01*
G01X1397028Y542823D02*
X1397020Y542824D01*
G01X1396989Y546003D02*
X1396988Y546010D01*
G01X1396991Y545996D02*
X1396989Y546003D01*
G01X1396995Y545989D02*
X1396991Y545996D01*
G01X1397000Y545984D02*
X1396995Y545989D01*
G01X1397006Y545979D02*
X1397000Y545984D01*
G01X1397013Y545976D02*
X1397006Y545979D01*
G01X1397020Y545974D02*
X1397013Y545976D01*
G01X1397028Y545973D02*
X1397020Y545974D01*
G01X1396989Y549152D02*
X1396988Y549159D01*
G01X1396991Y549145D02*
X1396989Y549152D01*
G01X1396995Y549139D02*
X1396991Y549145D01*
G01X1397000Y549133D02*
X1396995Y549139D01*
G01X1397006Y549129D02*
X1397000Y549133D01*
G01X1397013Y549125D02*
X1397006Y549129D01*
G01X1397020Y549123D02*
X1397013Y549125D01*
G01X1397028Y549122D02*
X1397020Y549123D01*
G01X1396989Y552302D02*
X1396988Y552309D01*
G01X1396991Y552295D02*
X1396989Y552302D01*
G01X1396995Y552289D02*
X1396991Y552295D01*
G01X1397000Y552283D02*
X1396995Y552289D01*
G01X1397006Y552278D02*
X1397000Y552283D01*
G01X1397013Y552275D02*
X1397006Y552278D01*
G01X1397020Y552273D02*
X1397013Y552275D01*
G01X1397028Y552272D02*
X1397020Y552273D01*
G01X1396989Y555452D02*
X1396988Y555459D01*
G01X1396991Y555444D02*
X1396989Y555452D01*
G01X1396995Y555438D02*
X1396991Y555444D01*
G01X1397000Y555433D02*
X1396995Y555438D01*
G01X1397006Y555428D02*
X1397000Y555433D01*
G01X1397013Y555424D02*
X1397006Y555428D01*
G01X1397020Y555422D02*
X1397013Y555424D01*
G01X1397028Y555422D02*
X1397020D01*
G01X1397942Y537715D02*
X1397952Y537711D01*
G01X1397931Y537717D02*
X1397942Y537715D01*
G01Y540865D02*
X1397952Y540861D01*
G01X1397931Y540866D02*
X1397942Y540865D01*
G01Y544014D02*
X1397952Y544010D01*
G01X1397931Y544016D02*
X1397942Y544014D01*
G01Y547164D02*
X1397952Y547160D01*
G01X1397931Y547165D02*
X1397942Y547164D01*
G01Y550313D02*
X1397952Y550309D01*
G01X1397931Y550315D02*
X1397942Y550313D01*
G01Y553463D02*
X1397952Y553459D01*
G01X1397931Y553465D02*
X1397942Y553463D01*
G01Y556613D02*
X1397952Y556609D01*
G01X1397931Y556614D02*
X1397942Y556613D01*
G01X1396988Y539715D02*
Y539711D01*
G01X1396990Y539708D02*
X1396988Y539715D01*
G01X1397002Y539693D02*
X1396990Y539708D01*
G01X1397026Y539685D02*
X1397002Y539693D01*
G01X1396988Y542864D02*
Y542860D01*
G01X1396990Y542858D02*
X1396988Y542864D01*
G01X1397001Y542843D02*
X1396990Y542858D01*
G01X1397026Y542835D02*
X1397001Y542843D01*
G01X1396988Y536565D02*
Y536561D01*
G01X1396990Y536559D02*
X1396988Y536565D01*
G01X1397001Y536544D02*
X1396990Y536559D01*
G01X1397026Y536535D02*
X1397001Y536544D01*
G01X1411385Y504755D02*
X1411396Y504740D01*
G01X1411361Y504764D02*
X1411385Y504755D01*
G01Y509755D02*
X1411396Y509740D01*
G01X1411361Y509764D02*
X1411385Y509755D01*
G01Y514755D02*
X1411396Y514740D01*
G01X1411361Y514764D02*
X1411385Y514755D01*
G01Y519755D02*
X1411396Y519740D01*
G01X1411361Y519764D02*
X1411385Y519755D01*
G01Y524755D02*
X1411396Y524740D01*
G01X1411361Y524764D02*
X1411385Y524755D01*
G01Y529755D02*
X1411396Y529740D01*
G01X1411361Y529764D02*
X1411385Y529755D01*
G01X1396988Y549163D02*
Y549159D01*
G01X1396990Y549157D02*
X1396988Y549163D01*
G01X1397001Y549142D02*
X1396990Y549157D01*
G01X1397026Y549134D02*
X1397001Y549142D01*
G01X1396988Y552313D02*
Y552309D01*
G01X1396990Y552307D02*
X1396988Y552313D01*
G01X1397001Y552292D02*
X1396990Y552307D01*
G01X1397026Y552283D02*
X1397001Y552292D01*
G01X1396988Y555463D02*
Y555459D01*
G01X1396990Y555457D02*
X1396988Y555463D01*
G01X1397001Y555441D02*
X1396990Y555457D01*
G01X1397026Y555433D02*
X1397001Y555441D01*
G01X1411385Y534755D02*
X1411396Y534740D01*
G01X1411361Y534764D02*
X1411385Y534755D01*
G01Y559755D02*
X1411396Y559740D01*
G01X1411361Y559764D02*
X1411385Y559755D01*
G01Y564755D02*
X1411396Y564740D01*
G01X1411361Y564764D02*
X1411385Y564755D01*
G01Y569755D02*
X1411396Y569740D01*
G01X1411361Y569764D02*
X1411385Y569755D01*
G01X1396988Y546014D02*
Y546010D01*
G01X1396990Y546008D02*
X1396988Y546014D01*
G01X1397000Y545994D02*
X1396990Y546008D01*
G01X1397023Y545984D02*
X1397000Y545994D01*
G01X1397941Y544015D02*
X1397931Y544016D01*
G01X1397950Y544011D02*
X1397941Y544015D01*
G01X1397957Y544006D02*
X1397950Y544011D01*
G01X1397941Y537715D02*
X1397931Y537717D01*
G01X1397950Y537712D02*
X1397941Y537715D01*
G01X1397957Y537707D02*
X1397950Y537712D01*
G01X1397941Y540865D02*
X1397931Y540866D01*
G01X1397950Y540862D02*
X1397941Y540865D01*
G01X1397957Y540856D02*
X1397950Y540862D01*
G01X1397941Y547164D02*
X1397931Y547165D01*
G01X1397950Y547161D02*
X1397941Y547164D01*
G01X1397957Y547156D02*
X1397950Y547161D01*
G01X1397941Y550314D02*
X1397931Y550315D01*
G01X1397950Y550311D02*
X1397941Y550314D01*
G01X1397957Y550305D02*
X1397950Y550311D01*
G01X1397941Y553463D02*
X1397931Y553465D01*
G01X1397950Y553460D02*
X1397941Y553463D01*
G01X1397957Y553455D02*
X1397950Y553460D01*
G01X1397941Y556613D02*
X1397931Y556614D01*
G01X1397950Y556610D02*
X1397941Y556613D01*
G01X1397957Y556604D02*
X1397950Y556610D01*
G01X1397027Y536530D02*
X1397028Y536524D01*
G01X1397026Y536534D02*
X1397027Y536530D01*
G01X1397025Y536535D02*
X1397026Y536534D01*
G01X1397027Y539680D02*
X1397028Y539674D01*
G01X1397026Y539684D02*
X1397027Y539680D01*
G01X1397025Y539685D02*
X1397026Y539684D01*
G01X1397027Y542830D02*
X1397028Y542823D01*
G01X1397026Y542833D02*
X1397027Y542830D01*
G01X1397025Y542835D02*
X1397026Y542833D01*
G01X1397027Y545979D02*
X1397028Y545973D01*
G01X1397026Y545983D02*
X1397027Y545979D01*
G01X1397025Y545984D02*
X1397026Y545983D01*
G01X1397027Y549129D02*
X1397028Y549122D01*
G01X1397026Y549133D02*
X1397027Y549129D01*
G01X1397025Y549134D02*
X1397026Y549133D01*
G01X1397027Y552278D02*
X1397028Y552272D01*
G01X1397026Y552282D02*
X1397027Y552278D01*
G01X1397025Y552283D02*
X1397026Y552282D01*
G01X1397027Y555428D02*
X1397028Y555422D01*
G01X1397026Y555432D02*
X1397027Y555428D01*
G01X1397025Y555433D02*
X1397026Y555432D01*
G01X1411398Y504731D02*
Y504738D01*
G01X1411399Y504726D02*
X1411398Y504731D01*
G01X1411400Y504724D02*
X1411399Y504726D01*
G01X1411398Y509731D02*
Y509738D01*
G01X1411399Y509726D02*
X1411398Y509731D01*
G01X1411400Y509724D02*
X1411399Y509726D01*
G01X1411398Y514731D02*
Y514738D01*
G01X1411399Y514726D02*
X1411398Y514731D01*
G01X1411400Y514724D02*
X1411399Y514726D01*
G01X1411398Y519731D02*
Y519738D01*
G01X1411399Y519726D02*
X1411398Y519731D01*
G01X1411400Y519724D02*
X1411399Y519726D01*
G01X1411398Y524731D02*
Y524738D01*
G01X1411399Y524726D02*
X1411398Y524731D01*
G01X1411400Y524724D02*
X1411399Y524726D01*
G01X1411398Y529731D02*
Y529738D01*
G01X1411399Y529726D02*
X1411398Y529731D01*
G01X1411400Y529724D02*
X1411399Y529726D01*
G01X1411398Y534731D02*
Y534738D01*
G01X1411399Y534726D02*
X1411398Y534731D01*
G01X1411400Y534724D02*
X1411399Y534726D01*
G01X1411398Y559731D02*
Y559738D01*
G01X1411399Y559726D02*
X1411398Y559731D01*
G01X1411400Y559724D02*
X1411399Y559726D01*
G01X1411398Y564731D02*
Y564738D01*
G01X1411399Y564726D02*
X1411398Y564731D01*
G01X1411400Y564724D02*
X1411399Y564726D01*
G01X1411398Y569731D02*
Y569738D01*
G01X1411399Y569726D02*
X1411398Y569731D01*
G01X1411400Y569724D02*
X1411399Y569726D01*
G01X1397011Y539687D02*
X1397025Y539685D01*
G01X1397000Y539694D02*
X1397011Y539687D01*
G01X1396987Y539713D02*
X1397000Y539694D01*
G01X1397011Y549136D02*
X1397025Y549134D01*
G01X1396999Y549144D02*
X1397011Y549136D01*
G01X1396987Y549162D02*
X1396999Y549144D01*
G01X1397011Y542837D02*
X1397025Y542835D01*
G01X1396998Y542845D02*
X1397011Y542837D01*
G01X1396987Y542865D02*
X1396998Y542845D01*
G01X1397011Y552286D02*
X1397025Y552283D01*
G01X1396998Y552294D02*
X1397011Y552286D01*
G01X1396987Y552314D02*
X1396998Y552294D01*
G01X1397972Y536569D02*
Y536561D01*
G01Y536573D02*
Y536569D01*
G01X1397971Y536575D02*
X1397972Y536573D01*
G01Y539719D02*
Y539711D01*
G01Y539723D02*
Y539719D01*
G01X1397971Y539724D02*
X1397972Y539723D01*
G01Y542868D02*
Y542860D01*
G01Y542872D02*
Y542868D01*
G01X1397971Y542874D02*
X1397972Y542872D01*
G01Y546018D02*
Y546010D01*
G01Y546022D02*
Y546018D01*
G01X1397971Y546024D02*
X1397972Y546022D01*
G01Y549167D02*
Y549159D01*
G01Y549172D02*
Y549167D01*
G01X1397971Y549173D02*
X1397972Y549172D01*
G01Y552317D02*
Y552309D01*
G01Y552321D02*
Y552317D01*
G01X1397971Y552323D02*
X1397972Y552321D01*
G01Y555467D02*
Y555459D01*
G01Y555471D02*
Y555467D01*
G01X1397971Y555472D02*
X1397972Y555471D01*
G01X1397011Y555436D02*
X1397025Y555433D01*
G01X1396998Y555444D02*
X1397011Y555436D01*
G01X1396987Y555464D02*
X1396998Y555444D01*
G01X1397010Y536538D02*
X1397025Y536535D01*
G01X1396997Y536547D02*
X1397010Y536538D01*
G01X1396987Y536567D02*
X1396997Y536547D01*
G01X1397972Y537697D02*
Y537691D01*
G01X1397970Y537704D02*
X1397972Y537697D01*
G01X1397967Y537709D02*
X1397970Y537704D01*
G01X1397972Y540847D02*
Y540840D01*
G01X1397970Y540853D02*
X1397972Y540847D01*
G01X1397967Y540859D02*
X1397970Y540853D01*
G01X1397972Y543996D02*
Y543990D01*
G01X1397970Y544003D02*
X1397972Y543996D01*
G01X1397967Y544009D02*
X1397970Y544003D01*
G01X1397972Y547146D02*
Y547139D01*
G01X1397970Y547152D02*
X1397972Y547146D01*
G01X1397967Y547158D02*
X1397970Y547152D01*
G01X1397972Y550296D02*
Y550289D01*
G01X1397970Y550302D02*
X1397972Y550296D01*
G01X1397967Y550308D02*
X1397970Y550302D01*
G01X1397972Y553445D02*
Y553439D01*
G01X1397970Y553452D02*
X1397972Y553445D01*
G01X1397967Y553457D02*
X1397970Y553452D01*
G01X1397972Y556595D02*
Y556588D01*
G01X1397970Y556601D02*
X1397972Y556595D01*
G01X1397967Y556607D02*
X1397970Y556601D01*
G01X1397933Y536530D02*
X1397934Y536524D01*
G01X1397932Y536534D02*
X1397933Y536530D01*
G01X1397931Y536535D02*
X1397932Y536534D01*
G01X1397933Y539680D02*
X1397934Y539674D01*
G01X1397932Y539683D02*
X1397933Y539680D01*
G01X1397931Y539685D02*
X1397932Y539683D01*
G01X1397933Y542830D02*
X1397934Y542823D01*
G01X1397932Y542833D02*
X1397933Y542830D01*
G01X1397931Y542835D02*
X1397932Y542833D01*
G01X1397933Y545979D02*
X1397934Y545973D01*
G01X1397932Y545983D02*
X1397933Y545979D01*
G01X1397931Y545984D02*
X1397932Y545983D01*
G01X1397933Y549129D02*
X1397934Y549122D01*
G01X1397932Y549132D02*
X1397933Y549129D01*
G01X1397931Y549134D02*
X1397932Y549132D01*
G01X1397933Y555428D02*
X1397934Y555422D01*
G01X1397932Y555431D02*
X1397933Y555428D01*
G01X1397931Y555433D02*
X1397932Y555431D01*
G01X1410413Y504771D02*
Y504780D01*
G01X1410414Y504765D02*
X1410413Y504771D01*
G01X1410415Y504764D02*
X1410414Y504765D01*
G01X1410413Y509771D02*
Y509780D01*
G01X1410414Y509765D02*
X1410413Y509771D01*
G01X1410415Y509764D02*
X1410414Y509765D01*
G01X1410413Y514771D02*
Y514780D01*
G01X1410414Y514765D02*
X1410413Y514771D01*
G01X1410415Y514764D02*
X1410414Y514765D01*
G01X1410413Y519771D02*
Y519780D01*
G01X1410414Y519765D02*
X1410413Y519771D01*
G01X1410415Y519764D02*
X1410414Y519765D01*
G01X1410413Y524771D02*
Y524780D01*
G01X1410414Y524765D02*
X1410413Y524771D01*
G01X1410415Y524764D02*
X1410414Y524765D01*
G01X1410413Y529771D02*
Y529780D01*
G01X1410414Y529765D02*
X1410413Y529771D01*
G01X1410415Y529764D02*
X1410414Y529765D01*
G01X1410413Y534771D02*
Y534780D01*
G01X1410414Y534765D02*
X1410413Y534771D01*
G01X1410415Y534764D02*
X1410414Y534765D01*
G01X1410413Y559771D02*
Y559780D01*
G01X1410414Y559765D02*
X1410413Y559771D01*
G01X1410415Y559764D02*
X1410414Y559765D01*
G01X1410413Y564771D02*
Y564780D01*
G01X1410414Y564765D02*
X1410413Y564771D01*
G01X1410415Y564764D02*
X1410414Y564765D01*
G01X1410413Y569771D02*
Y569780D01*
G01X1410414Y569765D02*
X1410413Y569771D01*
G01X1410415Y569764D02*
X1410414Y569765D01*
G01X1411390Y504907D02*
X1411398Y504881D01*
G01X1411380Y504934D02*
X1411390Y504907D01*
G01X1411369Y504961D02*
X1411380Y504934D01*
G01X1411390Y509907D02*
X1411398Y509881D01*
G01X1411380Y509934D02*
X1411390Y509907D01*
G01X1411369Y509961D02*
X1411380Y509934D01*
G01X1411390Y514907D02*
X1411398Y514881D01*
G01X1411380Y514934D02*
X1411390Y514907D01*
G01X1411369Y514961D02*
X1411380Y514934D01*
G01X1411390Y519907D02*
X1411398Y519881D01*
G01X1411380Y519934D02*
X1411390Y519907D01*
G01X1411369Y519961D02*
X1411380Y519934D01*
G01X1411390Y524907D02*
X1411398Y524881D01*
G01X1411380Y524934D02*
X1411390Y524907D01*
G01X1411369Y524961D02*
X1411380Y524934D01*
G01X1411390Y529907D02*
X1411398Y529881D01*
G01X1411380Y529934D02*
X1411390Y529907D01*
G01X1411369Y529961D02*
X1411380Y529934D01*
G01X1411390Y534907D02*
X1411398Y534881D01*
G01X1411380Y534934D02*
X1411390Y534907D01*
G01X1411369Y534961D02*
X1411380Y534934D01*
G01X1411390Y559907D02*
X1411398Y559881D01*
G01X1411380Y559934D02*
X1411390Y559907D01*
G01X1411369Y559961D02*
X1411380Y559934D01*
G01X1411390Y564907D02*
X1411398Y564881D01*
G01X1411380Y564934D02*
X1411390Y564907D01*
G01X1411369Y564961D02*
X1411380Y564934D01*
G01X1411390Y569907D02*
X1411398Y569881D01*
G01X1411380Y569934D02*
X1411390Y569907D01*
G01X1411369Y569961D02*
X1411380Y569934D01*
G01X1397006Y545989D02*
X1397025Y545984D01*
G01X1396993Y546002D02*
X1397006Y545989D01*
G01X1396986Y546019D02*
X1396993Y546002D01*
G01X1397027Y556619D02*
Y556625D01*
G01Y556615D02*
Y556619D01*
G01X1397025Y556614D02*
X1397027Y556615D01*
G01Y553469D02*
Y553476D01*
G01Y553466D02*
Y553469D01*
G01X1397025Y553465D02*
X1397027Y553466D01*
G01X1396989Y556594D02*
X1396988Y556588D01*
G01X1396991Y556601D02*
X1396989Y556594D01*
G01X1396993Y556607D02*
X1396991Y556601D01*
G01X1396997Y556612D02*
X1396993Y556607D01*
G01X1397002Y556617D02*
X1396997Y556612D01*
G01X1397007Y556620D02*
X1397002Y556617D01*
G01X1396989Y553445D02*
X1396988Y553439D01*
G01X1396991Y553451D02*
X1396989Y553445D01*
G01X1396993Y553457D02*
X1396991Y553451D01*
G01X1396997Y553462D02*
X1396993Y553457D01*
G01X1397002Y553467D02*
X1396997Y553462D01*
G01X1397007Y553470D02*
X1397002Y553467D01*
G01X1396989Y550295D02*
X1396988Y550289D01*
G01X1396991Y550302D02*
X1396989Y550295D01*
G01X1396993Y550307D02*
X1396991Y550302D01*
G01X1396997Y550313D02*
X1396993Y550307D01*
G01X1397002Y550317D02*
X1396997Y550313D01*
G01X1397007Y550321D02*
X1397002Y550317D01*
G01X1396989Y547146D02*
X1396988Y547139D01*
G01X1396991Y547152D02*
X1396989Y547146D01*
G01X1396993Y547158D02*
X1396991Y547152D01*
G01X1396997Y547163D02*
X1396993Y547158D01*
G01X1397002Y547168D02*
X1396997Y547163D01*
G01X1397007Y547171D02*
X1397002Y547168D01*
G01X1397944Y555435D02*
X1397931Y555433D01*
G01X1397954Y555440D02*
X1397944Y555435D01*
G01Y552285D02*
X1397931Y552283D01*
G01X1397954Y552290D02*
X1397944Y552285D01*
G01Y549136D02*
X1397931Y549134D01*
G01X1397954Y549141D02*
X1397944Y549136D01*
G01Y545986D02*
X1397931Y545984D01*
G01X1397954Y545991D02*
X1397944Y545986D01*
G01Y542837D02*
X1397931Y542835D01*
G01X1397954Y542841D02*
X1397944Y542837D01*
G01Y539687D02*
X1397931Y539685D01*
G01X1397954Y539692D02*
X1397944Y539687D01*
G01Y536537D02*
X1397931Y536535D01*
G01X1397954Y536542D02*
X1397944Y536537D01*
G01X1411380Y504759D02*
X1411361Y504764D01*
G01X1411395Y504744D02*
X1411380Y504759D01*
G01X1411400Y504724D02*
X1411395Y504744D01*
G01X1411380Y509759D02*
X1411361Y509764D01*
G01X1411395Y509744D02*
X1411380Y509759D01*
G01X1411400Y509724D02*
X1411395Y509744D01*
G01X1411380Y514759D02*
X1411361Y514764D01*
G01X1411395Y514744D02*
X1411380Y514759D01*
G01X1411400Y514724D02*
X1411395Y514744D01*
G01X1411380Y519759D02*
X1411361Y519764D01*
G01X1411395Y519744D02*
X1411380Y519759D01*
G01X1411400Y519724D02*
X1411395Y519744D01*
G01X1411380Y524759D02*
X1411361Y524764D01*
G01X1411395Y524744D02*
X1411380Y524759D01*
G01X1411400Y524724D02*
X1411395Y524744D01*
G01X1411380Y529759D02*
X1411361Y529764D01*
G01X1411395Y529744D02*
X1411380Y529759D01*
G01X1411400Y529724D02*
X1411395Y529744D01*
G01X1411380Y534759D02*
X1411361Y534764D01*
G01X1411395Y534744D02*
X1411380Y534759D01*
G01X1411400Y534724D02*
X1411395Y534744D01*
G01X1411380Y559759D02*
X1411361Y559764D01*
G01X1411395Y559744D02*
X1411380Y559759D01*
G01X1411400Y559724D02*
X1411395Y559744D01*
G01X1411380Y564759D02*
X1411361Y564764D01*
G01X1411395Y564744D02*
X1411380Y564759D01*
G01X1411400Y564724D02*
X1411395Y564744D01*
G01X1411380Y569759D02*
X1411361Y569764D01*
G01X1411395Y569744D02*
X1411380Y569759D01*
G01X1411400Y569724D02*
X1411395Y569744D01*
G01X1397965Y543998D02*
X1397957Y544006D01*
G01X1397970Y543987D02*
X1397965Y543998D01*
G01X1397971Y543976D02*
X1397970Y543987D01*
G01X1397965Y537698D02*
X1397957Y537707D01*
G01X1397970Y537688D02*
X1397965Y537698D01*
G01X1397971Y537677D02*
X1397970Y537688D01*
G01X1397965Y540848D02*
X1397957Y540856D01*
G01X1397970Y540838D02*
X1397965Y540848D01*
G01X1397971Y540827D02*
X1397970Y540838D01*
G01X1397965Y547147D02*
X1397957Y547156D01*
G01X1397970Y547137D02*
X1397965Y547147D01*
G01X1397971Y547126D02*
X1397970Y547137D01*
G01X1397965Y550297D02*
X1397957Y550305D01*
G01X1397970Y550287D02*
X1397965Y550297D01*
G01X1397971Y550276D02*
X1397970Y550287D01*
G01X1397965Y553446D02*
X1397957Y553455D01*
G01X1397970Y553436D02*
X1397965Y553446D01*
G01X1397971Y553425D02*
X1397970Y553436D01*
G01X1397965Y556596D02*
X1397957Y556604D01*
G01X1397970Y556586D02*
X1397965Y556596D01*
G01X1397971Y556575D02*
X1397970Y556586D01*
G01X1411365Y504862D02*
X1411369Y504961D01*
G01X1411359Y504790D02*
X1411365Y504862D01*
G01X1411361Y504764D02*
X1411359Y504790D01*
G01X1411365Y509862D02*
X1411369Y509961D01*
G01X1411359Y509790D02*
X1411365Y509862D01*
G01X1411361Y509764D02*
X1411359Y509790D01*
G01X1411365Y514862D02*
X1411369Y514961D01*
G01X1411359Y514790D02*
X1411365Y514862D01*
G01X1411361Y514764D02*
X1411359Y514790D01*
G01X1411365Y519862D02*
X1411369Y519961D01*
G01X1411359Y519790D02*
X1411365Y519862D01*
G01X1411361Y519764D02*
X1411359Y519790D01*
G01X1411365Y524862D02*
X1411369Y524961D01*
G01X1411359Y524790D02*
X1411365Y524862D01*
G01X1411361Y524764D02*
X1411359Y524790D01*
G01X1411365Y529862D02*
X1411369Y529961D01*
G01X1411359Y529790D02*
X1411365Y529862D01*
G01X1411361Y529764D02*
X1411359Y529790D01*
G01X1411365Y534862D02*
X1411369Y534961D01*
G01X1411359Y534790D02*
X1411365Y534862D01*
G01X1411361Y534764D02*
X1411359Y534790D01*
G01X1411365Y559862D02*
X1411369Y559961D01*
G01X1411359Y559790D02*
X1411365Y559862D01*
G01X1411361Y559764D02*
X1411359Y559790D01*
G01X1411365Y564862D02*
X1411369Y564961D01*
G01X1411359Y564790D02*
X1411365Y564862D01*
G01X1411361Y564764D02*
X1411359Y564790D01*
G01X1411365Y569862D02*
X1411369Y569961D01*
G01X1411359Y569790D02*
X1411365Y569862D01*
G01X1411361Y569764D02*
X1411359Y569790D01*
G01X1396988Y549167D02*
Y549160D01*
G01X1396987Y549172D02*
X1396988Y549167D01*
G01X1396987Y549162D02*
Y549172D01*
G01X1397028Y556798D02*
Y556811D01*
G01X1397025Y556785D02*
X1397028Y556798D01*
G01X1397025Y556772D02*
Y556785D01*
G01X1397028Y553649D02*
Y553661D01*
G01X1397025Y553636D02*
X1397028Y553649D01*
G01X1397025Y553622D02*
Y553636D01*
G01X1397028Y550499D02*
Y550512D01*
G01X1397025Y550486D02*
X1397028Y550499D01*
G01X1397025Y550472D02*
Y550486D01*
G01X1397028Y547350D02*
Y547362D01*
G01X1397025Y547337D02*
X1397028Y547350D01*
G01X1397025Y547323D02*
Y547337D01*
G01X1397028Y544200D02*
Y544213D01*
G01X1397025Y544187D02*
X1397028Y544200D01*
G01X1397025Y544173D02*
Y544187D01*
G01X1397028Y541050D02*
Y541063D01*
G01X1397025Y541037D02*
X1397028Y541050D01*
G01X1397025Y541024D02*
Y541037D01*
G01X1397028Y537901D02*
Y537913D01*
G01X1397025Y537888D02*
X1397028Y537901D01*
G01X1397025Y537874D02*
Y537888D01*
G01X1410414Y568384D02*
X1410415Y568386D01*
G01X1410413Y568378D02*
X1410414Y568384D01*
G01X1410413Y568370D02*
Y568378D01*
G01X1410414Y563384D02*
X1410415Y563386D01*
G01X1410413Y563378D02*
X1410414Y563384D01*
G01X1410413Y563370D02*
Y563378D01*
G01X1410414Y558384D02*
X1410415Y558386D01*
G01X1410413Y558378D02*
X1410414Y558384D01*
G01X1410413Y558370D02*
Y558378D01*
G01X1410414Y533384D02*
X1410415Y533386D01*
G01X1410413Y533378D02*
X1410414Y533384D01*
G01X1410413Y533370D02*
Y533378D01*
G01X1410414Y528384D02*
X1410415Y528386D01*
G01X1410413Y528378D02*
X1410414Y528384D01*
G01X1410413Y528370D02*
Y528378D01*
G01X1410414Y523384D02*
X1410415Y523386D01*
G01X1410413Y523378D02*
X1410414Y523384D01*
G01X1410413Y523370D02*
Y523378D01*
G01X1410414Y518384D02*
X1410415Y518386D01*
G01X1410413Y518378D02*
X1410414Y518384D01*
G01X1410413Y518370D02*
Y518378D01*
G01X1410414Y513384D02*
X1410415Y513386D01*
G01X1410413Y513378D02*
X1410414Y513384D01*
G01X1410413Y513370D02*
Y513378D01*
G01X1410414Y508384D02*
X1410415Y508386D01*
G01X1410413Y508378D02*
X1410414Y508384D01*
G01X1410413Y508370D02*
Y508378D01*
G01X1410414Y503384D02*
X1410415Y503386D01*
G01X1410413Y503378D02*
X1410414Y503384D01*
G01X1410413Y503370D02*
Y503378D01*
G01X1396988Y555467D02*
Y555459D01*
G01X1396987Y555471D02*
X1396988Y555467D01*
G01X1396987Y555463D02*
Y555471D01*
G01X1397025Y555261D02*
X1397024Y555275D01*
G01X1397028Y555249D02*
X1397025Y555261D01*
G01X1397028Y555236D02*
Y555249D01*
G01X1397025Y552112D02*
X1397024Y552126D01*
G01X1397028Y552099D02*
X1397025Y552112D01*
G01X1397028Y552087D02*
Y552099D01*
G01X1397025Y548962D02*
X1397024Y548976D01*
G01X1397028Y548950D02*
X1397025Y548962D01*
G01X1397028Y548937D02*
Y548950D01*
G01X1397025Y545813D02*
X1397024Y545826D01*
G01X1397028Y545800D02*
X1397025Y545813D01*
G01X1397028Y545787D02*
Y545800D01*
G01X1397025Y542663D02*
X1397024Y542677D01*
G01X1397028Y542650D02*
X1397025Y542663D01*
G01X1397028Y542638D02*
Y542650D01*
G01X1397025Y539513D02*
X1397024Y539527D01*
G01X1397028Y539501D02*
X1397025Y539513D01*
G01X1397028Y539488D02*
Y539501D01*
G01X1397025Y536364D02*
X1397024Y536378D01*
G01X1397028Y536351D02*
X1397025Y536364D01*
G01X1397028Y536339D02*
Y536351D01*
G01X1397935Y556785D02*
X1397937Y556772D01*
G01X1397932Y556798D02*
X1397935Y556785D01*
G01X1397933Y556811D02*
X1397932Y556798D01*
G01X1397935Y553636D02*
X1397937Y553622D01*
G01X1397932Y553649D02*
X1397935Y553636D01*
G01X1397933Y553661D02*
X1397932Y553649D01*
G01X1397935Y550486D02*
X1397937Y550472D01*
G01X1397932Y550499D02*
X1397935Y550486D01*
G01X1397933Y550512D02*
X1397932Y550499D01*
G01X1397935Y547337D02*
X1397937Y547323D01*
G01X1397932Y547350D02*
X1397935Y547337D01*
G01X1397933Y547362D02*
X1397932Y547350D01*
G01X1397935Y544187D02*
X1397937Y544173D01*
G01X1397932Y544200D02*
X1397935Y544187D01*
G01X1397933Y544213D02*
X1397932Y544200D01*
G01X1397935Y541037D02*
X1397937Y541024D01*
G01X1397932Y541050D02*
X1397935Y541037D01*
G01X1397933Y541063D02*
X1397932Y541050D01*
G01X1397935Y537888D02*
X1397937Y537874D01*
G01X1397932Y537901D02*
X1397935Y537888D01*
G01X1397933Y537913D02*
X1397932Y537901D01*
G01X1396988Y542868D02*
Y542861D01*
G01X1396987Y542872D02*
X1396988Y542868D01*
G01X1396987Y542865D02*
Y542872D01*
G01X1396988Y552317D02*
Y552309D01*
G01X1396987Y552321D02*
X1396988Y552317D01*
G01X1396987Y552314D02*
Y552321D01*
G01X1397932Y555249D02*
X1397933Y555236D01*
G01X1397935Y555261D02*
X1397932Y555249D01*
G01X1397936Y555275D02*
X1397935Y555261D01*
G01X1397932Y552099D02*
X1397933Y552087D01*
G01X1397935Y552112D02*
X1397932Y552099D01*
G01X1397936Y552126D02*
X1397935Y552112D01*
G01X1397932Y548950D02*
X1397933Y548937D01*
G01X1397935Y548962D02*
X1397932Y548950D01*
G01X1397936Y548976D02*
X1397935Y548962D01*
G01X1397932Y545800D02*
X1397933Y545787D01*
G01X1397935Y545813D02*
X1397932Y545800D01*
G01X1397936Y545826D02*
X1397935Y545813D01*
G01X1397932Y542650D02*
X1397933Y542638D01*
G01X1397935Y542663D02*
X1397932Y542650D01*
G01X1397936Y542677D02*
X1397935Y542663D01*
G01X1397932Y539501D02*
X1397933Y539488D01*
G01X1397935Y539513D02*
X1397932Y539501D01*
G01X1397936Y539527D02*
X1397935Y539513D01*
G01X1397932Y536351D02*
X1397933Y536339D01*
G01X1397935Y536364D02*
X1397932Y536351D01*
G01X1397936Y536378D02*
X1397935Y536364D01*
G01X1396988Y536569D02*
Y536561D01*
G01X1396987Y536573D02*
X1396988Y536569D01*
G01X1396987Y536567D02*
Y536573D01*
G01X1397001Y556606D02*
X1397025Y556614D01*
G01X1396990Y556591D02*
X1397001Y556606D01*
G01X1396988Y556584D02*
X1396990Y556591D01*
G01X1397001Y553456D02*
X1397025Y553465D01*
G01X1396990Y553441D02*
X1397001Y553456D01*
G01X1396988Y553435D02*
X1396990Y553441D01*
G01X1397001Y550306D02*
X1397025Y550315D01*
G01X1396990Y550292D02*
X1397001Y550306D01*
G01X1396988Y550285D02*
X1396990Y550292D01*
G01X1397001Y547157D02*
X1397025Y547165D01*
G01X1396990Y547142D02*
X1397001Y547157D01*
G01X1396988Y547135D02*
X1396990Y547142D01*
G01X1397001Y544007D02*
X1397025Y544016D01*
G01X1396990Y543993D02*
X1397001Y544007D01*
G01X1396988Y543986D02*
X1396990Y543993D01*
G01X1397001Y540857D02*
X1397025Y540866D01*
G01X1396990Y540843D02*
X1397001Y540857D01*
G01X1396988Y540836D02*
X1396990Y540843D01*
G01X1397001Y537708D02*
X1397025Y537717D01*
G01X1396990Y537693D02*
X1397001Y537708D01*
G01X1396988Y537687D02*
X1396990Y537693D01*
G01X1397972Y556581D02*
Y556588D01*
G01Y556576D02*
Y556581D01*
G01X1397971Y556575D02*
X1397972Y556576D01*
G01Y553431D02*
Y553439D01*
G01Y553427D02*
Y553431D01*
G01X1397971Y553425D02*
X1397972Y553427D01*
G01Y550282D02*
Y550289D01*
G01Y550277D02*
Y550282D01*
G01X1397971Y550276D02*
X1397972Y550277D01*
G01Y547132D02*
Y547139D01*
G01Y547128D02*
Y547132D01*
G01X1397971Y547126D02*
X1397972Y547128D01*
G01Y543983D02*
Y543990D01*
G01Y543978D02*
Y543983D01*
G01X1397971Y543976D02*
X1397972Y543978D01*
G01Y540833D02*
Y540840D01*
G01Y540828D02*
Y540833D01*
G01X1397971Y540827D02*
X1397972Y540828D01*
G01Y537683D02*
Y537691D01*
G01Y537679D02*
Y537683D01*
G01X1397971Y537677D02*
X1397972Y537679D01*
G01X1396988Y546018D02*
Y546010D01*
G01X1396987Y546022D02*
X1396988Y546018D01*
G01X1396986Y546019D02*
X1396987Y546022D01*
G01X1396988Y539719D02*
Y539711D01*
G01X1396987Y539723D02*
X1396988Y539719D01*
G01X1396986Y539721D02*
X1396987Y539723D01*
G01X1397933Y556619D02*
Y556625D01*
G01X1397932Y556615D02*
X1397933Y556619D01*
G01X1397931Y556614D02*
X1397932Y556615D01*
G01X1397933Y553470D02*
Y553476D01*
G01X1397932Y553466D02*
X1397933Y553470D01*
G01X1397931Y553465D02*
X1397932Y553466D01*
G01X1397933Y550320D02*
Y550326D01*
G01X1397932Y550316D02*
X1397933Y550320D01*
G01X1397931Y550315D02*
X1397932Y550316D01*
G01X1397933Y547170D02*
Y547176D01*
G01X1397932Y547167D02*
X1397933Y547170D01*
G01X1397931Y547165D02*
X1397932Y547167D01*
G01X1397933Y544021D02*
Y544027D01*
G01X1397932Y544017D02*
X1397933Y544021D01*
G01X1397931Y544016D02*
X1397932Y544017D01*
G01X1397933Y540871D02*
Y540877D01*
G01X1397932Y540867D02*
X1397933Y540871D01*
G01X1397931Y540866D02*
X1397932Y540867D01*
G01X1397933Y537722D02*
Y537728D01*
G01X1397932Y537718D02*
X1397933Y537722D01*
G01X1397931Y537717D02*
X1397932Y537718D01*
G01X1411398Y568378D02*
Y568369D01*
G01X1411399Y568384D02*
X1411398Y568378D01*
G01X1411400Y568386D02*
X1411399Y568384D01*
G01X1411398Y563378D02*
Y563369D01*
G01X1411399Y563384D02*
X1411398Y563378D01*
G01X1411400Y563386D02*
X1411399Y563384D01*
G01X1411398Y558378D02*
Y558369D01*
G01X1411399Y558384D02*
X1411398Y558378D01*
G01X1411400Y558386D02*
X1411399Y558384D01*
G01X1411398Y533378D02*
Y533369D01*
G01X1411399Y533384D02*
X1411398Y533378D01*
G01X1411400Y533386D02*
X1411399Y533384D01*
G01X1411398Y528378D02*
Y528369D01*
G01X1411399Y528384D02*
X1411398Y528378D01*
G01X1411400Y528386D02*
X1411399Y528384D01*
G01X1411398Y523378D02*
Y523369D01*
G01X1411399Y523384D02*
X1411398Y523378D01*
G01X1411400Y523386D02*
X1411399Y523384D01*
G01X1411398Y518378D02*
Y518369D01*
G01X1411399Y518384D02*
X1411398Y518378D01*
G01X1411400Y518386D02*
X1411399Y518384D01*
G01X1411398Y513378D02*
Y513369D01*
G01X1411399Y513384D02*
X1411398Y513378D01*
G01X1411400Y513386D02*
X1411399Y513384D01*
G01X1396988Y556581D02*
Y556588D01*
G01X1396987Y556576D02*
X1396988Y556581D01*
G01X1396986Y556575D02*
X1396987Y556576D01*
G01X1396988Y553431D02*
Y553439D01*
G01X1396987Y553427D02*
X1396988Y553431D01*
G01X1396986Y553425D02*
X1396987Y553427D01*
G01X1396988Y550281D02*
Y550289D01*
G01X1396987Y550277D02*
X1396988Y550281D01*
G01X1396986Y550276D02*
X1396987Y550277D01*
G01X1396988Y547132D02*
Y547139D01*
G01X1396987Y547128D02*
X1396988Y547132D01*
G01X1396986Y547126D02*
X1396987Y547128D01*
G01X1396988Y543982D02*
Y543990D01*
G01X1396987Y543978D02*
X1396988Y543982D01*
G01X1396986Y543976D02*
X1396987Y543978D01*
G01X1396988Y540833D02*
Y540840D01*
G01X1396987Y540828D02*
X1396988Y540833D01*
G01X1396986Y540827D02*
X1396987Y540828D01*
G01X1396988Y537683D02*
Y537691D01*
G01X1396987Y537679D02*
X1396988Y537683D01*
G01X1396986Y537677D02*
X1396987Y537679D01*
G01X1397970Y555446D02*
X1397972Y555459D01*
G01X1397963Y555435D02*
X1397970Y555446D01*
G01X1397953Y555427D02*
X1397963Y555435D01*
G01X1397970Y549147D02*
X1397972Y549159D01*
G01X1397963Y549136D02*
X1397970Y549147D01*
G01X1397953Y549128D02*
X1397963Y549136D01*
G01X1397970Y545998D02*
X1397972Y546010D01*
G01X1397963Y545986D02*
X1397970Y545998D01*
G01X1397953Y545978D02*
X1397963Y545986D01*
G01X1397970Y542848D02*
X1397972Y542860D01*
G01X1397963Y542837D02*
X1397970Y542848D01*
G01X1397953Y542829D02*
X1397963Y542837D01*
G01X1397970Y539698D02*
X1397972Y539711D01*
G01X1397963Y539687D02*
X1397970Y539698D01*
G01X1397953Y539679D02*
X1397963Y539687D01*
G01X1397970Y536549D02*
X1397972Y536561D01*
G01X1397963Y536537D02*
X1397970Y536549D01*
G01X1397953Y536530D02*
X1397963Y536537D01*
G01X1397027Y550320D02*
Y550326D01*
G01Y550316D02*
Y550320D01*
G01X1397025Y550315D02*
X1397027Y550316D01*
G01Y547170D02*
Y547176D01*
G01Y547167D02*
Y547170D01*
G01X1397025Y547165D02*
X1397027Y547167D01*
G01Y544020D02*
Y544027D01*
G01Y544017D02*
Y544020D01*
G01X1397025Y544016D02*
X1397027Y544017D01*
G01Y540871D02*
Y540877D01*
G01Y540867D02*
Y540871D01*
G01X1397025Y540866D02*
X1397027Y540867D01*
G01Y537721D02*
Y537728D01*
G01Y537718D02*
Y537721D01*
G01X1397025Y537717D02*
X1397027Y537718D01*
G01X1396989Y543996D02*
X1396988Y543990D01*
G01X1396991Y544002D02*
X1396989Y543996D01*
G01X1396993Y544008D02*
X1396991Y544002D01*
G01X1396997Y544013D02*
X1396993Y544008D01*
G01X1397002Y544018D02*
X1396997Y544013D01*
G01X1397007Y544022D02*
X1397002Y544018D01*
G01X1396989Y540846D02*
X1396988Y540840D01*
G01X1396991Y540853D02*
X1396989Y540846D01*
G01X1396993Y540859D02*
X1396991Y540853D01*
G01X1396997Y540864D02*
X1396993Y540859D01*
G01X1397002Y540869D02*
X1396997Y540864D01*
G01X1397007Y540872D02*
X1397002Y540869D01*
G01X1396989Y537697D02*
X1396988Y537691D01*
G01X1396991Y537703D02*
X1396989Y537697D01*
G01X1396993Y537709D02*
X1396991Y537703D01*
G01X1396997Y537714D02*
X1396993Y537709D01*
G01X1397002Y537719D02*
X1396997Y537714D01*
G01X1397007Y537722D02*
X1397002Y537719D01*
G01X1411398Y508378D02*
Y508369D01*
G01X1411399Y508384D02*
X1411398Y508378D01*
G01X1411400Y508386D02*
X1411399Y508384D01*
G01X1411398Y503378D02*
Y503369D01*
G01X1411399Y503384D02*
X1411398Y503378D01*
G01X1411400Y503386D02*
X1411399Y503384D01*
G01X1401969Y477894D02*
G03X1402559Y477303I590J-1D01*
G01X1409252D02*
G03X1409843Y477894I0J591D01*
G01X1407087Y479075D02*
G03Y481043I0J984D01*
G01X1404724D02*
G03Y479075I0J-984D01*
G01X1407008Y492264D02*
G03I-1102J0D01*
G01X1408465Y486988D02*
G03X1409646Y488169I0J1181D01*
G01X1402165D02*
G03X1403346Y486988I1181J0D01*
G01X1407480Y492264D02*
G03I-1574J0D01*
G01X1395079Y478484D02*
G03X1397047Y476516I1968J0D01*
G01X1414764D02*
G03X1416732Y478484I0J1968D01*
G01X1408390Y495335D02*
X1407087Y493366D01*
G01X1402414Y487444D02*
X1404724Y491673D01*
G01X1401378Y500256D02*
X1400197Y499075D01*
G01X1398425Y497579D02*
X1395079Y494232D01*
G01X1410827Y556437D02*
X1412008Y557618D01*
G01X1406890Y556437D02*
X1408071Y557618D01*
G01X1397972Y537679D02*
Y537691D01*
G01Y540829D02*
Y540840D01*
G01Y543978D02*
Y543990D01*
G01Y547128D02*
Y547139D01*
G01Y550278D02*
Y550289D01*
G01Y553427D02*
Y553439D01*
G01Y556577D02*
Y556588D01*
G01X1411398Y504738D02*
Y504746D01*
G01Y509738D02*
Y509746D01*
G01Y514738D02*
Y514746D01*
G01Y519738D02*
Y519746D01*
G01Y524738D02*
Y524746D01*
G01Y529738D02*
Y529746D01*
G01Y534738D02*
Y534746D01*
G01Y559738D02*
Y559746D01*
G01Y564738D02*
Y564746D01*
G01Y569738D02*
Y569746D01*
G01X1416732Y478484D02*
Y494232D01*
G01X1415748Y568386D02*
Y569764D01*
G01Y563386D02*
Y564764D01*
G01Y558386D02*
Y559764D01*
G01Y533386D02*
Y534764D01*
G01Y528386D02*
Y529764D01*
G01Y523386D02*
Y524764D01*
G01Y518386D02*
Y519764D01*
G01Y513386D02*
Y514764D01*
G01Y508386D02*
Y509764D01*
G01Y503386D02*
Y504764D01*
G01X1413386Y635571D02*
Y497579D01*
G01X1412795Y637815D02*
Y495335D01*
G01X1412579Y504764D02*
Y503386D01*
G01Y509764D02*
Y508386D01*
G01Y514764D02*
Y513386D01*
G01Y519764D02*
Y518386D01*
G01Y524764D02*
Y523386D01*
G01Y529764D02*
Y528386D01*
G01Y534764D02*
Y533386D01*
G01Y559764D02*
Y558386D01*
G01Y564764D02*
Y563386D01*
G01Y569764D02*
Y568386D01*
G01X1412008Y557618D02*
Y535531D01*
G01X1411398Y504738D02*
Y504881D01*
G01Y509738D02*
Y509881D01*
G01Y514738D02*
Y514881D01*
G01Y519738D02*
Y519881D01*
G01Y524738D02*
Y524881D01*
G01Y529738D02*
Y529881D01*
G01Y534738D02*
Y534881D01*
G01Y559738D02*
Y559881D01*
G01Y564738D02*
Y564881D01*
G01Y567894D02*
Y570256D01*
G01Y562894D02*
Y565256D01*
G01Y557894D02*
Y560256D01*
G01Y532894D02*
Y535256D01*
G01Y527894D02*
Y530256D01*
G01Y522894D02*
Y525256D01*
G01Y517894D02*
Y520256D01*
G01Y512894D02*
Y515256D01*
G01Y507894D02*
Y510256D01*
G01Y502894D02*
Y505256D01*
G01X1410827Y556437D02*
Y536713D01*
G01X1410413Y505256D02*
Y502894D01*
G01Y510256D02*
Y507894D01*
G01Y515256D02*
Y512894D01*
G01Y520256D02*
Y517894D01*
G01Y525256D02*
Y522894D01*
G01Y530256D02*
Y527894D01*
G01Y535256D02*
Y532894D01*
G01Y560256D02*
Y557894D01*
G01Y565256D02*
Y562894D01*
G01Y570256D02*
Y567894D01*
G01X1409843Y483996D02*
Y477894D01*
G01X1409646Y496713D02*
Y488169D01*
G01X1408071Y535531D02*
Y499075D01*
G01Y634075D02*
Y557618D01*
G01X1407087Y493366D02*
Y491673D01*
G01X1406890Y536713D02*
Y500256D01*
G01Y632894D02*
Y556437D01*
G01X1404724Y491673D02*
Y493366D01*
G01X1402165Y488169D02*
Y496713D01*
G01X1401969Y483996D02*
Y477894D01*
G01X1401378Y500256D02*
Y632894D01*
G01X1400197Y499075D02*
Y634075D01*
G01X1398425Y534370D02*
Y495335D01*
G01Y637815D02*
Y558780D01*
G01X1397972Y555275D02*
Y556772D01*
G01Y552126D02*
Y553622D01*
G01Y548976D02*
Y550472D01*
G01Y545826D02*
Y547323D01*
G01Y542677D02*
Y544173D01*
G01Y539527D02*
Y541024D01*
G01Y536378D02*
Y537874D01*
G01X1397933Y536524D02*
Y536377D01*
G01Y539674D02*
Y539527D01*
G01Y541024D02*
Y540877D01*
G01Y537874D02*
Y537728D01*
G01Y545973D02*
Y545826D01*
G01Y542823D02*
Y542676D01*
G01Y544174D02*
Y544027D01*
G01Y549122D02*
Y548976D01*
G01Y550473D02*
Y550326D01*
G01Y547323D02*
Y547176D01*
G01Y555422D02*
Y555275D01*
G01Y552272D02*
Y552125D01*
G01Y553622D02*
Y553476D01*
G01Y556772D02*
Y556625D01*
G01X1397028D02*
Y556772D01*
G01Y555275D02*
Y555422D01*
G01Y552125D02*
Y552272D01*
G01Y553476D02*
Y553622D01*
G01Y548976D02*
Y549122D01*
G01Y550326D02*
Y550473D01*
G01Y547176D02*
Y547323D01*
G01Y545826D02*
Y545973D01*
G01Y542676D02*
Y542823D01*
G01Y544027D02*
Y544174D01*
G01Y539527D02*
Y539674D01*
G01Y540877D02*
Y541024D01*
G01Y537728D02*
Y537874D01*
G01Y536377D02*
Y536524D01*
G01X1396988Y541024D02*
Y539528D01*
G01Y537874D02*
Y536378D01*
G01Y544173D02*
Y542677D01*
G01Y550472D02*
Y548976D01*
G01Y547323D02*
Y545827D01*
G01Y553622D02*
Y552126D01*
G01Y556772D02*
Y555276D01*
G01X1395807Y537717D02*
Y536535D01*
G01Y540866D02*
Y539685D01*
G01Y547165D02*
Y545984D01*
G01Y544016D02*
Y542835D01*
G01Y550315D02*
Y549134D01*
G01Y556614D02*
Y555433D01*
G01Y553465D02*
Y552283D01*
G01X1395472Y558780D02*
Y534370D01*
G01X1395079D02*
Y558780D01*
G01Y494232D02*
Y478484D01*
G01X1392047Y555433D02*
Y556614D01*
G01Y552283D02*
Y553465D01*
G01Y549134D02*
Y550315D01*
G01Y545984D02*
Y547165D01*
G01Y542835D02*
Y544016D01*
G01Y539685D02*
Y540866D01*
G01Y536535D02*
Y537717D01*
G01X1397972Y555459D02*
Y555470D01*
G01Y552309D02*
Y552320D01*
G01Y549160D02*
Y549170D01*
G01Y546010D02*
Y546021D01*
G01Y542861D02*
Y542871D01*
G01Y539711D02*
Y539722D01*
G01Y536561D02*
Y536572D01*
G01X1397931Y552283D02*
X1397935Y552272D01*
G01X1407087Y491673D02*
X1409397Y487444D01*
G01X1404724Y493366D02*
X1403421Y495335D01*
G01X1410827Y536713D02*
X1412008Y535531D01*
G01X1406890Y536713D02*
X1408071Y535531D01*
G01X1413386Y497579D02*
X1416732Y494232D01*
G01X1406890Y500256D02*
X1408071Y499075D01*
G01X1396875Y555472D02*
X1396987Y555464D01*
G01X1396986Y546019D02*
X1396875Y546024D01*
G01X1396986Y539721D02*
X1396875Y539724D01*
G01X1396986Y549170D02*
X1396875Y549173D01*
G01X1411398Y570256D02*
X1410413D01*
G01X1410415Y569764D02*
X1415748D01*
G01Y569724D02*
X1411400D01*
G01X1415748Y568386D02*
X1410415D01*
G01X1410413Y567894D02*
X1411398D01*
G01Y565256D02*
X1410413D01*
G01X1410415Y564764D02*
X1415748D01*
G01Y564724D02*
X1411400D01*
G01X1415748Y563386D02*
X1410415D01*
G01X1410413Y562894D02*
X1411398D01*
G01Y560256D02*
X1410413D01*
G01X1410415Y559764D02*
X1415748D01*
G01Y559724D02*
X1411400D01*
G01X1398425Y558780D02*
X1395079D01*
G01X1415748Y558386D02*
X1410415D01*
G01X1410413Y557894D02*
X1411398D01*
G01X1408071Y557618D02*
X1412008D01*
G01X1397933Y556811D02*
X1397028D01*
G01X1397972Y556772D02*
X1396988D01*
G01X1397931Y556614D02*
X1392047D01*
G01Y556575D02*
X1397971D01*
G01X1406890Y556437D02*
X1410827D01*
G01X1397971Y555472D02*
X1392047D01*
G01X1397931Y555433D02*
X1392047D01*
G01X1396988Y555276D02*
X1397972D01*
G01X1397028Y555236D02*
X1397933D01*
G01Y553661D02*
X1397028D01*
G01X1397972Y553622D02*
X1396988D01*
G01X1397931Y553465D02*
X1392047D01*
G01Y553425D02*
X1397971D01*
G01Y552323D02*
X1392047D01*
G01X1397931Y552283D02*
X1392047D01*
G01X1396988Y552126D02*
X1397972D01*
G01X1397028Y552087D02*
X1397933D01*
G01Y550512D02*
X1397028D01*
G01X1397972Y550472D02*
X1396988D01*
G01X1397931Y550315D02*
X1392047D01*
G01Y550276D02*
X1397971D01*
G01X1396241Y549173D02*
X1395807D01*
G01X1397971D02*
X1392047D01*
G01X1397931Y549134D02*
X1392047D01*
G01X1396988Y548976D02*
X1397972D01*
G01X1397028Y548937D02*
X1397933D01*
G01Y547362D02*
X1397028D01*
G01X1397972Y547323D02*
X1396988D01*
G01X1397931Y547165D02*
X1392047D01*
G01Y547126D02*
X1397971D01*
G01X1396241Y546024D02*
X1395807D01*
G01X1397971D02*
X1392047D01*
G01X1397931Y545984D02*
X1392047D01*
G01X1396988Y545827D02*
X1397972D01*
G01X1397028Y545787D02*
X1397933D01*
G01Y544213D02*
X1397028D01*
G01X1397972Y544173D02*
X1396988D01*
G01X1397931Y544016D02*
X1392047D01*
G01Y543976D02*
X1397971D01*
G01Y542874D02*
X1392047D01*
G01X1397931Y542835D02*
X1392047D01*
G01X1396988Y542677D02*
X1397972D01*
G01X1397028Y542638D02*
X1397933D01*
G01Y541063D02*
X1397028D01*
G01X1397972Y541024D02*
X1396988D01*
G01X1397931Y540866D02*
X1392047D01*
G01Y540827D02*
X1397971D01*
G01X1396241Y539724D02*
X1395807D01*
G01X1397971D02*
X1392047D01*
G01X1397931Y539685D02*
X1392047D01*
G01X1396988Y539528D02*
X1397972D01*
G01X1397028Y539488D02*
X1397933D01*
G01Y537913D02*
X1397028D01*
G01X1397972Y537874D02*
X1396988D01*
G01X1397931Y537717D02*
X1392047D01*
G01Y537677D02*
X1397971D01*
G01X1410827Y536713D02*
X1406890D01*
G01X1397971Y536575D02*
X1392047D01*
G01X1397931Y536535D02*
X1392047D01*
G01X1396988Y536378D02*
X1397972D01*
G01X1397028Y536339D02*
X1397933D01*
G01X1412008Y535531D02*
X1408071D01*
G01X1411398Y535256D02*
X1410413D01*
G01X1410415Y534764D02*
X1415748D01*
G01Y534724D02*
X1411400D01*
G01X1398425Y534370D02*
X1395079D01*
G01X1415748Y533386D02*
X1410415D01*
G01X1410413Y532894D02*
X1411398D01*
G01Y530256D02*
X1410413D01*
G01X1410415Y529764D02*
X1415748D01*
G01Y529724D02*
X1411400D01*
G01X1415748Y528386D02*
X1410415D01*
G01X1410413Y569959D02*
X1411369Y569961D01*
G01X1411398Y568190D02*
X1410413Y568189D01*
G01Y564959D02*
X1411369Y564961D01*
G01X1411398Y563190D02*
X1410413Y563189D01*
G01Y559959D02*
X1411369Y559961D01*
G01X1411398Y558190D02*
X1410413Y558189D01*
G01Y534959D02*
X1411369Y534961D01*
G01X1411398Y533190D02*
X1410413Y533189D01*
G01Y529959D02*
X1411369Y529961D01*
G01X1410413Y527894D02*
X1411398D01*
G01Y525256D02*
X1410413D01*
G01X1410415Y524764D02*
X1415748D01*
G01Y524724D02*
X1411400D01*
G01X1415748Y523386D02*
X1410415D01*
G01X1410413Y522894D02*
X1411398D01*
G01Y520256D02*
X1410413D01*
G01X1410415Y519764D02*
X1415748D01*
G01Y519724D02*
X1411400D01*
G01X1415748Y518386D02*
X1410415D01*
G01X1410413Y517894D02*
X1411398D01*
G01Y515256D02*
X1410413D01*
G01X1410415Y514764D02*
X1415748D01*
G01Y514724D02*
X1411400D01*
G01X1415748Y513386D02*
X1410415D01*
G01X1410413Y512894D02*
X1411398D01*
G01Y510256D02*
X1410413D01*
G01X1410415Y509764D02*
X1415748D01*
G01Y509724D02*
X1411400D01*
G01X1415748Y508386D02*
X1410415D01*
G01X1410413Y507894D02*
X1411398D01*
G01Y505256D02*
X1410413D01*
G01X1410415Y504764D02*
X1415748D01*
G01Y504724D02*
X1411400D01*
G01X1415748Y503386D02*
X1410415D01*
G01X1410413Y502894D02*
X1411398D01*
G01X1406890Y500256D02*
X1401378D01*
G01X1408071Y499075D02*
X1400197D01*
G01X1413386Y497579D02*
X1398425D01*
G01X1409646Y496713D02*
X1412795D01*
G01X1402165D02*
X1398425D01*
G01Y495335D02*
X1412795D01*
G01X1407087Y493366D02*
X1404724D01*
G01X1407087Y491673D02*
X1404724D01*
G01X1408465Y486988D02*
X1403346D01*
G01X1416732Y486949D02*
X1395079D01*
G01X1409843Y483996D02*
X1401969D01*
G01Y482421D02*
X1409843D01*
G01X1407087Y481043D02*
X1404724D01*
G01Y479075D02*
X1407087D01*
G01X1409252Y477303D02*
X1402559D01*
G01X1414764Y476516D02*
X1397047D01*
G01X1411398Y528190D02*
X1410413Y528189D01*
G01Y524959D02*
X1411369Y524961D01*
G01X1411398Y523190D02*
X1410413Y523189D01*
G01Y519959D02*
X1411369Y519961D01*
G01X1411398Y518190D02*
X1410413Y518189D01*
G01Y514959D02*
X1411369Y514961D01*
G01X1411398Y513190D02*
X1410413Y513189D01*
G01Y509959D02*
X1411369Y509961D01*
G01X1411398Y508190D02*
X1410413Y508189D01*
G01Y504959D02*
X1411369Y504961D01*
G01X1411398Y503190D02*
X1410413Y503189D01*
G01X1411385Y574755D02*
X1411396Y574740D01*
G01X1411361Y574764D02*
X1411385Y574755D01*
G01Y579755D02*
X1411396Y579740D01*
G01X1411361Y579764D02*
X1411385Y579755D01*
G01Y584755D02*
X1411396Y584740D01*
G01X1411361Y584764D02*
X1411385Y584755D01*
G01Y589755D02*
X1411396Y589740D01*
G01X1411361Y589764D02*
X1411385Y589755D01*
G01Y594755D02*
X1411396Y594740D01*
G01X1411361Y594764D02*
X1411385Y594755D01*
G01Y599755D02*
X1411396Y599740D01*
G01X1411361Y599764D02*
X1411385Y599755D01*
G01Y604755D02*
X1411396Y604740D01*
G01X1411361Y604764D02*
X1411385Y604755D01*
G01Y609755D02*
X1411396Y609740D01*
G01X1411361Y609764D02*
X1411385Y609755D01*
G01Y614755D02*
X1411396Y614740D01*
G01X1411361Y614764D02*
X1411385Y614755D01*
G01Y619755D02*
X1411396Y619740D01*
G01X1411361Y619764D02*
X1411385Y619755D01*
G01Y624755D02*
X1411396Y624740D01*
G01X1411361Y624764D02*
X1411385Y624755D01*
G01Y629755D02*
X1411396Y629740D01*
G01X1411361Y629764D02*
X1411385Y629755D01*
G01X1411398Y574731D02*
Y574738D01*
G01X1411399Y574726D02*
X1411398Y574731D01*
G01X1411400Y574724D02*
X1411399Y574726D01*
G01X1411398Y579731D02*
Y579738D01*
G01X1411399Y579726D02*
X1411398Y579731D01*
G01X1411400Y579724D02*
X1411399Y579726D01*
G01X1411398Y584731D02*
Y584738D01*
G01X1411399Y584726D02*
X1411398Y584731D01*
G01X1411400Y584724D02*
X1411399Y584726D01*
G01X1411398Y589731D02*
Y589738D01*
G01X1411399Y589726D02*
X1411398Y589731D01*
G01X1411400Y589724D02*
X1411399Y589726D01*
G01X1411398Y594731D02*
Y594738D01*
G01X1411399Y594726D02*
X1411398Y594731D01*
G01X1411400Y594724D02*
X1411399Y594726D01*
G01X1411398Y599731D02*
Y599738D01*
G01X1411399Y599726D02*
X1411398Y599731D01*
G01X1411400Y599724D02*
X1411399Y599726D01*
G01X1411398Y604731D02*
Y604738D01*
G01X1411399Y604726D02*
X1411398Y604731D01*
G01X1411400Y604724D02*
X1411399Y604726D01*
G01X1411398Y609731D02*
Y609738D01*
G01X1411399Y609726D02*
X1411398Y609731D01*
G01X1411400Y609724D02*
X1411399Y609726D01*
G01X1411398Y614731D02*
Y614738D01*
G01X1411399Y614726D02*
X1411398Y614731D01*
G01X1411400Y614724D02*
X1411399Y614726D01*
G01X1411398Y619731D02*
Y619738D01*
G01X1411399Y619726D02*
X1411398Y619731D01*
G01X1411400Y619724D02*
X1411399Y619726D01*
G01X1411398Y624731D02*
Y624738D01*
G01X1411399Y624726D02*
X1411398Y624731D01*
G01X1411400Y624724D02*
X1411399Y624726D01*
G01X1411398Y629731D02*
Y629738D01*
G01X1411399Y629726D02*
X1411398Y629731D01*
G01X1411400Y629724D02*
X1411399Y629726D01*
G01X1410413Y574771D02*
Y574780D01*
G01X1410414Y574765D02*
X1410413Y574771D01*
G01X1410415Y574764D02*
X1410414Y574765D01*
G01X1410413Y579771D02*
Y579780D01*
G01X1410414Y579765D02*
X1410413Y579771D01*
G01X1410415Y579764D02*
X1410414Y579765D01*
G01X1410413Y584771D02*
Y584780D01*
G01X1410414Y584765D02*
X1410413Y584771D01*
G01X1410415Y584764D02*
X1410414Y584765D01*
G01X1410413Y589771D02*
Y589780D01*
G01X1410414Y589765D02*
X1410413Y589771D01*
G01X1410415Y589764D02*
X1410414Y589765D01*
G01X1410413Y594771D02*
Y594780D01*
G01X1410414Y594765D02*
X1410413Y594771D01*
G01X1410415Y594764D02*
X1410414Y594765D01*
G01X1410413Y599771D02*
Y599780D01*
G01X1410414Y599765D02*
X1410413Y599771D01*
G01X1410415Y599764D02*
X1410414Y599765D01*
G01X1411390Y574907D02*
X1411398Y574881D01*
G01X1411380Y574934D02*
X1411390Y574907D01*
G01X1411369Y574961D02*
X1411380Y574934D01*
G01X1411390Y579907D02*
X1411398Y579881D01*
G01X1411380Y579934D02*
X1411390Y579907D01*
G01X1411369Y579961D02*
X1411380Y579934D01*
G01X1411390Y584907D02*
X1411398Y584881D01*
G01X1411380Y584934D02*
X1411390Y584907D01*
G01X1411369Y584961D02*
X1411380Y584934D01*
G01X1411390Y589907D02*
X1411398Y589881D01*
G01X1411380Y589934D02*
X1411390Y589907D01*
G01X1411369Y589961D02*
X1411380Y589934D01*
G01X1410413Y604771D02*
Y604780D01*
G01X1410414Y604765D02*
X1410413Y604771D01*
G01X1410415Y604764D02*
X1410414Y604765D01*
G01X1410413Y609771D02*
Y609780D01*
G01X1410414Y609765D02*
X1410413Y609771D01*
G01X1410415Y609764D02*
X1410414Y609765D01*
G01X1410413Y614771D02*
Y614780D01*
G01X1410414Y614765D02*
X1410413Y614771D01*
G01X1410415Y614764D02*
X1410414Y614765D01*
G01X1410413Y619771D02*
Y619780D01*
G01X1410414Y619765D02*
X1410413Y619771D01*
G01X1410415Y619764D02*
X1410414Y619765D01*
G01X1410413Y624771D02*
Y624780D01*
G01X1410414Y624765D02*
X1410413Y624771D01*
G01X1410415Y624764D02*
X1410414Y624765D01*
G01X1410413Y629771D02*
Y629780D01*
G01X1410414Y629765D02*
X1410413Y629771D01*
G01X1410415Y629764D02*
X1410414Y629765D01*
G01X1411390Y594907D02*
X1411398Y594881D01*
G01X1411380Y594934D02*
X1411390Y594907D01*
G01X1411369Y594961D02*
X1411380Y594934D01*
G01X1411390Y599907D02*
X1411398Y599881D01*
G01X1411380Y599934D02*
X1411390Y599907D01*
G01X1411369Y599961D02*
X1411380Y599934D01*
G01X1411390Y604907D02*
X1411398Y604881D01*
G01X1411380Y604934D02*
X1411390Y604907D01*
G01X1411369Y604961D02*
X1411380Y604934D01*
G01X1411390Y609907D02*
X1411398Y609881D01*
G01X1411380Y609934D02*
X1411390Y609907D01*
G01X1411369Y609961D02*
X1411380Y609934D01*
G01X1411390Y614907D02*
X1411398Y614881D01*
G01X1411380Y614934D02*
X1411390Y614907D01*
G01X1411369Y614961D02*
X1411380Y614934D01*
G01X1411390Y619907D02*
X1411398Y619881D01*
G01X1411380Y619934D02*
X1411390Y619907D01*
G01X1411369Y619961D02*
X1411380Y619934D01*
G01X1411390Y624907D02*
X1411398Y624881D01*
G01X1411380Y624934D02*
X1411390Y624907D01*
G01X1411369Y624961D02*
X1411380Y624934D01*
G01X1411390Y629907D02*
X1411398Y629881D01*
G01X1411380Y629934D02*
X1411390Y629907D01*
G01X1411369Y629961D02*
X1411380Y629934D01*
G01Y574759D02*
X1411361Y574764D01*
G01X1411395Y574744D02*
X1411380Y574759D01*
G01X1411400Y574724D02*
X1411395Y574744D01*
G01X1411380Y579759D02*
X1411361Y579764D01*
G01X1411395Y579744D02*
X1411380Y579759D01*
G01X1411400Y579724D02*
X1411395Y579744D01*
G01X1411380Y584759D02*
X1411361Y584764D01*
G01X1411395Y584744D02*
X1411380Y584759D01*
G01X1411400Y584724D02*
X1411395Y584744D01*
G01X1411380Y589759D02*
X1411361Y589764D01*
G01X1411395Y589744D02*
X1411380Y589759D01*
G01X1411400Y589724D02*
X1411395Y589744D01*
G01X1411380Y594759D02*
X1411361Y594764D01*
G01X1411395Y594744D02*
X1411380Y594759D01*
G01X1411400Y594724D02*
X1411395Y594744D01*
G01X1411380Y599759D02*
X1411361Y599764D01*
G01X1411395Y599744D02*
X1411380Y599759D01*
G01X1411400Y599724D02*
X1411395Y599744D01*
G01X1411380Y604759D02*
X1411361Y604764D01*
G01X1411395Y604744D02*
X1411380Y604759D01*
G01X1411400Y604724D02*
X1411395Y604744D01*
G01X1411380Y609759D02*
X1411361Y609764D01*
G01X1411395Y609744D02*
X1411380Y609759D01*
G01X1411400Y609724D02*
X1411395Y609744D01*
G01X1411380Y614759D02*
X1411361Y614764D01*
G01X1411395Y614744D02*
X1411380Y614759D01*
G01X1411400Y614724D02*
X1411395Y614744D01*
G01X1411380Y619759D02*
X1411361Y619764D01*
G01X1411395Y619744D02*
X1411380Y619759D01*
G01X1411400Y619724D02*
X1411395Y619744D01*
G01X1411380Y624759D02*
X1411361Y624764D01*
G01X1411395Y624744D02*
X1411380Y624759D01*
G01X1411400Y624724D02*
X1411395Y624744D01*
G01X1411380Y629759D02*
X1411361Y629764D01*
G01X1411395Y629744D02*
X1411380Y629759D01*
G01X1411400Y629724D02*
X1411395Y629744D01*
G01X1411365Y574862D02*
X1411369Y574961D01*
G01X1411359Y574790D02*
X1411365Y574862D01*
G01X1411361Y574764D02*
X1411359Y574790D01*
G01X1411365Y579862D02*
X1411369Y579961D01*
G01X1411359Y579790D02*
X1411365Y579862D01*
G01X1411361Y579764D02*
X1411359Y579790D01*
G01X1411365Y584862D02*
X1411369Y584961D01*
G01X1411359Y584790D02*
X1411365Y584862D01*
G01X1411361Y584764D02*
X1411359Y584790D01*
G01X1411365Y589862D02*
X1411369Y589961D01*
G01X1411359Y589790D02*
X1411365Y589862D01*
G01X1411361Y589764D02*
X1411359Y589790D01*
G01X1411365Y594862D02*
X1411369Y594961D01*
G01X1411359Y594790D02*
X1411365Y594862D01*
G01X1411361Y594764D02*
X1411359Y594790D01*
G01X1411365Y599862D02*
X1411369Y599961D01*
G01X1411359Y599790D02*
X1411365Y599862D01*
G01X1411361Y599764D02*
X1411359Y599790D01*
G01X1411365Y604862D02*
X1411369Y604961D01*
G01X1411359Y604790D02*
X1411365Y604862D01*
G01X1411361Y604764D02*
X1411359Y604790D01*
G01X1411365Y609862D02*
X1411369Y609961D01*
G01X1411359Y609790D02*
X1411365Y609862D01*
G01X1411361Y609764D02*
X1411359Y609790D01*
G01X1411365Y614862D02*
X1411369Y614961D01*
G01X1411359Y614790D02*
X1411365Y614862D01*
G01X1411361Y614764D02*
X1411359Y614790D01*
G01X1411365Y619862D02*
X1411369Y619961D01*
G01X1411359Y619790D02*
X1411365Y619862D01*
G01X1411361Y619764D02*
X1411359Y619790D01*
G01X1411365Y624862D02*
X1411369Y624961D01*
G01X1411359Y624790D02*
X1411365Y624862D01*
G01X1411361Y624764D02*
X1411359Y624790D01*
G01X1411365Y629862D02*
X1411369Y629961D01*
G01X1411359Y629790D02*
X1411365Y629862D01*
G01X1411361Y629764D02*
X1411359Y629790D01*
G01X1410414Y628384D02*
X1410415Y628386D01*
G01X1410413Y628378D02*
X1410414Y628384D01*
G01X1410413Y628370D02*
Y628378D01*
G01X1410414Y623384D02*
X1410415Y623386D01*
G01X1410413Y623378D02*
X1410414Y623384D01*
G01X1410413Y623370D02*
Y623378D01*
G01X1410414Y618384D02*
X1410415Y618386D01*
G01X1410413Y618378D02*
X1410414Y618384D01*
G01X1410413Y618370D02*
Y618378D01*
G01X1410414Y613384D02*
X1410415Y613386D01*
G01X1410413Y613378D02*
X1410414Y613384D01*
G01X1410413Y613370D02*
Y613378D01*
G01X1410414Y608384D02*
X1410415Y608386D01*
G01X1410413Y608378D02*
X1410414Y608384D01*
G01X1410413Y608370D02*
Y608378D01*
G01X1410414Y603384D02*
X1410415Y603386D01*
G01X1410413Y603378D02*
X1410414Y603384D01*
G01X1410413Y603370D02*
Y603378D01*
G01X1410414Y598384D02*
X1410415Y598386D01*
G01X1410413Y598378D02*
X1410414Y598384D01*
G01X1410413Y598370D02*
Y598378D01*
G01X1410414Y593384D02*
X1410415Y593386D01*
G01X1410413Y593378D02*
X1410414Y593384D01*
G01X1410413Y593370D02*
Y593378D01*
G01X1410414Y588384D02*
X1410415Y588386D01*
G01X1410413Y588378D02*
X1410414Y588384D01*
G01X1410413Y588370D02*
Y588378D01*
G01X1410414Y583384D02*
X1410415Y583386D01*
G01X1410413Y583378D02*
X1410414Y583384D01*
G01X1410413Y583370D02*
Y583378D01*
G01X1410414Y578384D02*
X1410415Y578386D01*
G01X1410413Y578378D02*
X1410414Y578384D01*
G01X1410413Y578370D02*
Y578378D01*
G01X1410414Y573384D02*
X1410415Y573386D01*
G01X1410413Y573378D02*
X1410414Y573384D01*
G01X1410413Y573370D02*
Y573378D01*
G01X1411398Y628378D02*
Y628369D01*
G01X1411399Y628384D02*
X1411398Y628378D01*
G01X1411400Y628386D02*
X1411399Y628384D01*
G01X1411398Y623378D02*
Y623369D01*
G01X1411399Y623384D02*
X1411398Y623378D01*
G01X1411400Y623386D02*
X1411399Y623384D01*
G01X1411398Y618378D02*
Y618369D01*
G01X1411399Y618384D02*
X1411398Y618378D01*
G01X1411400Y618386D02*
X1411399Y618384D01*
G01X1411398Y613378D02*
Y613369D01*
G01X1411399Y613384D02*
X1411398Y613378D01*
G01X1411400Y613386D02*
X1411399Y613384D01*
G01X1411398Y608378D02*
Y608369D01*
G01X1411399Y608384D02*
X1411398Y608378D01*
G01X1411400Y608386D02*
X1411399Y608384D01*
G01X1411398Y603378D02*
Y603369D01*
G01X1411399Y603384D02*
X1411398Y603378D01*
G01X1411400Y603386D02*
X1411399Y603384D01*
G01X1411398Y598378D02*
Y598369D01*
G01X1411399Y598384D02*
X1411398Y598378D01*
G01X1411400Y598386D02*
X1411399Y598384D01*
G01X1411398Y593378D02*
Y593369D01*
G01X1411399Y593384D02*
X1411398Y593378D01*
G01X1411400Y593386D02*
X1411399Y593384D01*
G01X1411398Y588378D02*
Y588369D01*
G01X1411399Y588384D02*
X1411398Y588378D01*
G01X1411400Y588386D02*
X1411399Y588384D01*
G01X1411398Y583378D02*
Y583369D01*
G01X1411399Y583384D02*
X1411398Y583378D01*
G01X1411400Y583386D02*
X1411399Y583384D01*
G01X1411398Y578378D02*
Y578369D01*
G01X1411399Y578384D02*
X1411398Y578378D01*
G01X1411400Y578386D02*
X1411399Y578384D01*
G01X1411398Y573378D02*
Y573369D01*
G01X1411399Y573384D02*
X1411398Y573378D01*
G01X1411400Y573386D02*
X1411399Y573384D01*
G01X1409843Y655256D02*
G03X1409252Y655846I-591J-1D01*
G01X1402559D02*
G03X1401969Y655256I0J-590D01*
G01X1404724Y654075D02*
G03Y652106I0J-985D01*
G01X1407087D02*
G03Y654075I0J984D01*
G01X1403346Y646161D02*
G03X1402165Y644980I0J-1181D01*
G01X1409646D02*
G03X1408465Y646161I-1181J0D01*
G01X1407795Y640886D02*
G03I-1889J0D01*
G01X1416732Y654665D02*
G03X1414764Y656634I-1968J1D01*
G01X1397047D02*
G03X1395079Y654665I1J-1969D01*
G01X1408268Y640886D02*
G03I-2362J0D01*
G01X1403421Y637815D02*
X1404724Y639783D01*
G01X1409397Y645706D02*
X1407087Y641476D01*
G01X1411398Y574738D02*
Y574746D01*
G01Y579738D02*
Y579746D01*
G01Y584738D02*
Y584746D01*
G01Y589738D02*
Y589746D01*
G01Y594738D02*
Y594746D01*
G01Y599738D02*
Y599746D01*
G01Y604738D02*
Y604746D01*
G01Y609738D02*
Y609746D01*
G01Y614738D02*
Y614746D01*
G01Y619738D02*
Y619746D01*
G01Y624738D02*
Y624746D01*
G01Y629738D02*
Y629746D01*
G01X1416732Y638917D02*
Y654665D01*
G01X1415748Y628386D02*
Y629764D01*
G01Y623386D02*
Y624764D01*
G01Y618386D02*
Y619764D01*
G01Y613386D02*
Y614764D01*
G01Y608386D02*
Y609764D01*
G01Y603386D02*
Y604764D01*
G01Y598386D02*
Y599764D01*
G01Y593386D02*
Y594764D01*
G01Y588386D02*
Y589764D01*
G01Y583386D02*
Y584764D01*
G01Y578386D02*
Y579764D01*
G01Y573386D02*
Y574764D01*
G01X1412579D02*
Y573386D01*
G01Y579764D02*
Y578386D01*
G01Y584764D02*
Y583386D01*
G01Y589764D02*
Y588386D01*
G01Y594764D02*
Y593386D01*
G01Y599764D02*
Y598386D01*
G01Y604764D02*
Y603386D01*
G01Y609764D02*
Y608386D01*
G01Y614764D02*
Y613386D01*
G01Y619764D02*
Y618386D01*
G01Y624764D02*
Y623386D01*
G01Y629764D02*
Y628386D01*
G01X1411398Y627894D02*
Y630256D01*
G01Y622894D02*
Y625256D01*
G01Y617894D02*
Y620256D01*
G01Y612894D02*
Y615256D01*
G01Y607894D02*
Y610256D01*
G01Y602894D02*
Y605256D01*
G01Y597894D02*
Y600256D01*
G01Y592894D02*
Y595256D01*
G01Y587894D02*
Y590256D01*
G01Y582894D02*
Y585256D01*
G01Y577894D02*
Y580256D01*
G01Y572894D02*
Y575256D01*
G01X1410413D02*
Y572894D01*
G01Y580256D02*
Y577894D01*
G01Y585256D02*
Y582894D01*
G01Y590256D02*
Y587894D01*
G01Y595256D02*
Y592894D01*
G01Y600256D02*
Y597894D01*
G01Y605256D02*
Y602894D01*
G01Y610256D02*
Y607894D01*
G01Y615256D02*
Y612894D01*
G01Y620256D02*
Y617894D01*
G01Y625256D02*
Y622894D01*
G01Y630256D02*
Y627894D01*
G01X1409843Y649154D02*
Y655256D01*
G01X1409646Y644980D02*
Y636437D01*
G01X1407087Y641476D02*
Y639783D01*
G01X1404724D02*
Y641476D01*
G01X1402165Y636437D02*
Y644980D01*
G01X1401969Y649154D02*
Y655256D01*
G01X1395079Y654665D02*
Y638917D01*
G01X1416732D02*
X1413386Y635571D01*
G01X1406890Y632894D02*
X1408071Y634075D01*
G01X1404724Y641476D02*
X1402414Y645706D01*
G01X1407087Y639783D02*
X1408390Y637815D01*
G01X1400197Y634075D02*
X1401378Y632894D01*
G01X1395079Y638917D02*
X1398425Y635571D01*
G01X1414764Y656634D02*
X1397047D01*
G01X1409252Y655846D02*
X1402559D01*
G01X1407087Y654075D02*
X1404724D01*
G01Y652106D02*
X1407087D01*
G01X1409843Y650728D02*
X1401969D01*
G01Y649154D02*
X1409843D01*
G01X1416732Y646201D02*
X1395079D01*
G01X1403346Y646161D02*
X1408465D01*
G01X1404724Y641476D02*
X1407087D01*
G01X1404724Y639783D02*
X1407087D01*
G01X1398425Y637815D02*
X1412795D01*
G01X1398425Y636437D02*
X1402165D01*
G01X1412795D02*
X1409646D01*
G01X1398425Y635571D02*
X1413386D01*
G01X1400197Y634075D02*
X1408071D01*
G01X1401378Y632894D02*
X1406890D01*
G01X1411398Y630256D02*
X1410413D01*
G01X1410415Y629764D02*
X1415748D01*
G01Y629724D02*
X1411400D01*
G01X1415748Y628386D02*
X1410415D01*
G01X1410413Y627894D02*
X1411398D01*
G01Y625256D02*
X1410413D01*
G01X1410415Y624764D02*
X1415748D01*
G01Y624724D02*
X1411400D01*
G01X1415748Y623386D02*
X1410415D01*
G01X1410413Y622894D02*
X1411398D01*
G01Y620256D02*
X1410413D01*
G01X1410415Y619764D02*
X1415748D01*
G01Y619724D02*
X1411400D01*
G01X1415748Y618386D02*
X1410415D01*
G01X1410413Y617894D02*
X1411398D01*
G01Y615256D02*
X1410413D01*
G01X1410415Y614764D02*
X1415748D01*
G01Y614724D02*
X1411400D01*
G01X1415748Y613386D02*
X1410415D01*
G01X1410413Y612894D02*
X1411398D01*
G01Y610256D02*
X1410413D01*
G01Y629959D02*
X1411369Y629961D01*
G01X1411398Y628190D02*
X1410413Y628189D01*
G01Y624959D02*
X1411369Y624961D01*
G01X1411398Y623190D02*
X1410413Y623189D01*
G01Y619959D02*
X1411369Y619961D01*
G01X1411398Y618190D02*
X1410413Y618189D01*
G01Y614959D02*
X1411369Y614961D01*
G01X1411398Y613190D02*
X1410413Y613189D01*
G01X1410415Y609764D02*
X1415748D01*
G01Y609724D02*
X1411400D01*
G01X1415748Y608386D02*
X1410415D01*
G01X1410413Y607894D02*
X1411398D01*
G01Y605256D02*
X1410413D01*
G01X1410415Y604764D02*
X1415748D01*
G01Y604724D02*
X1411400D01*
G01X1415748Y603386D02*
X1410415D01*
G01X1410413Y602894D02*
X1411398D01*
G01Y600256D02*
X1410413D01*
G01X1410415Y599764D02*
X1415748D01*
G01Y599724D02*
X1411400D01*
G01X1415748Y598386D02*
X1410415D01*
G01X1410413Y597894D02*
X1411398D01*
G01Y595256D02*
X1410413D01*
G01X1410415Y594764D02*
X1415748D01*
G01Y594724D02*
X1411400D01*
G01X1415748Y593386D02*
X1410415D01*
G01X1410413Y592894D02*
X1411398D01*
G01Y590256D02*
X1410413D01*
G01X1410415Y589764D02*
X1415748D01*
G01Y589724D02*
X1411400D01*
G01X1415748Y588386D02*
X1410415D01*
G01X1410413Y587894D02*
X1411398D01*
G01Y585256D02*
X1410413D01*
G01X1410415Y584764D02*
X1415748D01*
G01Y584724D02*
X1411400D01*
G01X1415748Y583386D02*
X1410415D01*
G01X1410413Y582894D02*
X1411398D01*
G01Y580256D02*
X1410413D01*
G01X1410415Y579764D02*
X1415748D01*
G01Y579724D02*
X1411400D01*
G01X1415748Y578386D02*
X1410415D01*
G01X1410413Y577894D02*
X1411398D01*
G01Y575256D02*
X1410413D01*
G01X1410415Y574764D02*
X1415748D01*
G01Y574724D02*
X1411400D01*
G01X1415748Y573386D02*
X1410415D01*
G01X1410413Y572894D02*
X1411398D01*
G01X1410413Y609959D02*
X1411369Y609961D01*
G01X1411398Y608190D02*
X1410413Y608189D01*
G01Y604959D02*
X1411369Y604961D01*
G01X1411398Y603190D02*
X1410413Y603189D01*
G01Y599959D02*
X1411369Y599961D01*
G01X1411398Y598190D02*
X1410413Y598189D01*
G01Y594959D02*
X1411369Y594961D01*
G01X1411398Y593190D02*
X1410413Y593189D01*
G01Y589959D02*
X1411369Y589961D01*
G01X1411398Y588190D02*
X1410413Y588189D01*
G01Y584959D02*
X1411369Y584961D01*
G01X1411398Y583190D02*
X1410413Y583189D01*
G01Y579959D02*
X1411369Y579961D01*
G01X1411398Y578190D02*
X1410413Y578189D01*
G01Y574959D02*
X1411369Y574961D01*
G01X1411398Y573190D02*
X1410413Y573189D01*
G01X1365945Y713386D02*
G03X1367126I590J0D01*
G01Y707087D02*
G03X1365945I-591J0D01*
G01X1363976D02*
G03X1362795I-591J0D01*
G01Y713386D02*
G03X1363976I591J0D01*
G01X1365945D02*
G03X1367126I590J0D01*
G01Y707087D02*
G03X1365945I-591J0D01*
G01X1363976D02*
G03X1362795I-591J0D01*
G01Y713386D02*
G03X1363976I591J0D01*
G01X1367913Y707087D02*
Y713386D01*
G01Y707087D02*
Y713386D01*
G01X1362008Y707087D02*
Y713386D01*
G01D02*
Y707087D01*
G01X1365945Y713386D02*
X1363976D01*
G01X1362795D02*
X1362008D01*
G01X1365945D02*
X1363976D01*
G01X1362795D02*
X1362008D01*
G01X1367913D02*
X1367126D01*
G01X1367913D02*
X1367126D01*
G01X1367913Y712402D02*
X1362008D01*
G01Y712205D02*
X1367913D01*
G01X1362008Y708268D02*
X1367913D01*
G01Y708071D02*
X1362008D01*
G01X1367126Y707087D02*
X1367913D01*
G01X1367126D02*
X1367913D01*
G01X1363976D02*
X1365945D01*
G01X1362008D02*
X1362795D01*
G01X1363976D02*
X1365945D01*
G01X1362008D02*
X1362795D01*
G01X1407008Y945020D02*
G03I-1102J0D01*
G01X1408465Y939744D02*
G03X1409646Y940925I0J1181D01*
G01X1402165D02*
G03X1403346Y939744I1181J0D01*
G01X1407480Y945020D02*
G03I-1574J0D01*
G01X1401969Y930650D02*
G03X1402559Y930059I590J-1D01*
G01X1409252D02*
G03X1409843Y930650I0J591D01*
G01X1407087Y931831D02*
G03Y933799I0J984D01*
G01X1404724D02*
G03Y931831I0J-984D01*
G01X1395079Y931240D02*
G03X1397047Y929272I1968J0D01*
G01X1414764D02*
G03X1416732Y931240I0J1968D01*
G01X1407087Y944429D02*
X1409397Y940200D01*
G01X1404724Y946122D02*
X1403421Y948091D01*
G01X1413386Y950335D02*
X1416732Y946988D01*
G01X1406890Y953012D02*
X1408071Y951831D01*
G01X1416732Y931240D02*
Y946988D01*
G01X1413386Y1088327D02*
Y950335D01*
G01X1412795Y1090571D02*
Y948091D01*
G01X1409843Y936752D02*
Y930650D01*
G01X1409646Y949469D02*
Y940925D01*
G01X1408071Y988287D02*
Y951831D01*
G01X1407087Y946122D02*
Y944429D01*
G01X1404724D02*
Y946122D01*
G01X1402165Y940925D02*
Y949469D01*
G01X1401969Y936752D02*
Y930650D01*
G01X1400197Y951831D02*
Y1086831D01*
G01X1398425Y987126D02*
Y948091D01*
G01X1395079Y946988D02*
Y931240D01*
G01X1408390Y948091D02*
X1407087Y946122D01*
G01X1402414Y940200D02*
X1404724Y944429D01*
G01X1408071Y951831D02*
X1400197D01*
G01X1413386Y950335D02*
X1398425D01*
G01X1409646Y949469D02*
X1412795D01*
G01X1402165D02*
X1398425D01*
G01Y948091D02*
X1412795D01*
G01X1407087Y946122D02*
X1404724D01*
G01X1407087Y944429D02*
X1404724D01*
G01X1408465Y939744D02*
X1403346D01*
G01X1416732Y939705D02*
X1395079D01*
G01X1409843Y936752D02*
X1401969D01*
G01Y935177D02*
X1409843D01*
G01X1407087Y933799D02*
X1404724D01*
G01Y931831D02*
X1407087D01*
G01X1409252Y930059D02*
X1402559D01*
G01X1414764Y929272D02*
X1397047D01*
G01X1401378Y953012D02*
X1400197Y951831D01*
G01X1398425Y950335D02*
X1395079Y946988D01*
G01X1397944Y1008191D02*
X1397931Y1008189D01*
G01X1397954Y1008196D02*
X1397944Y1008191D01*
G01Y1005041D02*
X1397931Y1005039D01*
G01X1397954Y1005046D02*
X1397944Y1005041D01*
G01Y1001892D02*
X1397931Y1001890D01*
G01X1397954Y1001896D02*
X1397944Y1001892D01*
G01Y998742D02*
X1397931Y998740D01*
G01X1397954Y998747D02*
X1397944Y998742D01*
G01Y995593D02*
X1397931Y995591D01*
G01X1397954Y995597D02*
X1397944Y995593D01*
G01Y992443D02*
X1397931Y992441D01*
G01X1397954Y992448D02*
X1397944Y992443D01*
G01Y989293D02*
X1397931Y989291D01*
G01X1397954Y989298D02*
X1397944Y989293D01*
G01X1397970Y1008202D02*
X1397972Y1008215D01*
G01X1397963Y1008191D02*
X1397970Y1008202D01*
G01X1397953Y1008183D02*
X1397963Y1008191D01*
G01X1397970Y1001903D02*
X1397972Y1001915D01*
G01X1397963Y1001892D02*
X1397970Y1001903D01*
G01X1397953Y1001884D02*
X1397963Y1001892D01*
G01X1397970Y998754D02*
X1397972Y998766D01*
G01X1397963Y998742D02*
X1397970Y998754D01*
G01X1397953Y998734D02*
X1397963Y998742D01*
G01X1397970Y995604D02*
X1397972Y995616D01*
G01X1397963Y995593D02*
X1397970Y995604D01*
G01X1397953Y995585D02*
X1397963Y995593D01*
G01X1397970Y992454D02*
X1397972Y992467D01*
G01X1397963Y992443D02*
X1397970Y992454D01*
G01X1397953Y992435D02*
X1397963Y992443D01*
G01X1397027Y1009375D02*
Y1009381D01*
G01Y1009371D02*
Y1009375D01*
G01X1397025Y1009370D02*
X1397027Y1009371D01*
G01Y1006225D02*
Y1006231D01*
G01Y1006222D02*
Y1006225D01*
G01X1397025Y1006220D02*
X1397027Y1006222D01*
G01Y1003076D02*
Y1003082D01*
G01Y1003072D02*
Y1003076D01*
G01X1397025Y1003071D02*
X1397027Y1003072D01*
G01Y999926D02*
Y999932D01*
G01Y999922D02*
Y999926D01*
G01X1397025Y999921D02*
X1397027Y999922D01*
G01Y996776D02*
Y996783D01*
G01Y996773D02*
Y996776D01*
G01X1397025Y996772D02*
X1397027Y996773D01*
G01Y993627D02*
Y993633D01*
G01Y993623D02*
Y993627D01*
G01X1397025Y993622D02*
X1397027Y993623D01*
G01Y990477D02*
Y990483D01*
G01Y990474D02*
Y990477D01*
G01X1397025Y990472D02*
X1397027Y990474D01*
G01X1396989Y1009350D02*
X1396988Y1009344D01*
G01X1396991Y1009357D02*
X1396989Y1009350D01*
G01X1396993Y1009363D02*
X1396991Y1009357D01*
G01X1396997Y1009368D02*
X1396993Y1009363D01*
G01X1397002Y1009372D02*
X1396997Y1009368D01*
G01X1397007Y1009376D02*
X1397002Y1009372D01*
G01X1396989Y1006201D02*
X1396988Y1006194D01*
G01X1396991Y1006207D02*
X1396989Y1006201D01*
G01X1396993Y1006213D02*
X1396991Y1006207D01*
G01X1396997Y1006218D02*
X1396993Y1006213D01*
G01X1397002Y1006223D02*
X1396997Y1006218D01*
G01X1397007Y1006226D02*
X1397002Y1006223D01*
G01X1396989Y1003051D02*
X1396988Y1003045D01*
G01X1396991Y1003057D02*
X1396989Y1003051D01*
G01X1396993Y1003063D02*
X1396991Y1003057D01*
G01X1396997Y1003069D02*
X1396993Y1003063D01*
G01X1397002Y1003073D02*
X1396997Y1003069D01*
G01X1397007Y1003077D02*
X1397002Y1003073D01*
G01X1396989Y999902D02*
X1396988Y999895D01*
G01X1396991Y999908D02*
X1396989Y999902D01*
G01X1396993Y999914D02*
X1396991Y999908D01*
G01X1396997Y999919D02*
X1396993Y999914D01*
G01X1397002Y999924D02*
X1396997Y999919D01*
G01X1397007Y999927D02*
X1397002Y999924D01*
G01X1396989Y996752D02*
X1396988Y996746D01*
G01X1396991Y996758D02*
X1396989Y996752D01*
G01X1396993Y996764D02*
X1396991Y996758D01*
G01X1396997Y996769D02*
X1396993Y996764D01*
G01X1397002Y996774D02*
X1396997Y996769D01*
G01X1397007Y996778D02*
X1397002Y996774D01*
G01X1396989Y993602D02*
X1396988Y993596D01*
G01X1396991Y993609D02*
X1396989Y993602D01*
G01X1396993Y993615D02*
X1396991Y993609D01*
G01X1396997Y993620D02*
X1396993Y993615D01*
G01X1397002Y993624D02*
X1396997Y993620D01*
G01X1397007Y993628D02*
X1397002Y993624D01*
G01X1396989Y990453D02*
X1396988Y990446D01*
G01X1396991Y990459D02*
X1396989Y990453D01*
G01X1396993Y990465D02*
X1396991Y990459D01*
G01X1396997Y990470D02*
X1396993Y990465D01*
G01X1397002Y990475D02*
X1396997Y990470D01*
G01X1397007Y990478D02*
X1397002Y990475D01*
G01X1411398Y1046134D02*
Y1046125D01*
G01X1411399Y1046140D02*
X1411398Y1046134D01*
G01X1411400Y1046142D02*
X1411399Y1046140D01*
G01X1411398Y1041134D02*
Y1041125D01*
G01X1411399Y1041140D02*
X1411398Y1041134D01*
G01X1411400Y1041142D02*
X1411399Y1041140D01*
G01X1411398Y1036134D02*
Y1036125D01*
G01X1411399Y1036140D02*
X1411398Y1036134D01*
G01X1411400Y1036142D02*
X1411399Y1036140D01*
G01X1396988Y1009337D02*
Y1009344D01*
G01X1396987Y1009332D02*
X1396988Y1009337D01*
G01X1396986Y1009331D02*
X1396987Y1009332D01*
G01X1396988Y1006187D02*
Y1006194D01*
G01X1396987Y1006183D02*
X1396988Y1006187D01*
G01X1396986Y1006181D02*
X1396987Y1006183D01*
G01X1396988Y1003037D02*
Y1003045D01*
G01X1396987Y1003033D02*
X1396988Y1003037D01*
G01X1396986Y1003031D02*
X1396987Y1003033D01*
G01X1396988Y999888D02*
Y999895D01*
G01X1396987Y999883D02*
X1396988Y999888D01*
G01X1396986Y999882D02*
X1396987Y999883D01*
G01X1396988Y996738D02*
Y996746D01*
G01X1396987Y996734D02*
X1396988Y996738D01*
G01X1396986Y996732D02*
X1396987Y996734D01*
G01X1396988Y993589D02*
Y993596D01*
G01X1396987Y993584D02*
X1396988Y993589D01*
G01X1396986Y993583D02*
X1396987Y993584D01*
G01X1396988Y990439D02*
Y990446D01*
G01X1396987Y990435D02*
X1396988Y990439D01*
G01X1396986Y990433D02*
X1396987Y990435D01*
G01X1397970Y989305D02*
X1397972Y989317D01*
G01X1397963Y989293D02*
X1397970Y989305D01*
G01X1397953Y989285D02*
X1397963Y989293D01*
G01X1396991Y990453D02*
X1396986Y990433D01*
G01X1397006Y990467D02*
X1396991Y990453D01*
G01X1397025Y990472D02*
X1397006Y990467D01*
G01X1396991Y993602D02*
X1396986Y993583D01*
G01X1397006Y993617D02*
X1396991Y993602D01*
G01X1397025Y993622D02*
X1397006Y993617D01*
G01X1396991Y996752D02*
X1396986Y996732D01*
G01X1397006Y996766D02*
X1396991Y996752D01*
G01X1397025Y996772D02*
X1397006Y996766D01*
G01X1396991Y999902D02*
X1396986Y999882D01*
G01X1397006Y999916D02*
X1396991Y999902D01*
G01X1397025Y999921D02*
X1397006Y999916D01*
G01X1396991Y1003051D02*
X1396986Y1003031D01*
G01X1397006Y1003065D02*
X1396991Y1003051D01*
G01X1397025Y1003071D02*
X1397006Y1003065D01*
G01X1396991Y1006201D02*
X1396986Y1006181D01*
G01X1397006Y1006215D02*
X1396991Y1006201D01*
G01X1397025Y1006220D02*
X1397006Y1006215D01*
G01X1396991Y1009350D02*
X1396986Y1009331D01*
G01X1397006Y1009365D02*
X1396991Y1009350D01*
G01X1397025Y1009370D02*
X1397006Y1009365D01*
G01X1397966Y989311D02*
X1397971Y989331D01*
G01X1397951Y989296D02*
X1397966Y989311D01*
G01X1397931Y989291D02*
X1397951Y989296D01*
G01X1397966Y992461D02*
X1397971Y992480D01*
G01X1397951Y992446D02*
X1397966Y992461D01*
G01X1397931Y992441D02*
X1397951Y992446D01*
G01X1397966Y995610D02*
X1397971Y995630D01*
G01X1397951Y995596D02*
X1397966Y995610D01*
G01X1397931Y995591D02*
X1397951Y995596D01*
G01X1397966Y998760D02*
X1397971Y998780D01*
G01X1397951Y998745D02*
X1397966Y998760D01*
G01X1397931Y998740D02*
X1397951Y998745D01*
G01X1397966Y1001909D02*
X1397971Y1001929D01*
G01X1397951Y1001895D02*
X1397966Y1001909D01*
G01X1397931Y1001890D02*
X1397951Y1001895D01*
G01X1397966Y1005059D02*
X1397971Y1005079D01*
G01X1397951Y1005044D02*
X1397966Y1005059D01*
G01X1397931Y1005039D02*
X1397951Y1005044D01*
G01X1397966Y1008209D02*
X1397971Y1008228D01*
G01X1397951Y1008194D02*
X1397966Y1008209D01*
G01X1397931Y1008189D02*
X1397951Y1008194D01*
G01X1397933Y1009375D02*
Y1009381D01*
G01X1397932Y1009371D02*
X1397933Y1009375D01*
G01X1397931Y1009370D02*
X1397932Y1009371D01*
G01X1397933Y1006226D02*
Y1006231D01*
G01X1397932Y1006222D02*
X1397933Y1006226D01*
G01X1397931Y1006220D02*
X1397932Y1006222D01*
G01X1397933Y1003076D02*
Y1003082D01*
G01X1397932Y1003072D02*
X1397933Y1003076D01*
G01X1397931Y1003071D02*
X1397932Y1003072D01*
G01X1397933Y999926D02*
Y999932D01*
G01X1397932Y999922D02*
X1397933Y999926D01*
G01X1397931Y999921D02*
X1397932Y999922D01*
G01X1397933Y996777D02*
Y996783D01*
G01X1397932Y996773D02*
X1397933Y996777D01*
G01X1397931Y996772D02*
X1397932Y996773D01*
G01X1397933Y993627D02*
Y993633D01*
G01X1397932Y993623D02*
X1397933Y993627D01*
G01X1397931Y993622D02*
X1397932Y993623D01*
G01X1397933Y990478D02*
Y990483D01*
G01X1397932Y990474D02*
X1397933Y990478D01*
G01X1397931Y990472D02*
X1397932Y990474D01*
G01X1411398Y1031134D02*
Y1031125D01*
G01X1411399Y1031140D02*
X1411398Y1031134D01*
G01X1411400Y1031142D02*
X1411399Y1031140D01*
G01X1411398Y1026134D02*
Y1026125D01*
G01X1411399Y1026140D02*
X1411398Y1026134D01*
G01X1411400Y1026142D02*
X1411399Y1026140D01*
G01X1411398Y1021134D02*
Y1021125D01*
G01X1411399Y1021140D02*
X1411398Y1021134D01*
G01X1411400Y1021142D02*
X1411399Y1021140D01*
G01X1411398Y1016134D02*
Y1016125D01*
G01X1411399Y1016140D02*
X1411398Y1016134D01*
G01X1411400Y1016142D02*
X1411399Y1016140D01*
G01X1411398Y1011134D02*
Y1011125D01*
G01X1411399Y1011140D02*
X1411398Y1011134D01*
G01X1411400Y1011142D02*
X1411399Y1011140D01*
G01X1411398Y986134D02*
Y986125D01*
G01X1411399Y986140D02*
X1411398Y986134D01*
G01X1411400Y986142D02*
X1411399Y986140D01*
G01X1411398Y981134D02*
Y981125D01*
G01X1411399Y981140D02*
X1411398Y981134D01*
G01X1411400Y981142D02*
X1411399Y981140D01*
G01X1411398Y976134D02*
Y976125D01*
G01X1411399Y976140D02*
X1411398Y976134D01*
G01X1411400Y976142D02*
X1411399Y976140D01*
G01X1411398Y971134D02*
Y971125D01*
G01X1411399Y971140D02*
X1411398Y971134D01*
G01X1411400Y971142D02*
X1411399Y971140D01*
G01X1411398Y966134D02*
Y966125D01*
G01X1411399Y966140D02*
X1411398Y966134D01*
G01X1411400Y966142D02*
X1411399Y966140D01*
G01X1411398Y961134D02*
Y961125D01*
G01X1411399Y961140D02*
X1411398Y961134D01*
G01X1411400Y961142D02*
X1411399Y961140D01*
G01X1411398Y956134D02*
Y956125D01*
G01X1411399Y956140D02*
X1411398Y956134D01*
G01X1411400Y956142D02*
X1411399Y956140D01*
G01X1397972Y1005058D02*
Y1005065D01*
G01X1397969Y1005051D02*
X1397972Y1005058D01*
G01X1397966Y1005044D02*
X1397969Y1005051D01*
G01X1397961Y1005039D02*
X1397966Y1005044D01*
G01X1397955Y1005034D02*
X1397961Y1005039D01*
G01X1397948Y1005031D02*
X1397955Y1005034D01*
G01X1397941Y1005029D02*
X1397948Y1005031D01*
G01X1397933Y1005028D02*
X1397941Y1005029D01*
G01X1397950Y989283D02*
X1397953Y989285D01*
G01X1397947Y989282D02*
X1397950Y989283D01*
G01X1397944Y989281D02*
X1397947Y989282D01*
G01X1397940Y989281D02*
X1397944D01*
G01X1397937Y989280D02*
X1397940Y989281D01*
G01X1397933Y989280D02*
X1397937D01*
G01X1397011Y990480D02*
X1397007Y990478D01*
G01X1397014Y990481D02*
X1397011Y990480D01*
G01X1397017Y990482D02*
X1397014Y990481D01*
G01X1397020Y990483D02*
X1397017Y990482D01*
G01X1397024Y990483D02*
X1397020D01*
G01X1397028D02*
X1397024D01*
G01X1397950Y992433D02*
X1397953Y992435D01*
G01X1397947Y992432D02*
X1397950Y992433D01*
G01X1397944Y992431D02*
X1397947Y992432D01*
G01X1397940Y992430D02*
X1397944Y992431D01*
G01X1397937Y992430D02*
X1397940D01*
G01X1397933D02*
X1397937D01*
G01X1397011Y993630D02*
X1397007Y993628D01*
G01X1397014Y993631D02*
X1397011Y993630D01*
G01X1397017Y993632D02*
X1397014Y993631D01*
G01X1397020Y993633D02*
X1397017Y993632D01*
G01X1397024Y993633D02*
X1397020D01*
G01X1397028D02*
X1397024D01*
G01X1397950Y995583D02*
X1397953Y995585D01*
G01X1397947Y995581D02*
X1397950Y995583D01*
G01X1397944Y995581D02*
X1397947D01*
G01X1397940Y995580D02*
X1397944Y995581D01*
G01X1397937Y995580D02*
X1397940D01*
G01X1397933Y995579D02*
X1397937Y995580D01*
G01X1397011Y996779D02*
X1397007Y996778D01*
G01X1397014Y996780D02*
X1397011Y996779D01*
G01X1397017Y996781D02*
X1397014Y996780D01*
G01X1397020Y996782D02*
X1397017Y996781D01*
G01X1397024Y996783D02*
X1397020Y996782D01*
G01X1397028Y996783D02*
X1397024D01*
G01X1397950Y998732D02*
X1397953Y998734D01*
G01X1397947Y998731D02*
X1397950Y998732D01*
G01X1397944Y998730D02*
X1397947Y998731D01*
G01X1397940Y998730D02*
X1397944D01*
G01X1397937Y998729D02*
X1397940Y998730D01*
G01X1397933Y998729D02*
X1397937D01*
G01X1397011Y999929D02*
X1397007Y999927D01*
G01X1397014Y999930D02*
X1397011Y999929D01*
G01X1397017Y999931D02*
X1397014Y999930D01*
G01X1397020Y999932D02*
X1397017Y999931D01*
G01X1397024Y999932D02*
X1397020D01*
G01X1397028D02*
X1397024D01*
G01X1397950Y1001882D02*
X1397953Y1001884D01*
G01X1397947Y1001881D02*
X1397950Y1001882D01*
G01X1397944Y1001880D02*
X1397947Y1001881D01*
G01X1397940Y1001879D02*
X1397944Y1001880D01*
G01X1397937Y1001879D02*
X1397940D01*
G01X1397933Y1001878D02*
X1397937Y1001879D01*
G01X1397011Y1003078D02*
X1397007Y1003077D01*
G01X1397014Y1003080D02*
X1397011Y1003078D01*
G01X1397017Y1003081D02*
X1397014Y1003080D01*
G01X1397020Y1003081D02*
X1397017D01*
G01X1397024Y1003082D02*
X1397020Y1003081D01*
G01X1397028Y1003082D02*
X1397024D01*
G01X1397011Y1006228D02*
X1397007Y1006226D01*
G01X1397014Y1006229D02*
X1397011Y1006228D01*
G01X1397017Y1006230D02*
X1397014Y1006229D01*
G01X1397020Y1006231D02*
X1397017Y1006230D01*
G01X1397024Y1006231D02*
X1397020D01*
G01X1397028D02*
X1397024D01*
G01X1397950Y1008181D02*
X1397953Y1008183D01*
G01X1397947Y1008180D02*
X1397950Y1008181D01*
G01X1397944Y1008179D02*
X1397947Y1008180D01*
G01X1397940Y1008178D02*
X1397944Y1008179D01*
G01X1397937Y1008178D02*
X1397940D01*
G01X1397933D02*
X1397937D01*
G01X1397011Y1009378D02*
X1397007Y1009376D01*
G01X1397014Y1009379D02*
X1397011Y1009378D01*
G01X1397017Y1009380D02*
X1397014Y1009379D01*
G01X1397020Y1009381D02*
X1397017Y1009380D01*
G01X1397024Y1009381D02*
X1397020D01*
G01X1397028D02*
X1397024D01*
G01X1397972Y1009337D02*
Y1009344D01*
G01Y1009332D02*
Y1009337D01*
G01X1397971Y1009331D02*
X1397972Y1009332D01*
G01Y1006187D02*
Y1006194D01*
G01Y1006183D02*
Y1006187D01*
G01X1397971Y1006181D02*
X1397972Y1006183D01*
G01Y1003038D02*
Y1003045D01*
G01Y1003033D02*
Y1003038D01*
G01X1397971Y1003031D02*
X1397972Y1003033D01*
G01Y999888D02*
Y999895D01*
G01Y999883D02*
Y999888D01*
G01X1397971Y999882D02*
X1397972Y999883D01*
G01Y996739D02*
Y996746D01*
G01Y996734D02*
Y996739D01*
G01X1397971Y996732D02*
X1397972Y996734D01*
G01Y993589D02*
Y993596D01*
G01Y993584D02*
Y993589D01*
G01X1397971Y993583D02*
X1397972Y993584D01*
G01Y990439D02*
Y990446D01*
G01Y990435D02*
Y990439D01*
G01X1397971Y990433D02*
X1397972Y990435D01*
G01X1396988Y998774D02*
Y998766D01*
G01X1396987Y998778D02*
X1396988Y998774D01*
G01X1396986Y998775D02*
X1396987Y998778D01*
G01X1396988Y992474D02*
Y992467D01*
G01X1396987Y992479D02*
X1396988Y992474D01*
G01X1396986Y992477D02*
X1396987Y992479D01*
G01X1397963Y990471D02*
X1397967Y990465D01*
G01X1397958Y990475D02*
X1397963Y990471D01*
G01X1397952Y990479D02*
X1397958Y990475D01*
G01X1397946Y990481D02*
X1397952Y990479D01*
G01X1397940Y990483D02*
X1397946Y990481D01*
G01X1397933Y990483D02*
X1397940D01*
G01X1397963Y993620D02*
X1397967Y993615D01*
G01X1397958Y993625D02*
X1397963Y993620D01*
G01X1397952Y993628D02*
X1397958Y993625D01*
G01X1397946Y993631D02*
X1397952Y993628D01*
G01X1397940Y993633D02*
X1397946Y993631D01*
G01X1397933Y993633D02*
X1397940D01*
G01X1397963Y996770D02*
X1397967Y996765D01*
G01X1397958Y996774D02*
X1397963Y996770D01*
G01X1397952Y996778D02*
X1397958Y996774D01*
G01X1397946Y996781D02*
X1397952Y996778D01*
G01X1397940Y996782D02*
X1397946Y996781D01*
G01X1397933Y996783D02*
X1397940Y996782D01*
G01X1397963Y999920D02*
X1397967Y999914D01*
G01X1397958Y999924D02*
X1397963Y999920D01*
G01X1397952Y999928D02*
X1397958Y999924D01*
G01X1397946Y999930D02*
X1397952Y999928D01*
G01X1397940Y999932D02*
X1397946Y999930D01*
G01X1397933Y999932D02*
X1397940D01*
G01X1397963Y1003069D02*
X1397967Y1003064D01*
G01X1397958Y1003074D02*
X1397963Y1003069D01*
G01X1397952Y1003077D02*
X1397958Y1003074D01*
G01X1397946Y1003080D02*
X1397952Y1003077D01*
G01X1397940Y1003081D02*
X1397946Y1003080D01*
G01X1397933Y1003082D02*
X1397940Y1003081D01*
G01X1397963Y1006219D02*
X1397967Y1006213D01*
G01X1397958Y1006223D02*
X1397963Y1006219D01*
G01X1397952Y1006227D02*
X1397958Y1006223D01*
G01X1397946Y1006230D02*
X1397952Y1006227D01*
G01X1397940Y1006231D02*
X1397946Y1006230D01*
G01X1397933Y1006231D02*
X1397940D01*
G01X1397963Y1009369D02*
X1397967Y1009363D01*
G01X1397958Y1009373D02*
X1397963Y1009369D01*
G01X1397952Y1009376D02*
X1397958Y1009373D01*
G01X1397946Y1009379D02*
X1397952Y1009376D01*
G01X1397940Y1009381D02*
X1397946Y1009379D01*
G01X1397933Y1009381D02*
X1397940D01*
G01X1396989Y989310D02*
X1396988Y989317D01*
G01X1396991Y989303D02*
X1396989Y989310D01*
G01X1396995Y989296D02*
X1396991Y989303D01*
G01X1397000Y989291D02*
X1396995Y989296D01*
G01X1397006Y989286D02*
X1397000Y989291D01*
G01X1397013Y989283D02*
X1397006Y989286D01*
G01X1397020Y989281D02*
X1397013Y989283D01*
G01X1397028Y989280D02*
X1397020Y989281D01*
G01X1396989Y992459D02*
X1396988Y992467D01*
G01X1396991Y992452D02*
X1396989Y992459D01*
G01X1396995Y992446D02*
X1396991Y992452D01*
G01X1397000Y992441D02*
X1396995Y992446D01*
G01X1397006Y992436D02*
X1397000Y992441D01*
G01X1397013Y992432D02*
X1397006Y992436D01*
G01X1397020Y992430D02*
X1397013Y992432D01*
G01X1397028Y992430D02*
X1397020D01*
G01X1396989Y995609D02*
X1396988Y995616D01*
G01X1396991Y995602D02*
X1396989Y995609D01*
G01X1396995Y995596D02*
X1396991Y995602D01*
G01X1397000Y995590D02*
X1396995Y995596D01*
G01X1397006Y995585D02*
X1397000Y995590D01*
G01X1397013Y995582D02*
X1397006Y995585D01*
G01X1397020Y995580D02*
X1397013Y995582D01*
G01X1397028Y995579D02*
X1397020Y995580D01*
G01X1396989Y998759D02*
X1396988Y998766D01*
G01X1396991Y998752D02*
X1396989Y998759D01*
G01X1396995Y998745D02*
X1396991Y998752D01*
G01X1397000Y998740D02*
X1396995Y998745D01*
G01X1397006Y998735D02*
X1397000Y998740D01*
G01X1397013Y998731D02*
X1397006Y998735D01*
G01X1397020Y998730D02*
X1397013Y998731D01*
G01X1397028Y998729D02*
X1397020Y998730D01*
G01X1396989Y1001908D02*
X1396988Y1001915D01*
G01X1396991Y1001901D02*
X1396989Y1001908D01*
G01X1396995Y1001895D02*
X1396991Y1001901D01*
G01X1397000Y1001889D02*
X1396995Y1001895D01*
G01X1397006Y1001885D02*
X1397000Y1001889D01*
G01X1397013Y1001881D02*
X1397006Y1001885D01*
G01X1397020Y1001879D02*
X1397013Y1001881D01*
G01X1397028Y1001878D02*
X1397020Y1001879D01*
G01X1396989Y1005058D02*
X1396988Y1005065D01*
G01X1396991Y1005051D02*
X1396989Y1005058D01*
G01X1396995Y1005044D02*
X1396991Y1005051D01*
G01X1397000Y1005039D02*
X1396995Y1005044D01*
G01X1397006Y1005034D02*
X1397000Y1005039D01*
G01X1397013Y1005031D02*
X1397006Y1005034D01*
G01X1397020Y1005029D02*
X1397013Y1005031D01*
G01X1397028Y1005028D02*
X1397020Y1005029D01*
G01X1396989Y1008207D02*
X1396988Y1008215D01*
G01X1396991Y1008200D02*
X1396989Y1008207D01*
G01X1396995Y1008194D02*
X1396991Y1008200D01*
G01X1397000Y1008189D02*
X1396995Y1008194D01*
G01X1397006Y1008184D02*
X1397000Y1008189D01*
G01X1397013Y1008180D02*
X1397006Y1008184D01*
G01X1397020Y1008178D02*
X1397013Y1008180D01*
G01X1397028Y1008178D02*
X1397020D01*
G01X1397942Y990471D02*
X1397952Y990467D01*
G01X1397931Y990472D02*
X1397942Y990471D01*
G01Y993620D02*
X1397952Y993617D01*
G01X1397931Y993622D02*
X1397942Y993620D01*
G01Y996770D02*
X1397952Y996766D01*
G01X1397931Y996772D02*
X1397942Y996770D01*
G01Y999920D02*
X1397952Y999916D01*
G01X1397931Y999921D02*
X1397942Y999920D01*
G01Y1003069D02*
X1397952Y1003065D01*
G01X1397931Y1003071D02*
X1397942Y1003069D01*
G01Y1006219D02*
X1397952Y1006215D01*
G01X1397931Y1006220D02*
X1397942Y1006219D01*
G01Y1009369D02*
X1397952Y1009365D01*
G01X1397931Y1009370D02*
X1397942Y1009369D01*
G01X1411385Y957511D02*
X1411396Y957496D01*
G01X1411361Y957520D02*
X1411385Y957511D01*
G01Y962511D02*
X1411396Y962496D01*
G01X1411361Y962520D02*
X1411385Y962511D01*
G01X1397025Y1008017D02*
X1397024Y1008031D01*
G01X1397028Y1008005D02*
X1397025Y1008017D01*
G01X1397028Y1007992D02*
Y1008005D01*
G01X1397025Y1004868D02*
X1397024Y1004881D01*
G01X1397028Y1004855D02*
X1397025Y1004868D01*
G01X1397028Y1004843D02*
Y1004855D01*
G01X1397025Y1001718D02*
X1397024Y1001732D01*
G01X1397028Y1001706D02*
X1397025Y1001718D01*
G01X1397028Y1001693D02*
Y1001706D01*
G01X1397025Y998569D02*
X1397024Y998582D01*
G01X1397028Y998556D02*
X1397025Y998569D01*
G01X1397028Y998543D02*
Y998556D01*
G01X1397025Y995419D02*
X1397024Y995433D01*
G01X1397028Y995406D02*
X1397025Y995419D01*
G01X1397028Y995394D02*
Y995406D01*
G01X1397025Y992269D02*
X1397024Y992283D01*
G01X1397028Y992257D02*
X1397025Y992269D01*
G01X1397028Y992244D02*
Y992257D01*
G01X1397025Y989120D02*
X1397024Y989133D01*
G01X1397028Y989107D02*
X1397025Y989120D01*
G01X1397028Y989094D02*
Y989107D01*
G01X1397935Y1009541D02*
X1397937Y1009528D01*
G01X1397932Y1009554D02*
X1397935Y1009541D01*
G01X1397933Y1009567D02*
X1397932Y1009554D01*
G01X1397935Y1006392D02*
X1397937Y1006378D01*
G01X1397932Y1006405D02*
X1397935Y1006392D01*
G01X1397933Y1006417D02*
X1397932Y1006405D01*
G01X1397935Y1003242D02*
X1397937Y1003228D01*
G01X1397932Y1003255D02*
X1397935Y1003242D01*
G01X1397933Y1003268D02*
X1397932Y1003255D01*
G01X1397935Y1000093D02*
X1397937Y1000079D01*
G01X1397932Y1000106D02*
X1397935Y1000093D01*
G01X1397933Y1000118D02*
X1397932Y1000106D01*
G01X1397935Y996943D02*
X1397937Y996929D01*
G01X1397932Y996956D02*
X1397935Y996943D01*
G01X1397933Y996969D02*
X1397932Y996956D01*
G01X1397935Y993793D02*
X1397937Y993780D01*
G01X1397932Y993806D02*
X1397935Y993793D01*
G01X1397933Y993819D02*
X1397932Y993806D01*
G01X1397935Y990644D02*
X1397937Y990630D01*
G01X1397932Y990657D02*
X1397935Y990644D01*
G01X1397933Y990669D02*
X1397932Y990657D01*
G01X1396988Y995624D02*
Y995617D01*
G01X1396987Y995628D02*
X1396988Y995624D01*
G01X1396987Y995621D02*
Y995628D01*
G01X1396988Y1005073D02*
Y1005065D01*
G01X1396987Y1005077D02*
X1396988Y1005073D01*
G01X1396987Y1005070D02*
Y1005077D01*
G01X1397932Y1008005D02*
X1397933Y1007992D01*
G01X1397935Y1008017D02*
X1397932Y1008005D01*
G01X1397936Y1008031D02*
X1397935Y1008017D01*
G01X1397932Y1004855D02*
X1397933Y1004843D01*
G01X1397935Y1004868D02*
X1397932Y1004855D01*
G01X1397936Y1004881D02*
X1397935Y1004868D01*
G01X1397932Y1001706D02*
X1397933Y1001693D01*
G01X1397935Y1001718D02*
X1397932Y1001706D01*
G01X1397936Y1001732D02*
X1397935Y1001718D01*
G01X1397932Y998556D02*
X1397933Y998543D01*
G01X1397935Y998569D02*
X1397932Y998556D01*
G01X1397936Y998582D02*
X1397935Y998569D01*
G01X1397932Y995406D02*
X1397933Y995394D01*
G01X1397935Y995419D02*
X1397932Y995406D01*
G01X1397936Y995433D02*
X1397935Y995419D01*
G01X1397932Y992257D02*
X1397933Y992244D01*
G01X1397935Y992269D02*
X1397932Y992257D01*
G01X1397936Y992283D02*
X1397935Y992269D01*
G01X1397932Y989107D02*
X1397933Y989094D01*
G01X1397935Y989120D02*
X1397932Y989107D01*
G01X1397936Y989133D02*
X1397935Y989120D01*
G01X1396988Y989325D02*
Y989317D01*
G01X1396987Y989329D02*
X1396988Y989325D01*
G01X1396987Y989323D02*
Y989329D01*
G01X1397001Y1009361D02*
X1397025Y1009370D01*
G01X1396990Y1009347D02*
X1397001Y1009361D01*
G01X1396988Y1009340D02*
X1396990Y1009347D01*
G01X1396988Y992470D02*
Y992467D01*
G01X1396990Y992464D02*
X1396988Y992470D01*
G01X1397002Y992449D02*
X1396990Y992464D01*
G01X1397026Y992441D02*
X1397002Y992449D01*
G01X1396988Y995620D02*
Y995616D01*
G01X1396990Y995614D02*
X1396988Y995620D01*
G01X1397001Y995599D02*
X1396990Y995614D01*
G01X1397026Y995591D02*
X1397001Y995599D01*
G01X1396988Y1001919D02*
Y1001915D01*
G01X1396990Y1001913D02*
X1396988Y1001919D01*
G01X1397001Y1001898D02*
X1396990Y1001913D01*
G01X1397026Y1001890D02*
X1397001Y1001898D01*
G01X1396988Y1005069D02*
Y1005065D01*
G01X1396990Y1005063D02*
X1396988Y1005069D01*
G01X1397001Y1005048D02*
X1396990Y1005063D01*
G01X1397026Y1005039D02*
X1397001Y1005048D01*
G01X1396988Y989321D02*
Y989317D01*
G01X1396990Y989315D02*
X1396988Y989321D01*
G01X1397001Y989300D02*
X1396990Y989315D01*
G01X1397026Y989291D02*
X1397001Y989300D01*
G01X1396988Y1008219D02*
Y1008215D01*
G01X1396990Y1008213D02*
X1396988Y1008219D01*
G01X1397001Y1008197D02*
X1396990Y1008213D01*
G01X1397026Y1008189D02*
X1397001Y1008197D01*
G01X1411385Y967511D02*
X1411396Y967496D01*
G01X1411361Y967520D02*
X1411385Y967511D01*
G01Y972511D02*
X1411396Y972496D01*
G01X1411361Y972520D02*
X1411385Y972511D01*
G01Y977511D02*
X1411396Y977496D01*
G01X1411361Y977520D02*
X1411385Y977511D01*
G01Y982511D02*
X1411396Y982496D01*
G01X1411361Y982520D02*
X1411385Y982511D01*
G01Y987511D02*
X1411396Y987496D01*
G01X1411361Y987520D02*
X1411385Y987511D01*
G01Y1012511D02*
X1411396Y1012496D01*
G01X1411361Y1012520D02*
X1411385Y1012511D01*
G01Y1017511D02*
X1411396Y1017496D01*
G01X1411361Y1017520D02*
X1411385Y1017511D01*
G01Y1022511D02*
X1411396Y1022496D01*
G01X1411361Y1022520D02*
X1411385Y1022511D01*
G01Y1027511D02*
X1411396Y1027496D01*
G01X1411361Y1027520D02*
X1411385Y1027511D01*
G01Y1032511D02*
X1411396Y1032496D01*
G01X1411361Y1032520D02*
X1411385Y1032511D01*
G01Y1037511D02*
X1411396Y1037496D01*
G01X1411361Y1037520D02*
X1411385Y1037511D01*
G01Y1042511D02*
X1411396Y1042496D01*
G01X1411361Y1042520D02*
X1411385Y1042511D01*
G01Y1047511D02*
X1411396Y1047496D01*
G01X1411361Y1047520D02*
X1411385Y1047511D01*
G01X1396988Y998770D02*
Y998766D01*
G01X1396990Y998764D02*
X1396988Y998770D01*
G01X1397000Y998750D02*
X1396990Y998764D01*
G01X1397023Y998740D02*
X1397000Y998750D01*
G01X1411365Y957618D02*
X1411369Y957717D01*
G01X1411359Y957546D02*
X1411365Y957618D01*
G01X1411361Y957520D02*
X1411359Y957546D01*
G01X1411365Y962618D02*
X1411369Y962717D01*
G01X1411359Y962546D02*
X1411365Y962618D01*
G01X1411361Y962520D02*
X1411359Y962546D01*
G01X1411365Y967618D02*
X1411369Y967717D01*
G01X1411359Y967546D02*
X1411365Y967618D01*
G01X1411361Y967520D02*
X1411359Y967546D01*
G01X1411365Y972618D02*
X1411369Y972717D01*
G01X1411359Y972546D02*
X1411365Y972618D01*
G01X1411361Y972520D02*
X1411359Y972546D01*
G01X1411365Y977618D02*
X1411369Y977717D01*
G01X1411359Y977546D02*
X1411365Y977618D01*
G01X1411361Y977520D02*
X1411359Y977546D01*
G01X1411365Y982618D02*
X1411369Y982717D01*
G01X1411359Y982546D02*
X1411365Y982618D01*
G01X1411361Y982520D02*
X1411359Y982546D01*
G01X1411365Y987618D02*
X1411369Y987717D01*
G01X1411359Y987546D02*
X1411365Y987618D01*
G01X1411361Y987520D02*
X1411359Y987546D01*
G01X1411365Y1012618D02*
X1411369Y1012717D01*
G01X1411359Y1012546D02*
X1411365Y1012618D01*
G01X1411361Y1012520D02*
X1411359Y1012546D01*
G01X1411365Y1017618D02*
X1411369Y1017717D01*
G01X1411359Y1017546D02*
X1411365Y1017618D01*
G01X1411361Y1017520D02*
X1411359Y1017546D01*
G01X1411365Y1022618D02*
X1411369Y1022717D01*
G01X1411359Y1022546D02*
X1411365Y1022618D01*
G01X1411361Y1022520D02*
X1411359Y1022546D01*
G01X1411365Y1027618D02*
X1411369Y1027717D01*
G01X1411359Y1027546D02*
X1411365Y1027618D01*
G01X1411361Y1027520D02*
X1411359Y1027546D01*
G01X1411365Y1032618D02*
X1411369Y1032717D01*
G01X1411359Y1032546D02*
X1411365Y1032618D01*
G01X1411361Y1032520D02*
X1411359Y1032546D01*
G01X1411365Y1037618D02*
X1411369Y1037717D01*
G01X1411359Y1037546D02*
X1411365Y1037618D01*
G01X1411361Y1037520D02*
X1411359Y1037546D01*
G01X1411365Y1042618D02*
X1411369Y1042717D01*
G01X1411359Y1042546D02*
X1411365Y1042618D01*
G01X1411361Y1042520D02*
X1411359Y1042546D01*
G01X1396988Y1001923D02*
Y1001916D01*
G01X1396987Y1001928D02*
X1396988Y1001923D01*
G01X1396987Y1001918D02*
Y1001928D01*
G01X1397028Y1009554D02*
Y1009567D01*
G01X1397025Y1009541D02*
X1397028Y1009554D01*
G01X1397025Y1009528D02*
Y1009541D01*
G01X1397028Y1006405D02*
Y1006417D01*
G01X1397025Y1006392D02*
X1397028Y1006405D01*
G01X1397025Y1006378D02*
Y1006392D01*
G01X1397028Y1003255D02*
Y1003268D01*
G01X1397025Y1003242D02*
X1397028Y1003255D01*
G01X1397025Y1003228D02*
Y1003242D01*
G01X1397028Y1000106D02*
Y1000118D01*
G01X1397025Y1000093D02*
X1397028Y1000106D01*
G01X1397025Y1000079D02*
Y1000093D01*
G01X1397028Y996956D02*
Y996969D01*
G01X1397025Y996943D02*
X1397028Y996956D01*
G01X1397025Y996929D02*
Y996943D01*
G01X1397028Y993806D02*
Y993819D01*
G01X1397025Y993793D02*
X1397028Y993806D01*
G01X1397025Y993780D02*
Y993793D01*
G01X1397028Y990657D02*
Y990669D01*
G01X1397025Y990644D02*
X1397028Y990657D01*
G01X1397025Y990630D02*
Y990644D01*
G01X1410414Y1046140D02*
X1410415Y1046142D01*
G01X1410413Y1046134D02*
X1410414Y1046140D01*
G01X1410413Y1046126D02*
Y1046134D01*
G01X1410414Y1041140D02*
X1410415Y1041142D01*
G01X1410413Y1041134D02*
X1410414Y1041140D01*
G01X1410413Y1041126D02*
Y1041134D01*
G01X1410414Y1036140D02*
X1410415Y1036142D01*
G01X1410413Y1036134D02*
X1410414Y1036140D01*
G01X1410413Y1036126D02*
Y1036134D01*
G01X1410414Y1031140D02*
X1410415Y1031142D01*
G01X1410413Y1031134D02*
X1410414Y1031140D01*
G01X1410413Y1031126D02*
Y1031134D01*
G01X1410414Y1026140D02*
X1410415Y1026142D01*
G01X1410413Y1026134D02*
X1410414Y1026140D01*
G01X1410413Y1026126D02*
Y1026134D01*
G01X1410414Y1021140D02*
X1410415Y1021142D01*
G01X1410413Y1021134D02*
X1410414Y1021140D01*
G01X1410413Y1021126D02*
Y1021134D01*
G01X1410414Y1016140D02*
X1410415Y1016142D01*
G01X1410413Y1016134D02*
X1410414Y1016140D01*
G01X1410413Y1016126D02*
Y1016134D01*
G01X1410414Y1011140D02*
X1410415Y1011142D01*
G01X1410413Y1011134D02*
X1410414Y1011140D01*
G01X1410413Y1011126D02*
Y1011134D01*
G01X1410414Y986140D02*
X1410415Y986142D01*
G01X1410413Y986134D02*
X1410414Y986140D01*
G01X1410413Y986126D02*
Y986134D01*
G01X1410414Y981140D02*
X1410415Y981142D01*
G01X1410413Y981134D02*
X1410414Y981140D01*
G01X1410413Y981126D02*
Y981134D01*
G01X1410414Y976140D02*
X1410415Y976142D01*
G01X1410413Y976134D02*
X1410414Y976140D01*
G01X1410413Y976126D02*
Y976134D01*
G01X1410414Y971140D02*
X1410415Y971142D01*
G01X1410413Y971134D02*
X1410414Y971140D01*
G01X1410413Y971126D02*
Y971134D01*
G01X1410414Y966140D02*
X1410415Y966142D01*
G01X1410413Y966134D02*
X1410414Y966140D01*
G01X1410413Y966126D02*
Y966134D01*
G01X1410414Y961140D02*
X1410415Y961142D01*
G01X1410413Y961134D02*
X1410414Y961140D01*
G01X1410413Y961126D02*
Y961134D01*
G01X1410414Y956140D02*
X1410415Y956142D01*
G01X1410413Y956134D02*
X1410414Y956140D01*
G01X1410413Y956126D02*
Y956134D01*
G01X1396988Y1008222D02*
Y1008215D01*
G01X1396987Y1008227D02*
X1396988Y1008222D01*
G01X1396987Y1008219D02*
Y1008227D01*
G01X1397001Y1006212D02*
X1397025Y1006220D01*
G01X1396990Y1006197D02*
X1397001Y1006212D01*
G01X1396988Y1006191D02*
X1396990Y1006197D01*
G01X1396988Y1006194D02*
Y1006191D01*
G01X1397001Y1003062D02*
X1397025Y1003071D01*
G01X1396990Y1003048D02*
X1397001Y1003062D01*
G01X1396988Y1003041D02*
X1396990Y1003048D01*
G01X1396988Y1003045D02*
Y1003041D01*
G01X1397001Y999913D02*
X1397025Y999921D01*
G01X1396990Y999898D02*
X1397001Y999913D01*
G01X1396988Y999891D02*
X1396990Y999898D01*
G01X1396988Y999895D02*
Y999891D01*
G01X1397001Y996763D02*
X1397025Y996772D01*
G01X1396990Y996748D02*
X1397001Y996763D01*
G01X1396988Y996742D02*
X1396990Y996748D01*
G01X1396988Y996746D02*
Y996742D01*
G01X1397001Y993613D02*
X1397025Y993622D01*
G01X1396990Y993599D02*
X1397001Y993613D01*
G01X1396988Y993592D02*
X1396990Y993599D01*
G01X1396988Y993596D02*
Y993592D01*
G01X1397001Y990464D02*
X1397025Y990472D01*
G01X1396990Y990449D02*
X1397001Y990464D01*
G01X1396988Y990443D02*
X1396990Y990449D01*
G01X1396988Y990446D02*
Y990443D01*
G01X1397941Y996770D02*
X1397931Y996772D01*
G01X1397950Y996767D02*
X1397941Y996770D01*
G01X1397957Y996762D02*
X1397950Y996767D01*
G01X1397941Y990471D02*
X1397931Y990472D01*
G01X1397950Y990468D02*
X1397941Y990471D01*
G01X1397957Y990463D02*
X1397950Y990468D01*
G01X1397941Y993621D02*
X1397931Y993622D01*
G01X1397950Y993618D02*
X1397941Y993621D01*
G01X1397957Y993612D02*
X1397950Y993618D01*
G01X1397941Y999920D02*
X1397931Y999921D01*
G01X1397950Y999917D02*
X1397941Y999920D01*
G01X1397957Y999911D02*
X1397950Y999917D01*
G01X1397941Y1003070D02*
X1397931Y1003071D01*
G01X1397950Y1003067D02*
X1397941Y1003070D01*
G01X1397957Y1003061D02*
X1397950Y1003067D01*
G01X1397941Y1006219D02*
X1397931Y1006220D01*
G01X1397950Y1006216D02*
X1397941Y1006219D01*
G01X1397957Y1006211D02*
X1397950Y1006216D01*
G01X1397941Y1009369D02*
X1397931Y1009370D01*
G01X1397950Y1009366D02*
X1397941Y1009369D01*
G01X1397957Y1009360D02*
X1397950Y1009366D01*
G01X1397027Y989286D02*
X1397028Y989280D01*
G01X1397026Y989290D02*
X1397027Y989286D01*
G01X1397025Y989291D02*
X1397026Y989290D01*
G01X1397027Y992436D02*
X1397028Y992430D01*
G01X1397026Y992440D02*
X1397027Y992436D01*
G01X1397025Y992441D02*
X1397026Y992440D01*
G01X1397027Y995585D02*
X1397028Y995579D01*
G01X1397026Y995589D02*
X1397027Y995585D01*
G01X1397025Y995591D02*
X1397026Y995589D01*
G01X1397027Y998735D02*
X1397028Y998729D01*
G01X1397026Y998739D02*
X1397027Y998735D01*
G01X1397025Y998740D02*
X1397026Y998739D01*
G01X1397027Y1001885D02*
X1397028Y1001878D01*
G01X1397026Y1001889D02*
X1397027Y1001885D01*
G01X1397025Y1001890D02*
X1397026Y1001889D01*
G01X1397027Y1005034D02*
X1397028Y1005028D01*
G01X1397026Y1005038D02*
X1397027Y1005034D01*
G01X1397025Y1005039D02*
X1397026Y1005038D01*
G01X1397027Y1008184D02*
X1397028Y1008178D01*
G01X1397026Y1008188D02*
X1397027Y1008184D01*
G01X1397025Y1008189D02*
X1397026Y1008188D01*
G01X1411398Y957487D02*
Y957494D01*
G01X1411399Y957482D02*
X1411398Y957487D01*
G01X1411400Y957480D02*
X1411399Y957482D01*
G01X1411398Y962487D02*
Y962494D01*
G01X1411399Y962482D02*
X1411398Y962487D01*
G01X1411400Y962480D02*
X1411399Y962482D01*
G01X1411398Y967487D02*
Y967494D01*
G01X1411399Y967482D02*
X1411398Y967487D01*
G01X1411400Y967480D02*
X1411399Y967482D01*
G01X1411398Y972487D02*
Y972494D01*
G01X1411399Y972482D02*
X1411398Y972487D01*
G01X1411400Y972480D02*
X1411399Y972482D01*
G01X1411398Y977487D02*
Y977494D01*
G01X1411399Y977482D02*
X1411398Y977487D01*
G01X1411400Y977480D02*
X1411399Y977482D01*
G01X1411398Y982487D02*
Y982494D01*
G01X1411399Y982482D02*
X1411398Y982487D01*
G01X1411400Y982480D02*
X1411399Y982482D01*
G01X1411398Y987487D02*
Y987494D01*
G01X1411399Y987482D02*
X1411398Y987487D01*
G01X1411400Y987480D02*
X1411399Y987482D01*
G01X1411398Y1012487D02*
Y1012494D01*
G01X1411399Y1012482D02*
X1411398Y1012487D01*
G01X1411400Y1012480D02*
X1411399Y1012482D01*
G01X1397011Y992443D02*
X1397025Y992441D01*
G01X1397000Y992450D02*
X1397011Y992443D01*
G01X1396987Y992469D02*
X1397000Y992450D01*
G01X1397011Y1001892D02*
X1397025Y1001890D01*
G01X1396999Y1001900D02*
X1397011Y1001892D01*
G01X1396987Y1001918D02*
X1396999Y1001900D01*
G01X1397011Y995593D02*
X1397025Y995591D01*
G01X1396998Y995601D02*
X1397011Y995593D01*
G01X1396987Y995621D02*
X1396998Y995601D01*
G01X1397011Y1005042D02*
X1397025Y1005039D01*
G01X1396998Y1005050D02*
X1397011Y1005042D01*
G01X1396987Y1005070D02*
X1396998Y1005050D01*
G01X1397972Y989325D02*
Y989317D01*
G01Y989329D02*
Y989325D01*
G01X1397971Y989331D02*
X1397972Y989329D01*
G01Y992474D02*
Y992467D01*
G01Y992479D02*
Y992474D01*
G01X1397971Y992480D02*
X1397972Y992479D01*
G01Y995624D02*
Y995616D01*
G01Y995628D02*
Y995624D01*
G01X1397971Y995630D02*
X1397972Y995628D01*
G01Y998774D02*
Y998766D01*
G01Y998778D02*
Y998774D01*
G01X1397971Y998780D02*
X1397972Y998778D01*
G01Y1001923D02*
Y1001915D01*
G01Y1001928D02*
Y1001923D01*
G01X1397971Y1001929D02*
X1397972Y1001928D01*
G01Y1005073D02*
Y1005065D01*
G01Y1005077D02*
Y1005073D01*
G01X1397971Y1005079D02*
X1397972Y1005077D01*
G01Y1008222D02*
Y1008215D01*
G01Y1008227D02*
Y1008222D01*
G01X1397971Y1008228D02*
X1397972Y1008227D01*
G01X1397011Y1008192D02*
X1397025Y1008189D01*
G01X1396998Y1008200D02*
X1397011Y1008192D01*
G01X1396987Y1008220D02*
X1396998Y1008200D01*
G01X1397010Y989294D02*
X1397025Y989291D01*
G01X1396997Y989303D02*
X1397010Y989294D01*
G01X1396987Y989323D02*
X1396997Y989303D01*
G01X1397972Y990453D02*
Y990446D01*
G01X1397970Y990459D02*
X1397972Y990453D01*
G01X1397967Y990465D02*
X1397970Y990459D01*
G01X1397972Y993603D02*
Y993596D01*
G01X1397970Y993609D02*
X1397972Y993603D01*
G01X1397967Y993615D02*
X1397970Y993609D01*
G01X1397972Y996752D02*
Y996746D01*
G01X1397970Y996759D02*
X1397972Y996752D01*
G01X1397967Y996765D02*
X1397970Y996759D01*
G01X1397972Y999902D02*
Y999895D01*
G01X1397970Y999908D02*
X1397972Y999902D01*
G01X1397967Y999914D02*
X1397970Y999908D01*
G01X1397972Y1003052D02*
Y1003045D01*
G01X1397970Y1003058D02*
X1397972Y1003052D01*
G01X1397967Y1003064D02*
X1397970Y1003058D01*
G01X1397972Y1006201D02*
Y1006194D01*
G01X1397970Y1006207D02*
X1397972Y1006201D01*
G01X1397967Y1006213D02*
X1397970Y1006207D01*
G01X1397972Y1009351D02*
Y1009344D01*
G01X1397970Y1009357D02*
X1397972Y1009351D01*
G01X1397967Y1009363D02*
X1397970Y1009357D01*
G01X1397933Y989286D02*
X1397934Y989280D01*
G01X1397932Y989290D02*
X1397933Y989286D01*
G01X1397931Y989291D02*
X1397932Y989290D01*
G01X1397933Y992436D02*
X1397934Y992430D01*
G01X1397932Y992439D02*
X1397933Y992436D01*
G01X1397931Y992441D02*
X1397932Y992439D01*
G01X1397933Y995585D02*
X1397934Y995579D01*
G01X1397932Y995589D02*
X1397933Y995585D01*
G01X1397931Y995591D02*
X1397932Y995589D01*
G01X1397933Y998735D02*
X1397934Y998729D01*
G01X1397932Y998739D02*
X1397933Y998735D01*
G01X1397931Y998740D02*
X1397932Y998739D01*
G01X1397933Y1001885D02*
X1397934Y1001878D01*
G01X1397932Y1001888D02*
X1397933Y1001885D01*
G01X1397931Y1001890D02*
X1397932Y1001888D01*
G01X1397933Y1008184D02*
X1397934Y1008178D01*
G01X1397932Y1008187D02*
X1397933Y1008184D01*
G01X1397931Y1008189D02*
X1397932Y1008187D01*
G01X1410413Y957527D02*
Y957536D01*
G01X1410414Y957521D02*
X1410413Y957527D01*
G01X1410415Y957520D02*
X1410414Y957521D01*
G01X1410413Y962527D02*
Y962536D01*
G01X1410414Y962521D02*
X1410413Y962527D01*
G01X1410415Y962520D02*
X1410414Y962521D01*
G01X1410413Y967527D02*
Y967536D01*
G01X1410414Y967521D02*
X1410413Y967527D01*
G01X1410415Y967520D02*
X1410414Y967521D01*
G01X1410413Y972527D02*
Y972536D01*
G01X1410414Y972521D02*
X1410413Y972527D01*
G01X1410415Y972520D02*
X1410414Y972521D01*
G01X1410413Y977527D02*
Y977536D01*
G01X1410414Y977521D02*
X1410413Y977527D01*
G01X1410415Y977520D02*
X1410414Y977521D01*
G01X1410413Y982527D02*
Y982536D01*
G01X1410414Y982521D02*
X1410413Y982527D01*
G01X1410415Y982520D02*
X1410414Y982521D01*
G01X1410413Y987527D02*
Y987536D01*
G01X1410414Y987521D02*
X1410413Y987527D01*
G01X1410415Y987520D02*
X1410414Y987521D01*
G01X1411390Y957663D02*
X1411398Y957637D01*
G01X1411380Y957690D02*
X1411390Y957663D01*
G01X1411369Y957717D02*
X1411380Y957690D01*
G01X1411390Y962663D02*
X1411398Y962637D01*
G01X1411380Y962690D02*
X1411390Y962663D01*
G01X1411369Y962717D02*
X1411380Y962690D01*
G01X1411390Y967663D02*
X1411398Y967637D01*
G01X1411380Y967690D02*
X1411390Y967663D01*
G01X1411369Y967717D02*
X1411380Y967690D01*
G01X1411390Y972663D02*
X1411398Y972637D01*
G01X1411380Y972690D02*
X1411390Y972663D01*
G01X1411369Y972717D02*
X1411380Y972690D01*
G01X1411390Y977663D02*
X1411398Y977637D01*
G01X1411380Y977690D02*
X1411390Y977663D01*
G01X1411369Y977717D02*
X1411380Y977690D01*
G01X1411390Y982663D02*
X1411398Y982637D01*
G01X1411380Y982690D02*
X1411390Y982663D01*
G01X1411369Y982717D02*
X1411380Y982690D01*
G01X1411390Y987663D02*
X1411398Y987637D01*
G01X1411380Y987690D02*
X1411390Y987663D01*
G01X1411369Y987717D02*
X1411380Y987690D01*
G01X1397006Y998745D02*
X1397025Y998740D01*
G01X1396993Y998757D02*
X1397006Y998745D01*
G01X1396986Y998775D02*
X1396993Y998757D01*
G01X1411380Y957515D02*
X1411361Y957520D01*
G01X1411395Y957500D02*
X1411380Y957515D01*
G01X1411400Y957480D02*
X1411395Y957500D01*
G01X1411380Y962515D02*
X1411361Y962520D01*
G01X1411395Y962500D02*
X1411380Y962515D01*
G01X1411400Y962480D02*
X1411395Y962500D01*
G01X1411380Y967515D02*
X1411361Y967520D01*
G01X1411395Y967500D02*
X1411380Y967515D01*
G01X1411400Y967480D02*
X1411395Y967500D01*
G01X1411380Y972515D02*
X1411361Y972520D01*
G01X1411395Y972500D02*
X1411380Y972515D01*
G01X1411400Y972480D02*
X1411395Y972500D01*
G01X1411380Y977515D02*
X1411361Y977520D01*
G01X1411395Y977500D02*
X1411380Y977515D01*
G01X1411400Y977480D02*
X1411395Y977500D01*
G01X1411380Y982515D02*
X1411361Y982520D01*
G01X1411395Y982500D02*
X1411380Y982515D01*
G01X1411400Y982480D02*
X1411395Y982500D01*
G01X1411380Y987515D02*
X1411361Y987520D01*
G01X1411395Y987500D02*
X1411380Y987515D01*
G01X1411400Y987480D02*
X1411395Y987500D01*
G01X1411380Y1012515D02*
X1411361Y1012520D01*
G01X1411395Y1012500D02*
X1411380Y1012515D01*
G01X1411400Y1012480D02*
X1411395Y1012500D01*
G01X1411380Y1017515D02*
X1411361Y1017520D01*
G01X1411395Y1017500D02*
X1411380Y1017515D01*
G01X1411400Y1017480D02*
X1411395Y1017500D01*
G01X1411380Y1022515D02*
X1411361Y1022520D01*
G01X1411395Y1022500D02*
X1411380Y1022515D01*
G01X1411400Y1022480D02*
X1411395Y1022500D01*
G01X1411380Y1027515D02*
X1411361Y1027520D01*
G01X1411395Y1027500D02*
X1411380Y1027515D01*
G01X1411400Y1027480D02*
X1411395Y1027500D01*
G01X1411380Y1032515D02*
X1411361Y1032520D01*
G01X1411395Y1032500D02*
X1411380Y1032515D01*
G01X1411400Y1032480D02*
X1411395Y1032500D01*
G01X1411380Y1037515D02*
X1411361Y1037520D01*
G01X1411395Y1037500D02*
X1411380Y1037515D01*
G01X1411400Y1037480D02*
X1411395Y1037500D01*
G01X1411380Y1042515D02*
X1411361Y1042520D01*
G01X1411395Y1042500D02*
X1411380Y1042515D01*
G01X1411400Y1042480D02*
X1411395Y1042500D01*
G01X1411380Y1047515D02*
X1411361Y1047520D01*
G01X1411395Y1047500D02*
X1411380Y1047515D01*
G01X1411400Y1047480D02*
X1411395Y1047500D01*
G01X1397965Y996754D02*
X1397957Y996762D01*
G01X1397970Y996743D02*
X1397965Y996754D01*
G01X1397971Y996732D02*
X1397970Y996743D01*
G01X1397965Y990454D02*
X1397957Y990463D01*
G01X1397970Y990444D02*
X1397965Y990454D01*
G01X1397971Y990433D02*
X1397970Y990444D01*
G01X1397965Y993604D02*
X1397957Y993612D01*
G01X1397970Y993594D02*
X1397965Y993604D01*
G01X1397971Y993583D02*
X1397970Y993594D01*
G01X1397965Y999903D02*
X1397957Y999911D01*
G01X1397970Y999893D02*
X1397965Y999903D01*
G01X1397971Y999882D02*
X1397970Y999893D01*
G01X1397965Y1003053D02*
X1397957Y1003061D01*
G01X1397970Y1003043D02*
X1397965Y1003053D01*
G01X1397971Y1003031D02*
X1397970Y1003043D01*
G01X1397965Y1006202D02*
X1397957Y1006211D01*
G01X1397970Y1006192D02*
X1397965Y1006202D01*
G01X1397971Y1006181D02*
X1397970Y1006192D01*
G01X1397965Y1009352D02*
X1397957Y1009360D01*
G01X1397970Y1009342D02*
X1397965Y1009352D01*
G01X1397971Y1009331D02*
X1397970Y1009342D01*
G01X1411398Y1017487D02*
Y1017494D01*
G01X1411399Y1017482D02*
X1411398Y1017487D01*
G01X1411400Y1017480D02*
X1411399Y1017482D01*
G01X1411398Y1022487D02*
Y1022494D01*
G01X1411399Y1022482D02*
X1411398Y1022487D01*
G01X1411400Y1022480D02*
X1411399Y1022482D01*
G01X1411398Y1027487D02*
Y1027494D01*
G01X1411399Y1027482D02*
X1411398Y1027487D01*
G01X1411400Y1027480D02*
X1411399Y1027482D01*
G01X1411398Y1032487D02*
Y1032494D01*
G01X1411399Y1032482D02*
X1411398Y1032487D01*
G01X1411400Y1032480D02*
X1411399Y1032482D01*
G01X1411398Y1037487D02*
Y1037494D01*
G01X1411399Y1037482D02*
X1411398Y1037487D01*
G01X1411400Y1037480D02*
X1411399Y1037482D01*
G01X1411398Y1042487D02*
Y1042494D01*
G01X1411399Y1042482D02*
X1411398Y1042487D01*
G01X1411400Y1042480D02*
X1411399Y1042482D01*
G01Y1047482D02*
X1411398Y1047487D01*
G01X1411400Y1047480D02*
X1411399Y1047482D01*
G01X1410413Y1012527D02*
Y1012536D01*
G01X1410414Y1012521D02*
X1410413Y1012527D01*
G01X1410415Y1012520D02*
X1410414Y1012521D01*
G01X1410413Y1017527D02*
Y1017536D01*
G01X1410414Y1017521D02*
X1410413Y1017527D01*
G01X1410415Y1017520D02*
X1410414Y1017521D01*
G01X1410413Y1022527D02*
Y1022536D01*
G01X1410414Y1022521D02*
X1410413Y1022527D01*
G01X1410415Y1022520D02*
X1410414Y1022521D01*
G01X1410413Y1027527D02*
Y1027536D01*
G01X1410414Y1027521D02*
X1410413Y1027527D01*
G01X1410415Y1027520D02*
X1410414Y1027521D01*
G01X1410413Y1032527D02*
Y1032536D01*
G01X1410414Y1032521D02*
X1410413Y1032527D01*
G01X1410415Y1032520D02*
X1410414Y1032521D01*
G01X1410413Y1037527D02*
Y1037536D01*
G01X1410414Y1037521D02*
X1410413Y1037527D01*
G01X1410415Y1037520D02*
X1410414Y1037521D01*
G01X1410413Y1042527D02*
Y1042536D01*
G01X1410414Y1042521D02*
X1410413Y1042527D01*
G01X1410415Y1042520D02*
X1410414Y1042521D01*
G01X1410415Y1047520D02*
X1410414Y1047521D01*
G01X1411390Y1012663D02*
X1411398Y1012637D01*
G01X1411380Y1012690D02*
X1411390Y1012663D01*
G01X1411369Y1012717D02*
X1411380Y1012690D01*
G01X1411390Y1017663D02*
X1411398Y1017637D01*
G01X1411380Y1017690D02*
X1411390Y1017663D01*
G01X1411369Y1017717D02*
X1411380Y1017690D01*
G01X1411390Y1022663D02*
X1411398Y1022637D01*
G01X1411380Y1022690D02*
X1411390Y1022663D01*
G01X1411369Y1022717D02*
X1411380Y1022690D01*
G01X1411390Y1027663D02*
X1411398Y1027637D01*
G01X1411380Y1027690D02*
X1411390Y1027663D01*
G01X1411369Y1027717D02*
X1411380Y1027690D01*
G01X1411390Y1032663D02*
X1411398Y1032637D01*
G01X1411380Y1032690D02*
X1411390Y1032663D01*
G01X1411369Y1032717D02*
X1411380Y1032690D01*
G01X1411390Y1037663D02*
X1411398Y1037637D01*
G01X1411380Y1037690D02*
X1411390Y1037663D01*
G01X1411369Y1037717D02*
X1411380Y1037690D01*
G01X1411390Y1042663D02*
X1411398Y1042637D01*
G01X1411380Y1042690D02*
X1411390Y1042663D01*
G01X1411369Y1042717D02*
X1411380Y1042690D01*
G01X1397931Y1005039D02*
X1397935Y1005028D01*
G01X1410827Y989469D02*
X1412008Y988287D01*
G01X1406890Y989469D02*
X1408071Y988287D01*
G01X1397972Y990435D02*
Y990446D01*
G01Y993585D02*
Y993596D01*
G01Y996734D02*
Y996746D01*
G01Y999884D02*
Y999895D01*
G01Y1003033D02*
Y1003045D01*
G01Y1006183D02*
Y1006194D01*
G01Y1009333D02*
Y1009344D01*
G01X1411398Y957494D02*
Y957502D01*
G01Y962494D02*
Y962502D01*
G01Y967494D02*
Y967502D01*
G01Y972494D02*
Y972502D01*
G01Y977494D02*
Y977502D01*
G01Y982494D02*
Y982502D01*
G01Y987494D02*
Y987502D01*
G01Y1012494D02*
Y1012502D01*
G01Y1017494D02*
Y1017502D01*
G01Y1022494D02*
Y1022502D01*
G01Y1027494D02*
Y1027502D01*
G01Y1032494D02*
Y1032502D01*
G01Y1037494D02*
Y1037502D01*
G01Y1042494D02*
Y1042502D01*
G01X1415748Y1046142D02*
Y1047520D01*
G01Y1041142D02*
Y1042520D01*
G01Y1036142D02*
Y1037520D01*
G01Y1031142D02*
Y1032520D01*
G01Y1026142D02*
Y1027520D01*
G01Y1021142D02*
Y1022520D01*
G01Y1016142D02*
Y1017520D01*
G01Y1011142D02*
Y1012520D01*
G01Y986142D02*
Y987520D01*
G01Y981142D02*
Y982520D01*
G01Y976142D02*
Y977520D01*
G01Y971142D02*
Y972520D01*
G01Y966142D02*
Y967520D01*
G01Y961142D02*
Y962520D01*
G01Y956142D02*
Y957520D01*
G01X1412579D02*
Y956142D01*
G01Y962520D02*
Y961142D01*
G01Y967520D02*
Y966142D01*
G01Y972520D02*
Y971142D01*
G01Y977520D02*
Y976142D01*
G01Y982520D02*
Y981142D01*
G01Y987520D02*
Y986142D01*
G01Y1012520D02*
Y1011142D01*
G01Y1017520D02*
Y1016142D01*
G01Y1022520D02*
Y1021142D01*
G01Y1027520D02*
Y1026142D01*
G01Y1032520D02*
Y1031142D01*
G01Y1037520D02*
Y1036142D01*
G01Y1042520D02*
Y1041142D01*
G01Y1047520D02*
Y1046142D01*
G01X1412008Y1010374D02*
Y988287D01*
G01X1411398Y1045650D02*
Y1048012D01*
G01Y1040650D02*
Y1043012D01*
G01Y1035650D02*
Y1038012D01*
G01Y1030650D02*
Y1033012D01*
G01Y1025650D02*
Y1028012D01*
G01Y1020650D02*
Y1023012D01*
G01Y1015650D02*
Y1018012D01*
G01Y1010650D02*
Y1013012D01*
G01Y985650D02*
Y988012D01*
G01Y980650D02*
Y983012D01*
G01Y975650D02*
Y978012D01*
G01Y970650D02*
Y973012D01*
G01Y965650D02*
Y968012D01*
G01Y960650D02*
Y963012D01*
G01Y955650D02*
Y958012D01*
G01Y962494D02*
Y962637D01*
G01Y967494D02*
Y967637D01*
G01Y972494D02*
Y972637D01*
G01Y977494D02*
Y977637D01*
G01Y982494D02*
Y982637D01*
G01Y987494D02*
Y987637D01*
G01Y1012494D02*
Y1012637D01*
G01Y1017494D02*
Y1017637D01*
G01Y1022494D02*
Y1022637D01*
G01Y1027494D02*
Y1027637D01*
G01Y1032494D02*
Y1032637D01*
G01Y1037494D02*
Y1037637D01*
G01Y1042494D02*
Y1042637D01*
G01X1410827Y1009193D02*
Y989469D01*
G01X1410413Y958012D02*
Y955650D01*
G01Y963012D02*
Y960650D01*
G01Y968012D02*
Y965650D01*
G01Y973012D02*
Y970650D01*
G01Y978012D02*
Y975650D01*
G01Y983012D02*
Y980650D01*
G01Y988012D02*
Y985650D01*
G01Y1013012D02*
Y1010650D01*
G01Y1018012D02*
Y1015650D01*
G01Y1023012D02*
Y1020650D01*
G01Y1028012D02*
Y1025650D01*
G01Y1033012D02*
Y1030650D01*
G01Y1038012D02*
Y1035650D01*
G01Y1043012D02*
Y1040650D01*
G01Y1048012D02*
Y1045650D01*
G01X1408071Y1086831D02*
Y1010374D01*
G01X1406890Y989469D02*
Y953012D01*
G01Y1085650D02*
Y1009193D01*
G01X1401378Y953012D02*
Y1085650D01*
G01X1398425Y1090571D02*
Y1011535D01*
G01X1397972Y1008031D02*
Y1009528D01*
G01Y1004881D02*
Y1006378D01*
G01Y1001732D02*
Y1003228D01*
G01Y998582D02*
Y1000079D01*
G01Y995433D02*
Y996929D01*
G01Y992283D02*
Y993780D01*
G01Y989133D02*
Y990630D01*
G01X1397933Y989280D02*
Y989133D01*
G01Y990630D02*
Y990483D01*
G01Y995579D02*
Y995432D01*
G01Y992430D02*
Y992283D01*
G01Y993780D02*
Y993633D01*
G01Y998729D02*
Y998582D01*
G01Y1000079D02*
Y999932D01*
G01Y996930D02*
Y996783D01*
G01Y1001878D02*
Y1001731D01*
G01Y1003229D02*
Y1003082D01*
G01Y1008178D02*
Y1008031D01*
G01Y1009528D02*
Y1009381D01*
G01Y1005028D02*
Y1004881D01*
G01Y1006378D02*
Y1006231D01*
G01X1397028Y1008031D02*
Y1008178D01*
G01Y1009381D02*
Y1009528D01*
G01Y1004881D02*
Y1005028D01*
G01Y1006231D02*
Y1006378D01*
G01Y1001731D02*
Y1001878D01*
G01Y1003082D02*
Y1003229D01*
G01Y998582D02*
Y998729D01*
G01Y999932D02*
Y1000079D01*
G01Y996783D02*
Y996930D01*
G01Y995432D02*
Y995579D01*
G01Y992283D02*
Y992430D01*
G01Y993633D02*
Y993780D01*
G01Y989133D02*
Y989280D01*
G01Y990483D02*
Y990630D01*
G01X1396988D02*
Y989134D01*
G01Y993780D02*
Y992283D01*
G01Y1000079D02*
Y998583D01*
G01Y996929D02*
Y995433D01*
G01Y1003228D02*
Y1001732D01*
G01Y1009528D02*
Y1008031D01*
G01Y1006378D02*
Y1004882D01*
G01X1395807Y990472D02*
Y989291D01*
G01Y996772D02*
Y995591D01*
G01Y993622D02*
Y992441D01*
G01Y999921D02*
Y998740D01*
G01Y1003071D02*
Y1001890D01*
G01Y1009370D02*
Y1008189D01*
G01Y1006220D02*
Y1005039D01*
G01X1395472Y1011535D02*
Y987126D01*
G01X1395079D02*
Y1011535D01*
G01X1392047Y1008189D02*
Y1009370D01*
G01Y1005039D02*
Y1006220D01*
G01Y1001890D02*
Y1003071D01*
G01Y998740D02*
Y999921D01*
G01Y995591D02*
Y996772D01*
G01Y992441D02*
Y993622D01*
G01Y989291D02*
Y990472D01*
G01X1397972Y1008215D02*
Y1008226D01*
G01Y1005065D02*
Y1005076D01*
G01Y1001916D02*
Y1001926D01*
G01Y998766D02*
Y998777D01*
G01Y995617D02*
Y995627D01*
G01Y992467D02*
Y992478D01*
G01Y989317D02*
Y989328D01*
G01X1396875Y1008228D02*
X1396987Y1008220D01*
G01X1415748Y1046142D02*
X1410415D01*
G01X1410413Y1045650D02*
X1411398D01*
G01Y1043012D02*
X1410413D01*
G01X1410415Y1042520D02*
X1415748D01*
G01Y1042480D02*
X1411400D01*
G01X1415748Y1041142D02*
X1410415D01*
G01X1410413Y1040650D02*
X1411398D01*
G01Y1038012D02*
X1410413D01*
G01X1410415Y1037520D02*
X1415748D01*
G01Y1037480D02*
X1411400D01*
G01X1415748Y1036142D02*
X1410415D01*
G01X1410413Y1035650D02*
X1411398D01*
G01Y1033012D02*
X1410413D01*
G01X1410415Y1032520D02*
X1415748D01*
G01Y1032480D02*
X1411400D01*
G01X1415748Y1031142D02*
X1410415D01*
G01X1410413Y1030650D02*
X1411398D01*
G01Y1028012D02*
X1410413D01*
G01X1410415Y1027520D02*
X1415748D01*
G01Y1027480D02*
X1411400D01*
G01X1415748Y1026142D02*
X1410415D01*
G01X1410413Y1025650D02*
X1411398D01*
G01Y1023012D02*
X1410413D01*
G01X1410415Y1022520D02*
X1415748D01*
G01Y1022480D02*
X1411400D01*
G01X1415748Y1021142D02*
X1410415D01*
G01X1411398Y1045946D02*
X1410413Y1045945D01*
G01Y1042715D02*
X1411369Y1042717D01*
G01X1411398Y1040946D02*
X1410413Y1040945D01*
G01Y1037715D02*
X1411369Y1037717D01*
G01X1411398Y1035946D02*
X1410413Y1035945D01*
G01Y1032715D02*
X1411369Y1032717D01*
G01X1411398Y1030946D02*
X1410413Y1030945D01*
G01Y1027715D02*
X1411369Y1027717D01*
G01X1411398Y1025946D02*
X1410413Y1025945D01*
G01Y1022715D02*
X1411369Y1022717D01*
G01X1396986Y998775D02*
X1396875Y998780D01*
G01X1396986Y992477D02*
X1396875Y992480D01*
G01X1396986Y1001926D02*
X1396875Y1001929D01*
G01X1410413Y1020650D02*
X1411398D01*
G01Y1018012D02*
X1410413D01*
G01X1410415Y1017520D02*
X1415748D01*
G01Y1017480D02*
X1411400D01*
G01X1415748Y1016142D02*
X1410415D01*
G01X1410413Y1015650D02*
X1411398D01*
G01Y1013012D02*
X1410413D01*
G01X1410415Y1012520D02*
X1415748D01*
G01Y1012480D02*
X1411400D01*
G01X1398425Y1011535D02*
X1395079D01*
G01X1415748Y1011142D02*
X1410415D01*
G01X1410413Y1010650D02*
X1411398D01*
G01X1408071Y1010374D02*
X1412008D01*
G01X1397933Y1009567D02*
X1397028D01*
G01X1397972Y1009528D02*
X1396988D01*
G01X1397931Y1009370D02*
X1392047D01*
G01Y1009331D02*
X1397971D01*
G01X1406890Y1009193D02*
X1410827D01*
G01X1397971Y1008228D02*
X1392047D01*
G01X1397931Y1008189D02*
X1392047D01*
G01X1396988Y1008031D02*
X1397972D01*
G01X1397028Y1007992D02*
X1397933D01*
G01Y1006417D02*
X1397028D01*
G01X1397972Y1006378D02*
X1396988D01*
G01X1397931Y1006220D02*
X1392047D01*
G01Y1006181D02*
X1397971D01*
G01Y1005079D02*
X1392047D01*
G01X1397931Y1005039D02*
X1392047D01*
G01X1396988Y1004882D02*
X1397972D01*
G01X1397028Y1004843D02*
X1397933D01*
G01Y1003268D02*
X1397028D01*
G01X1397972Y1003228D02*
X1396988D01*
G01X1397931Y1003071D02*
X1392047D01*
G01Y1003031D02*
X1397971D01*
G01X1396241Y1001929D02*
X1395807D01*
G01X1397971D02*
X1392047D01*
G01X1397931Y1001890D02*
X1392047D01*
G01X1396988Y1001732D02*
X1397972D01*
G01X1397028Y1001693D02*
X1397933D01*
G01Y1000118D02*
X1397028D01*
G01X1397972Y1000079D02*
X1396988D01*
G01X1397931Y999921D02*
X1392047D01*
G01Y999882D02*
X1397971D01*
G01X1396241Y998780D02*
X1395807D01*
G01X1397971D02*
X1392047D01*
G01X1397931Y998740D02*
X1392047D01*
G01X1396988Y998583D02*
X1397972D01*
G01X1397028Y998543D02*
X1397933D01*
G01Y996969D02*
X1397028D01*
G01X1397972Y996929D02*
X1396988D01*
G01X1397931Y996772D02*
X1392047D01*
G01Y996732D02*
X1397971D01*
G01Y995630D02*
X1392047D01*
G01X1397931Y995591D02*
X1392047D01*
G01X1396988Y995433D02*
X1397972D01*
G01X1397028Y995394D02*
X1397933D01*
G01Y993819D02*
X1397028D01*
G01X1397972Y993780D02*
X1396988D01*
G01X1397931Y993622D02*
X1392047D01*
G01Y993583D02*
X1397971D01*
G01X1396241Y992480D02*
X1395807D01*
G01X1397971D02*
X1392047D01*
G01X1397931Y992441D02*
X1392047D01*
G01X1396988Y992283D02*
X1397972D01*
G01X1397028Y992244D02*
X1397933D01*
G01Y990669D02*
X1397028D01*
G01X1397972Y990630D02*
X1396988D01*
G01X1397931Y990472D02*
X1392047D01*
G01Y990433D02*
X1397971D01*
G01X1410827Y989469D02*
X1406890D01*
G01X1397971Y989331D02*
X1392047D01*
G01X1397931Y989291D02*
X1392047D01*
G01X1396988Y989134D02*
X1397972D01*
G01X1397028Y989094D02*
X1397933D01*
G01X1412008Y988287D02*
X1408071D01*
G01X1411398Y988012D02*
X1410413D01*
G01X1410415Y987520D02*
X1415748D01*
G01Y987480D02*
X1411400D01*
G01X1398425Y987126D02*
X1395079D01*
G01X1415748Y986142D02*
X1410415D01*
G01X1410413Y985650D02*
X1411398D01*
G01Y983012D02*
X1410413D01*
G01X1410415Y982520D02*
X1415748D01*
G01Y982480D02*
X1411400D01*
G01X1415748Y981142D02*
X1410415D01*
G01X1410413Y980650D02*
X1411398D01*
G01Y978012D02*
X1410413D01*
G01X1410415Y977520D02*
X1415748D01*
G01Y977480D02*
X1411400D01*
G01X1415748Y976142D02*
X1410415D01*
G01X1410413Y975650D02*
X1411398D01*
G01Y973012D02*
X1410413D01*
G01X1410415Y972520D02*
X1415748D01*
G01Y972480D02*
X1411400D01*
G01X1415748Y971142D02*
X1410415D01*
G01X1410413Y970650D02*
X1411398D01*
G01Y968012D02*
X1410413D01*
G01X1410415Y967520D02*
X1415748D01*
G01Y967480D02*
X1411400D01*
G01X1415748Y966142D02*
X1410415D01*
G01X1410413Y965650D02*
X1411398D01*
G01Y963012D02*
X1410413D01*
G01X1410415Y962520D02*
X1415748D01*
G01Y962480D02*
X1411400D01*
G01X1415748Y961142D02*
X1410415D01*
G01X1410413Y960650D02*
X1411398D01*
G01Y958012D02*
X1410413D01*
G01X1410415Y957520D02*
X1415748D01*
G01Y957480D02*
X1411400D01*
G01X1415748Y956142D02*
X1410415D01*
G01X1410413Y955650D02*
X1411398D01*
G01X1406890Y953012D02*
X1401378D01*
G01X1411398Y1020946D02*
X1410413Y1020945D01*
G01Y1017715D02*
X1411369Y1017717D01*
G01X1411398Y1015946D02*
X1410413Y1015945D01*
G01Y1012715D02*
X1411369Y1012717D01*
G01X1411398Y1010946D02*
X1410413Y1010945D01*
G01Y987715D02*
X1411369Y987717D01*
G01X1411398Y985946D02*
X1410413Y985945D01*
G01Y982715D02*
X1411369Y982717D01*
G01X1411398Y980946D02*
X1410413Y980945D01*
G01Y977715D02*
X1411369Y977717D01*
G01X1411398Y975946D02*
X1410413Y975945D01*
G01Y972715D02*
X1411369Y972717D01*
G01X1411398Y970946D02*
X1410413Y970945D01*
G01Y967715D02*
X1411369Y967717D01*
G01X1411398Y965946D02*
X1410413Y965945D01*
G01Y962715D02*
X1411369Y962717D01*
G01X1411398Y960946D02*
X1410413Y960945D01*
G01Y957715D02*
X1411369Y957717D01*
G01X1411398Y955946D02*
X1410413Y955945D01*
G01X1410827Y1009193D02*
X1412008Y1010374D01*
G01X1406890Y1009193D02*
X1408071Y1010374D01*
G01X1411398Y1081134D02*
Y1081125D01*
G01X1411399Y1081140D02*
X1411398Y1081134D01*
G01X1411400Y1081142D02*
X1411399Y1081140D01*
G01X1411398Y1076134D02*
Y1076125D01*
G01X1411399Y1076140D02*
X1411398Y1076134D01*
G01X1411400Y1076142D02*
X1411399Y1076140D01*
G01X1411398Y1071134D02*
Y1071125D01*
G01X1411399Y1071140D02*
X1411398Y1071134D01*
G01X1411400Y1071142D02*
X1411399Y1071140D01*
G01X1411398Y1066134D02*
Y1066125D01*
G01X1411399Y1066140D02*
X1411398Y1066134D01*
G01X1411400Y1066142D02*
X1411399Y1066140D01*
G01X1411398Y1061134D02*
Y1061125D01*
G01X1411399Y1061140D02*
X1411398Y1061134D01*
G01X1411400Y1061142D02*
X1411399Y1061140D01*
G01X1411398Y1056134D02*
Y1056125D01*
G01X1411399Y1056140D02*
X1411398Y1056134D01*
G01X1411400Y1056142D02*
X1411399Y1056140D01*
G01X1411398Y1051134D02*
Y1051125D01*
G01X1411399Y1051140D02*
X1411398Y1051134D01*
G01X1411400Y1051142D02*
X1411399Y1051140D01*
G01X1411385Y1052511D02*
X1411396Y1052496D01*
G01X1411361Y1052520D02*
X1411385Y1052511D01*
G01X1411365Y1047618D02*
X1411369Y1047717D01*
G01X1411359Y1047546D02*
X1411365Y1047618D01*
G01X1411361Y1047520D02*
X1411359Y1047546D01*
G01X1411365Y1052618D02*
X1411369Y1052717D01*
G01X1411359Y1052546D02*
X1411365Y1052618D01*
G01X1411361Y1052520D02*
X1411359Y1052546D01*
G01X1411365Y1057618D02*
X1411369Y1057717D01*
G01X1411359Y1057546D02*
X1411365Y1057618D01*
G01X1411361Y1057520D02*
X1411359Y1057546D01*
G01X1411365Y1062618D02*
X1411369Y1062717D01*
G01X1411359Y1062546D02*
X1411365Y1062618D01*
G01X1411361Y1062520D02*
X1411359Y1062546D01*
G01X1411365Y1067618D02*
X1411369Y1067717D01*
G01X1411359Y1067546D02*
X1411365Y1067618D01*
G01X1411361Y1067520D02*
X1411359Y1067546D01*
G01X1411365Y1072618D02*
X1411369Y1072717D01*
G01X1411359Y1072546D02*
X1411365Y1072618D01*
G01X1411361Y1072520D02*
X1411359Y1072546D01*
G01X1411365Y1077618D02*
X1411369Y1077717D01*
G01X1411359Y1077546D02*
X1411365Y1077618D01*
G01X1411361Y1077520D02*
X1411359Y1077546D01*
G01X1411365Y1082618D02*
X1411369Y1082717D01*
G01X1411359Y1082546D02*
X1411365Y1082618D01*
G01X1411361Y1082520D02*
X1411359Y1082546D01*
G01X1410414Y1081140D02*
X1410415Y1081142D01*
G01X1410413Y1081134D02*
X1410414Y1081140D01*
G01X1410413Y1081126D02*
Y1081134D01*
G01X1410414Y1076140D02*
X1410415Y1076142D01*
G01X1410413Y1076134D02*
X1410414Y1076140D01*
G01X1410413Y1076126D02*
Y1076134D01*
G01X1410414Y1071140D02*
X1410415Y1071142D01*
G01X1410413Y1071134D02*
X1410414Y1071140D01*
G01X1410413Y1071126D02*
Y1071134D01*
G01X1410414Y1066140D02*
X1410415Y1066142D01*
G01X1410413Y1066134D02*
X1410414Y1066140D01*
G01X1410413Y1066126D02*
Y1066134D01*
G01X1410414Y1061140D02*
X1410415Y1061142D01*
G01X1410413Y1061134D02*
X1410414Y1061140D01*
G01X1410413Y1061126D02*
Y1061134D01*
G01X1410414Y1056140D02*
X1410415Y1056142D01*
G01X1410413Y1056134D02*
X1410414Y1056140D01*
G01X1410413Y1056126D02*
Y1056134D01*
G01X1410414Y1051140D02*
X1410415Y1051142D01*
G01X1410413Y1051134D02*
X1410414Y1051140D01*
G01X1410413Y1051126D02*
Y1051134D01*
G01X1411385Y1057511D02*
X1411396Y1057496D01*
G01X1411361Y1057520D02*
X1411385Y1057511D01*
G01Y1062511D02*
X1411396Y1062496D01*
G01X1411361Y1062520D02*
X1411385Y1062511D01*
G01Y1067511D02*
X1411396Y1067496D01*
G01X1411361Y1067520D02*
X1411385Y1067511D01*
G01Y1072511D02*
X1411396Y1072496D01*
G01X1411361Y1072520D02*
X1411385Y1072511D01*
G01Y1077511D02*
X1411396Y1077496D01*
G01X1411361Y1077520D02*
X1411385Y1077511D01*
G01Y1082511D02*
X1411396Y1082496D01*
G01X1411361Y1082520D02*
X1411385Y1082511D01*
G01X1411380Y1052515D02*
X1411361Y1052520D01*
G01X1411395Y1052500D02*
X1411380Y1052515D01*
G01X1411400Y1052480D02*
X1411395Y1052500D01*
G01X1411398Y1047487D02*
Y1047494D01*
G01Y1052487D02*
Y1052494D01*
G01X1411399Y1052482D02*
X1411398Y1052487D01*
G01X1411400Y1052480D02*
X1411399Y1052482D01*
G01X1411398Y1057487D02*
Y1057494D01*
G01X1411399Y1057482D02*
X1411398Y1057487D01*
G01X1411400Y1057480D02*
X1411399Y1057482D01*
G01X1411398Y1062487D02*
Y1062494D01*
G01X1411399Y1062482D02*
X1411398Y1062487D01*
G01X1411400Y1062480D02*
X1411399Y1062482D01*
G01X1411398Y1067487D02*
Y1067494D01*
G01X1411399Y1067482D02*
X1411398Y1067487D01*
G01X1411400Y1067480D02*
X1411399Y1067482D01*
G01X1411398Y1072487D02*
Y1072494D01*
G01X1411399Y1072482D02*
X1411398Y1072487D01*
G01X1411400Y1072480D02*
X1411399Y1072482D01*
G01X1411398Y1077487D02*
Y1077494D01*
G01X1411399Y1077482D02*
X1411398Y1077487D01*
G01X1411400Y1077480D02*
X1411399Y1077482D01*
G01X1411398Y1082487D02*
Y1082494D01*
G01X1411399Y1082482D02*
X1411398Y1082487D01*
G01X1411400Y1082480D02*
X1411399Y1082482D01*
G01X1410413Y1047527D02*
Y1047536D01*
G01X1410414Y1047521D02*
X1410413Y1047527D01*
G01Y1052527D02*
Y1052536D01*
G01X1410414Y1052521D02*
X1410413Y1052527D01*
G01X1410415Y1052520D02*
X1410414Y1052521D01*
G01X1410413Y1057527D02*
Y1057536D01*
G01X1410414Y1057521D02*
X1410413Y1057527D01*
G01X1410415Y1057520D02*
X1410414Y1057521D01*
G01X1410413Y1062527D02*
Y1062536D01*
G01X1410414Y1062521D02*
X1410413Y1062527D01*
G01X1410415Y1062520D02*
X1410414Y1062521D01*
G01X1410413Y1067527D02*
Y1067536D01*
G01X1410414Y1067521D02*
X1410413Y1067527D01*
G01X1410415Y1067520D02*
X1410414Y1067521D01*
G01X1410413Y1072527D02*
Y1072536D01*
G01X1410414Y1072521D02*
X1410413Y1072527D01*
G01X1410415Y1072520D02*
X1410414Y1072521D01*
G01X1410413Y1077527D02*
Y1077536D01*
G01X1410414Y1077521D02*
X1410413Y1077527D01*
G01X1410415Y1077520D02*
X1410414Y1077521D01*
G01X1410413Y1082527D02*
Y1082536D01*
G01X1410414Y1082521D02*
X1410413Y1082527D01*
G01X1410415Y1082520D02*
X1410414Y1082521D01*
G01X1411390Y1047663D02*
X1411398Y1047637D01*
G01X1411380Y1047690D02*
X1411390Y1047663D01*
G01X1411369Y1047717D02*
X1411380Y1047690D01*
G01X1411390Y1052663D02*
X1411398Y1052637D01*
G01X1411380Y1052690D02*
X1411390Y1052663D01*
G01X1411369Y1052717D02*
X1411380Y1052690D01*
G01X1411390Y1057663D02*
X1411398Y1057637D01*
G01X1411380Y1057690D02*
X1411390Y1057663D01*
G01X1411369Y1057717D02*
X1411380Y1057690D01*
G01X1411390Y1062663D02*
X1411398Y1062637D01*
G01X1411380Y1062690D02*
X1411390Y1062663D01*
G01X1411369Y1062717D02*
X1411380Y1062690D01*
G01X1411390Y1067663D02*
X1411398Y1067637D01*
G01X1411380Y1067690D02*
X1411390Y1067663D01*
G01X1411369Y1067717D02*
X1411380Y1067690D01*
G01X1411390Y1072663D02*
X1411398Y1072637D01*
G01X1411380Y1072690D02*
X1411390Y1072663D01*
G01X1411369Y1072717D02*
X1411380Y1072690D01*
G01X1411390Y1077663D02*
X1411398Y1077637D01*
G01X1411380Y1077690D02*
X1411390Y1077663D01*
G01X1411369Y1077717D02*
X1411380Y1077690D01*
G01X1411390Y1082663D02*
X1411398Y1082637D01*
G01X1411380Y1082690D02*
X1411390Y1082663D01*
G01X1411369Y1082717D02*
X1411380Y1082690D01*
G01Y1057515D02*
X1411361Y1057520D01*
G01X1411395Y1057500D02*
X1411380Y1057515D01*
G01X1411400Y1057480D02*
X1411395Y1057500D01*
G01X1411380Y1062515D02*
X1411361Y1062520D01*
G01X1411395Y1062500D02*
X1411380Y1062515D01*
G01X1411400Y1062480D02*
X1411395Y1062500D01*
G01X1411380Y1067515D02*
X1411361Y1067520D01*
G01X1411395Y1067500D02*
X1411380Y1067515D01*
G01X1411400Y1067480D02*
X1411395Y1067500D01*
G01X1411380Y1072515D02*
X1411361Y1072520D01*
G01X1411395Y1072500D02*
X1411380Y1072515D01*
G01X1411400Y1072480D02*
X1411395Y1072500D01*
G01X1411380Y1077515D02*
X1411361Y1077520D01*
G01X1411395Y1077500D02*
X1411380Y1077515D01*
G01X1411400Y1077480D02*
X1411395Y1077500D01*
G01X1411380Y1082515D02*
X1411361Y1082520D01*
G01X1411395Y1082500D02*
X1411380Y1082515D01*
G01X1411400Y1082480D02*
X1411395Y1082500D01*
G01X1409843Y1108012D02*
G03X1409252Y1108602I-591J-1D01*
G01X1402559D02*
G03X1401969Y1108012I0J-590D01*
G01X1404724Y1106831D02*
G03Y1104862I0J-985D01*
G01X1407087D02*
G03Y1106831I0J984D01*
G01X1403346Y1098917D02*
G03X1402165Y1097736I0J-1181D01*
G01X1409646D02*
G03X1408465Y1098917I-1181J0D01*
G01X1407795Y1093642D02*
G03I-1889J0D01*
G01X1416732Y1107421D02*
G03X1414764Y1109390I-1969J0D01*
G01X1397047D02*
G03X1395079Y1107421I1J-1969D01*
G01X1408268Y1093642D02*
G03I-2362J0D01*
G01X1404724Y1094232D02*
X1402414Y1098461D01*
G01X1407087Y1092539D02*
X1408390Y1090571D01*
G01X1400197Y1086831D02*
X1401378Y1085650D01*
G01X1395079Y1091673D02*
X1398425Y1088327D01*
G01X1411398Y1047494D02*
Y1047502D01*
G01Y1052494D02*
Y1052502D01*
G01Y1057494D02*
Y1057502D01*
G01Y1062494D02*
Y1062502D01*
G01Y1067494D02*
Y1067502D01*
G01Y1072494D02*
Y1072502D01*
G01Y1077494D02*
Y1077502D01*
G01Y1082494D02*
Y1082502D01*
G01X1416732Y1091673D02*
Y1107421D01*
G01X1415748Y1081142D02*
Y1082520D01*
G01Y1076142D02*
Y1077520D01*
G01Y1071142D02*
Y1072520D01*
G01Y1066142D02*
Y1067520D01*
G01Y1061142D02*
Y1062520D01*
G01Y1056142D02*
Y1057520D01*
G01Y1051142D02*
Y1052520D01*
G01X1412579D02*
Y1051142D01*
G01Y1057520D02*
Y1056142D01*
G01Y1062520D02*
Y1061142D01*
G01Y1067520D02*
Y1066142D01*
G01Y1072520D02*
Y1071142D01*
G01Y1077520D02*
Y1076142D01*
G01Y1082520D02*
Y1081142D01*
G01X1411398Y1080650D02*
Y1083012D01*
G01Y1075650D02*
Y1078012D01*
G01Y1070650D02*
Y1073012D01*
G01Y1065650D02*
Y1068012D01*
G01Y1060650D02*
Y1063012D01*
G01Y1055650D02*
Y1058012D01*
G01Y1050650D02*
Y1053012D01*
G01Y1047494D02*
Y1047637D01*
G01Y1052494D02*
Y1052637D01*
G01Y1057494D02*
Y1057637D01*
G01Y1062494D02*
Y1062637D01*
G01Y1067494D02*
Y1067637D01*
G01Y1072494D02*
Y1072637D01*
G01Y1077494D02*
Y1077637D01*
G01Y1082494D02*
Y1082637D01*
G01X1410413Y1053012D02*
Y1050650D01*
G01Y1058012D02*
Y1055650D01*
G01Y1063012D02*
Y1060650D01*
G01Y1068012D02*
Y1065650D01*
G01Y1073012D02*
Y1070650D01*
G01Y1078012D02*
Y1075650D01*
G01Y1083012D02*
Y1080650D01*
G01X1409843Y1101909D02*
Y1108012D01*
G01X1409646Y1097736D02*
Y1089193D01*
G01X1407087Y1094232D02*
Y1092539D01*
G01X1404724D02*
Y1094232D01*
G01X1402165Y1089193D02*
Y1097736D01*
G01X1401969Y1101909D02*
Y1108012D01*
G01X1395079Y1107421D02*
Y1091673D01*
G01X1414764Y1109390D02*
X1397047D01*
G01X1409252Y1108602D02*
X1402559D01*
G01X1407087Y1106831D02*
X1404724D01*
G01Y1104862D02*
X1407087D01*
G01X1409843Y1103484D02*
X1401969D01*
G01Y1101909D02*
X1409843D01*
G01X1416732Y1098957D02*
X1395079D01*
G01X1403346Y1098917D02*
X1408465D01*
G01X1404724Y1094232D02*
X1407087D01*
G01X1404724Y1092539D02*
X1407087D01*
G01X1398425Y1090571D02*
X1412795D01*
G01X1398425Y1089193D02*
X1402165D01*
G01X1412795D02*
X1409646D01*
G01X1398425Y1088327D02*
X1413386D01*
G01X1400197Y1086831D02*
X1408071D01*
G01X1401378Y1085650D02*
X1406890D01*
G01X1411398Y1083012D02*
X1410413D01*
G01X1410415Y1082520D02*
X1415748D01*
G01Y1082480D02*
X1411400D01*
G01X1415748Y1081142D02*
X1410415D01*
G01X1410413Y1080650D02*
X1411398D01*
G01Y1078012D02*
X1410413D01*
G01X1410415Y1077520D02*
X1415748D01*
G01Y1077480D02*
X1411400D01*
G01X1415748Y1076142D02*
X1410415D01*
G01X1410413Y1075650D02*
X1411398D01*
G01Y1073012D02*
X1410413D01*
G01X1410415Y1072520D02*
X1415748D01*
G01Y1072480D02*
X1411400D01*
G01X1415748Y1071142D02*
X1410415D01*
G01X1410413Y1070650D02*
X1411398D01*
G01Y1068012D02*
X1410413D01*
G01X1410415Y1067520D02*
X1415748D01*
G01Y1067480D02*
X1411400D01*
G01X1415748Y1066142D02*
X1410415D01*
G01X1410413Y1065650D02*
X1411398D01*
G01Y1063012D02*
X1410413D01*
G01X1410415Y1062520D02*
X1415748D01*
G01Y1062480D02*
X1411400D01*
G01X1415748Y1061142D02*
X1410415D01*
G01X1410413Y1060650D02*
X1411398D01*
G01Y1058012D02*
X1410413D01*
G01X1410415Y1057520D02*
X1415748D01*
G01Y1057480D02*
X1411400D01*
G01X1415748Y1056142D02*
X1410415D01*
G01X1410413Y1055650D02*
X1411398D01*
G01Y1053012D02*
X1410413D01*
G01X1410415Y1052520D02*
X1415748D01*
G01Y1052480D02*
X1411400D01*
G01X1415748Y1051142D02*
X1410415D01*
G01X1410413Y1050650D02*
X1411398D01*
G01Y1048012D02*
X1410413D01*
G01X1410415Y1047520D02*
X1415748D01*
G01Y1047480D02*
X1411400D01*
G01X1410413Y1082715D02*
X1411369Y1082717D01*
G01X1411398Y1080946D02*
X1410413Y1080945D01*
G01Y1077715D02*
X1411369Y1077717D01*
G01X1411398Y1075946D02*
X1410413Y1075945D01*
G01Y1072715D02*
X1411369Y1072717D01*
G01X1411398Y1070946D02*
X1410413Y1070945D01*
G01Y1067715D02*
X1411369Y1067717D01*
G01X1411398Y1065946D02*
X1410413Y1065945D01*
G01Y1062715D02*
X1411369Y1062717D01*
G01X1411398Y1060946D02*
X1410413Y1060945D01*
G01Y1057715D02*
X1411369Y1057717D01*
G01X1411398Y1055946D02*
X1410413Y1055945D01*
G01Y1052715D02*
X1411369Y1052717D01*
G01X1411398Y1050946D02*
X1410413Y1050945D01*
G01Y1047715D02*
X1411369Y1047717D01*
G01X1403421Y1090571D02*
X1404724Y1092539D01*
G01X1409397Y1098461D02*
X1407087Y1094232D01*
G01X1416732Y1091673D02*
X1413386Y1088327D01*
G01X1406890Y1085650D02*
X1408071Y1086831D01*
G01X1431890Y1515748D02*
G03X1427953Y1519685I-3937J0D01*
G01X1431890Y1500000D02*
Y1515748D01*
G01Y1500000D02*
G03X1435827Y1496063I3937J0D01*
G01X1381102Y1497059D02*
G03Y1494280I0J-1389D01*
G01Y1498764D02*
G03Y1492575I0J-3094D01*
G01X1431890Y1500000D02*
G03X1435827Y1496063I3937J0D01*
G01X1431890Y1515748D02*
G03X1427953Y1519685I-3937J0D01*
G01X1379842Y1499606D02*
G03Y1491732I1260J-3937D01*
G01X1376969Y1499606D02*
G03Y1491732I4134J-3937D01*
G01X1368504Y1523622D02*
X1402362D01*
G01Y1521654D02*
X1398819D01*
G01X1381102Y1520210D02*
X1364567D01*
G01X1368504Y1510954D02*
X1391732D01*
G01X1350000D02*
X1360630D01*
G01X1379035Y1505512D02*
X1383169D01*
G01X1362500D02*
X1366634D01*
G01X1345965D02*
X1350098D01*
G01X1360630Y1505210D02*
X1364567D01*
G01X1346063D02*
X1350000D01*
G01X1381102Y1499606D02*
X1376969D01*
G01X1391732Y1492913D02*
X1402362D01*
G01X1376969Y1491732D02*
X1381102D01*
G01X1355118Y1485827D02*
X1340945D01*
G01X1371654D02*
X1357480D01*
G01X1388189D02*
X1374016D01*
G01X1350098Y1469783D02*
X1345965D01*
G01X1366634D02*
X1362500D01*
G01X1383169D02*
X1379035D01*
G01X1350098Y1468996D02*
X1345965D01*
G01X1366634D02*
X1362500D01*
G01X1383169D02*
X1379035D01*
G01X1350098Y1464862D02*
X1345965D01*
G01X1366634D02*
X1362500D01*
G01X1383169D02*
X1379035D01*
G01X1350098Y1448130D02*
X1345965D01*
G01X1366634D02*
X1362500D01*
G01X1383169D02*
X1379035D01*
G01X1350098Y1447343D02*
X1345965D01*
G01X1366634D02*
X1362500D01*
G01X1383169D02*
X1379035D01*
G01X1350098Y1443209D02*
X1345965D01*
G01X1366634D02*
X1362500D01*
G01X1383169D02*
X1379035D01*
G01X1431890Y1515748D02*
Y1500000D01*
G01X1402362Y1492913D02*
Y1526772D01*
G01X1400669Y1519685D02*
Y1521604D01*
G01X1398819Y1526772D02*
Y1521654D01*
G01X1391732Y1510954D02*
Y1471260D01*
G01X1388189Y1516929D02*
Y1485827D01*
G01X1386969Y1523622D02*
Y1471260D01*
G01X1384252Y1485827D02*
Y1512992D01*
G01X1383465Y1523622D02*
Y1471260D01*
G01X1383169Y1443209D02*
Y1471260D01*
G01Y1505512D02*
Y1485827D01*
G01X1381102Y1498764D02*
Y1497059D01*
G01Y1510954D02*
Y1526772D01*
G01Y1491732D02*
Y1499606D01*
G01Y1494279D02*
Y1492574D01*
G01X1379035Y1471260D02*
Y1443209D01*
G01Y1505512D02*
Y1485827D01*
G01X1377953D02*
Y1512992D01*
G01X1374016Y1485827D02*
Y1512992D01*
G01X1371654Y1485827D02*
Y1512992D01*
G01X1368504Y1523622D02*
Y1509843D01*
G01X1367717Y1485827D02*
Y1512992D01*
G01X1366634Y1443209D02*
Y1471260D01*
G01Y1505512D02*
Y1485827D01*
G01X1364567Y1526772D02*
Y1505210D01*
G01X1362500Y1471260D02*
Y1443209D01*
G01Y1505512D02*
Y1485827D01*
G01X1361417D02*
Y1512992D01*
G01X1360630Y1505210D02*
Y1523622D01*
G01X1357480Y1485827D02*
Y1512992D01*
G01X1355118Y1485827D02*
Y1512992D01*
G01X1351181Y1485827D02*
Y1512992D01*
G01X1350098Y1443209D02*
Y1471260D01*
G01Y1505512D02*
Y1485827D01*
G01X1350000Y1523622D02*
Y1505210D01*
G01X1346063D02*
Y1523622D01*
G01X1345965Y1471260D02*
Y1443209D01*
G01Y1505512D02*
Y1485827D01*
G01X1344882D02*
Y1512992D01*
G01X1340945Y1485827D02*
Y1512992D01*
G01X1402362Y1523622D02*
X1391732Y1510954D01*
G01X1398819Y1526772D02*
X1388189Y1516929D01*
G01X1398819Y1521654D02*
X1388189Y1516929D01*
G01X1356944Y1808346D02*
Y1789409D01*
G01X1521204Y84941D02*
X1521198Y84921D01*
G01X1521218Y84955D02*
X1521204Y84941D01*
G01X1521238Y84961D02*
X1521218Y84955D01*
G01X1521204Y88091D02*
X1521198Y88071D01*
G01X1521218Y88105D02*
X1521204Y88091D01*
G01X1521238Y88110D02*
X1521218Y88105D01*
G01X1521204Y91240D02*
X1521198Y91220D01*
G01X1521218Y91254D02*
X1521204Y91240D01*
G01X1521238Y91260D02*
X1521218Y91254D01*
G01X1522178Y83799D02*
X1522183Y83819D01*
G01X1522164Y83785D02*
X1522178Y83799D01*
G01X1522144Y83780D02*
X1522164Y83785D01*
G01X1522178Y86949D02*
X1522183Y86969D01*
G01X1522164Y86934D02*
X1522178Y86949D01*
G01X1522144Y86929D02*
X1522164Y86934D01*
G01X1522178Y90098D02*
X1522183Y90118D01*
G01X1522164Y90084D02*
X1522178Y90098D01*
G01X1522144Y90079D02*
X1522164Y90084D01*
G01X1522178Y93248D02*
X1522183Y93268D01*
G01X1522164Y93233D02*
X1522178Y93248D01*
G01X1522144Y93228D02*
X1522164Y93233D01*
G01X1522163Y83772D02*
X1522166Y83774D01*
G01X1522159Y83770D02*
X1522163Y83772D01*
G01X1522156Y83770D02*
X1522159D01*
G01X1522153Y83769D02*
X1522156Y83770D01*
G01X1522149Y83769D02*
X1522153D01*
G01X1522146Y83768D02*
X1522149Y83769D01*
G01X1521223Y84968D02*
X1521220Y84967D01*
G01X1521226Y84969D02*
X1521223Y84968D01*
G01X1521230Y84970D02*
X1521226Y84969D01*
G01X1521233Y84971D02*
X1521230Y84970D01*
G01X1521237Y84972D02*
X1521233Y84971D01*
G01X1521240Y84972D02*
X1521237D01*
G01X1522163Y86921D02*
X1522166Y86923D01*
G01X1522159Y86920D02*
X1522163Y86921D01*
G01X1522156Y86919D02*
X1522159Y86920D01*
G01X1522153Y86919D02*
X1522156D01*
G01X1522149Y86918D02*
X1522153Y86919D01*
G01X1522146Y86918D02*
X1522149D01*
G01X1521223Y88118D02*
X1521220Y88116D01*
G01X1521226Y88119D02*
X1521223Y88118D01*
G01X1521230Y88120D02*
X1521226Y88119D01*
G01X1521233Y88121D02*
X1521230Y88120D01*
G01X1521237Y88121D02*
X1521233D01*
G01X1521240D02*
X1521237D01*
G01X1522163Y90071D02*
X1522166Y90073D01*
G01X1522159Y90070D02*
X1522163Y90071D01*
G01X1522156Y90069D02*
X1522159Y90070D01*
G01X1522153Y90068D02*
X1522156Y90069D01*
G01X1522149Y90068D02*
X1522153D01*
G01X1522146Y90067D02*
X1522149Y90068D01*
G01X1521223Y91267D02*
X1521220Y91266D01*
G01X1521226Y91269D02*
X1521223Y91267D01*
G01X1521230Y91270D02*
X1521226Y91269D01*
G01X1521233Y91270D02*
X1521230D01*
G01X1521237Y91271D02*
X1521233Y91270D01*
G01X1521240Y91271D02*
X1521237D01*
G01X1522163Y93220D02*
X1522166Y93222D01*
G01X1522159Y93219D02*
X1522163Y93220D01*
G01X1522156Y93219D02*
X1522159D01*
G01X1522153Y93218D02*
X1522156Y93219D01*
G01X1522149Y93217D02*
X1522153Y93218D01*
G01X1522146Y93217D02*
X1522149D01*
G01X1522176Y84959D02*
X1522180Y84954D01*
G01X1522171Y84963D02*
X1522176Y84959D01*
G01X1522165Y84967D02*
X1522171Y84963D01*
G01X1522159Y84970D02*
X1522165Y84967D01*
G01X1522152Y84971D02*
X1522159Y84970D01*
G01X1522146Y84972D02*
X1522152Y84971D01*
G01X1522176Y88109D02*
X1522180Y88103D01*
G01X1522171Y88113D02*
X1522176Y88109D01*
G01X1522165Y88117D02*
X1522171Y88113D01*
G01X1522159Y88119D02*
X1522165Y88117D01*
G01X1522152Y88121D02*
X1522159Y88119D01*
G01X1522146Y88121D02*
X1522152D01*
G01X1522176Y91258D02*
X1522180Y91253D01*
G01X1522171Y91263D02*
X1522176Y91258D01*
G01X1522165Y91266D02*
X1522171Y91263D01*
G01X1522159Y91269D02*
X1522165Y91266D01*
G01X1522152Y91270D02*
X1522159Y91269D01*
G01X1522146Y91271D02*
X1522152Y91270D01*
G01X1521202Y83798D02*
X1521201Y83805D01*
G01X1521204Y83791D02*
X1521202Y83798D01*
G01X1521207Y83785D02*
X1521204Y83791D01*
G01X1521212Y83779D02*
X1521207Y83785D01*
G01X1521219Y83774D02*
X1521212Y83779D01*
G01X1521225Y83771D02*
X1521219Y83774D01*
G01X1521233Y83769D02*
X1521225Y83771D01*
G01X1521240Y83768D02*
X1521233Y83769D01*
G01X1521202Y86948D02*
X1521201Y86955D01*
G01X1521204Y86941D02*
X1521202Y86948D01*
G01X1521207Y86934D02*
X1521204Y86941D01*
G01X1521212Y86929D02*
X1521207Y86934D01*
G01X1521219Y86924D02*
X1521212Y86929D01*
G01X1521225Y86920D02*
X1521219Y86924D01*
G01X1521233Y86919D02*
X1521225Y86920D01*
G01X1521240Y86918D02*
X1521233Y86919D01*
G01X1521202Y90097D02*
X1521201Y90104D01*
G01X1521204Y90090D02*
X1521202Y90097D01*
G01X1521207Y90084D02*
X1521204Y90090D01*
G01X1521212Y90078D02*
X1521207Y90084D01*
G01X1521219Y90074D02*
X1521212Y90078D01*
G01X1521225Y90070D02*
X1521219Y90074D01*
G01X1521233Y90068D02*
X1521225Y90070D01*
G01X1521240Y90067D02*
X1521233Y90068D01*
G01X1521202Y93247D02*
X1521201Y93254D01*
G01X1521204Y93240D02*
X1521202Y93247D01*
G01X1521207Y93233D02*
X1521204Y93240D01*
G01X1521212Y93228D02*
X1521207Y93233D01*
G01X1521219Y93223D02*
X1521212Y93228D01*
G01X1521225Y93220D02*
X1521219Y93223D01*
G01X1521233Y93218D02*
X1521225Y93220D01*
G01X1521240Y93217D02*
X1521233Y93218D01*
G01X1522155Y84959D02*
X1522164Y84955D01*
G01X1522144Y84961D02*
X1522155Y84959D01*
G01Y88109D02*
X1522164Y88105D01*
G01X1522144Y88110D02*
X1522155Y88109D01*
G01Y91258D02*
X1522164Y91254D01*
G01X1522144Y91260D02*
X1522155Y91258D01*
G01X1521201Y86959D02*
Y86955D01*
G01X1521202Y86952D02*
X1521201Y86959D01*
G01X1521214Y86937D02*
X1521202Y86952D01*
G01X1521239Y86929D02*
X1521214Y86937D01*
G01X1521201Y90108D02*
Y90104D01*
G01X1521202Y90102D02*
X1521201Y90108D01*
G01X1521214Y90087D02*
X1521202Y90102D01*
G01X1521238Y90079D02*
X1521214Y90087D01*
G01X1521201Y83809D02*
Y83806D01*
G01X1521202Y83803D02*
X1521201Y83809D01*
G01X1521214Y83788D02*
X1521202Y83803D01*
G01X1521238Y83780D02*
X1521214Y83788D01*
G01X1521201Y93258D02*
Y93254D01*
G01X1521202Y93252D02*
X1521201Y93258D01*
G01X1521213Y93238D02*
X1521202Y93252D01*
G01X1521235Y93228D02*
X1521213Y93238D01*
G01X1522154Y91259D02*
X1522144Y91260D01*
G01X1522162Y91256D02*
X1522154Y91259D01*
G01X1522170Y91250D02*
X1522162Y91256D01*
G01X1522154Y84959D02*
X1522144Y84961D01*
G01X1522163Y84956D02*
X1522154Y84959D01*
G01X1522170Y84951D02*
X1522163Y84956D01*
G01X1522154Y88109D02*
X1522144Y88110D01*
G01X1522163Y88106D02*
X1522154Y88109D01*
G01X1522170Y88100D02*
X1522163Y88106D01*
G01X1521240Y83774D02*
Y83768D01*
G01X1521239Y83778D02*
X1521240Y83774D01*
G01X1521238Y83780D02*
X1521239Y83778D01*
G01X1521240Y86924D02*
Y86918D01*
G01X1521239Y86928D02*
X1521240Y86924D01*
G01X1521238Y86929D02*
X1521239Y86928D01*
G01X1521240Y90074D02*
Y90067D01*
G01X1521239Y90078D02*
X1521240Y90074D01*
G01X1521238Y90079D02*
X1521239Y90078D01*
G01X1521240Y93223D02*
Y93217D01*
G01X1521239Y93227D02*
X1521240Y93223D01*
G01X1521238Y93228D02*
X1521239Y93227D01*
G01X1521224Y86931D02*
X1521238Y86929D01*
G01X1521212Y86939D02*
X1521224Y86931D01*
G01X1521200Y86957D02*
X1521212Y86939D01*
G01X1521223Y90081D02*
X1521238Y90079D01*
G01X1521211Y90089D02*
X1521223Y90081D01*
G01X1521199Y90109D02*
X1521211Y90089D01*
G01X1522185Y83813D02*
Y83805D01*
G01X1522184Y83817D02*
X1522185Y83813D01*
G01X1522183Y83819D02*
X1522184Y83817D01*
G01X1522185Y86963D02*
Y86955D01*
G01X1522184Y86967D02*
X1522185Y86963D01*
G01X1522183Y86969D02*
X1522184Y86967D01*
G01X1522185Y90112D02*
Y90104D01*
G01X1522184Y90117D02*
X1522185Y90112D01*
G01X1522183Y90118D02*
X1522184Y90117D01*
G01X1522185Y93262D02*
Y93254D01*
G01X1522184Y93266D02*
X1522185Y93262D01*
G01X1522183Y93268D02*
X1522184Y93266D01*
G01X1521223Y83782D02*
X1521238Y83780D01*
G01X1521210Y83791D02*
X1521223Y83782D01*
G01X1521199Y83811D02*
X1521210Y83791D01*
G01X1522184Y84941D02*
X1522185Y84935D01*
G01X1522183Y84948D02*
X1522184Y84941D01*
G01X1522180Y84954D02*
X1522183Y84948D01*
G01X1522184Y88091D02*
X1522185Y88084D01*
G01X1522183Y88097D02*
X1522184Y88091D01*
G01X1522180Y88103D02*
X1522183Y88097D01*
G01X1522184Y91241D02*
X1522185Y91234D01*
G01X1522183Y91247D02*
X1522184Y91241D01*
G01X1522180Y91253D02*
X1522183Y91247D01*
G01X1522146Y83774D02*
Y83768D01*
G01X1522145Y83778D02*
X1522146Y83774D01*
G01X1522144Y83780D02*
X1522145Y83778D01*
G01X1522146Y86924D02*
Y86918D01*
G01X1522145Y86928D02*
X1522146Y86924D01*
G01X1522144Y86929D02*
X1522145Y86928D01*
G01X1522146Y90074D02*
Y90067D01*
G01X1522145Y90077D02*
X1522146Y90074D01*
G01X1522144Y90079D02*
X1522145Y90077D01*
G01X1522146Y93223D02*
Y93217D01*
G01X1522145Y93227D02*
X1522146Y93223D01*
G01X1522144Y93228D02*
X1522145Y93227D01*
G01X1521219Y93233D02*
X1521238Y93228D01*
G01X1521205Y93246D02*
X1521219Y93233D01*
G01X1521198Y93263D02*
X1521205Y93246D01*
G01X1522178Y91242D02*
X1522170Y91250D01*
G01X1522182Y91231D02*
X1522178Y91242D01*
G01X1522184Y91220D02*
X1522182Y91231D01*
G01X1522178Y84943D02*
X1522170Y84951D01*
G01X1522182Y84932D02*
X1522178Y84943D01*
G01X1522184Y84921D02*
X1522182Y84932D01*
G01X1522178Y88092D02*
X1522170Y88100D01*
G01X1522182Y88082D02*
X1522178Y88092D01*
G01X1522184Y88071D02*
X1522182Y88082D01*
G01X1521241Y91444D02*
X1521240Y91457D01*
G01X1521238Y91431D02*
X1521241Y91444D01*
G01X1521238Y91417D02*
Y91431D01*
G01X1521241Y88294D02*
X1521240Y88307D01*
G01X1521238Y88281D02*
X1521241Y88294D01*
G01X1521238Y88268D02*
Y88281D01*
G01X1521241Y85145D02*
X1521240Y85157D01*
G01X1521238Y85132D02*
X1521241Y85145D01*
G01X1521238Y85118D02*
Y85132D01*
G01Y93057D02*
X1521237Y93070D01*
G01X1521241Y93044D02*
X1521238Y93057D01*
G01X1521240Y93031D02*
X1521241Y93044D01*
G01X1521238Y89907D02*
X1521237Y89921D01*
G01X1521241Y89894D02*
X1521238Y89907D01*
G01X1521240Y89882D02*
X1521241Y89894D01*
G01X1521238Y86757D02*
X1521237Y86771D01*
G01X1521241Y86745D02*
X1521238Y86757D01*
G01X1521240Y86732D02*
X1521241Y86745D01*
G01X1521238Y83608D02*
X1521237Y83622D01*
G01X1521241Y83595D02*
X1521238Y83608D01*
G01X1521240Y83583D02*
X1521241Y83595D01*
G01X1522148Y91431D02*
X1522149Y91417D01*
G01X1522145Y91444D02*
X1522148Y91431D01*
G01X1522146Y91457D02*
X1522145Y91444D01*
G01X1522148Y88281D02*
X1522149Y88268D01*
G01X1522145Y88294D02*
X1522148Y88281D01*
G01X1522146Y88307D02*
X1522145Y88294D01*
G01X1522148Y85132D02*
X1522149Y85118D01*
G01X1522145Y85145D02*
X1522148Y85132D01*
G01X1522146Y85157D02*
X1522145Y85145D01*
G01X1521200Y90112D02*
X1521201Y90105D01*
G01X1521200Y90117D02*
Y90112D01*
G01X1521199Y90109D02*
X1521200Y90117D01*
G01X1522145Y93044D02*
X1522146Y93031D01*
G01X1522148Y93057D02*
X1522145Y93044D01*
G01X1522149Y93070D02*
X1522148Y93057D01*
G01X1522145Y89894D02*
X1522146Y89882D01*
G01X1522148Y89907D02*
X1522145Y89894D01*
G01X1522149Y89921D02*
X1522148Y89907D01*
G01X1522145Y86745D02*
X1522146Y86732D01*
G01X1522148Y86757D02*
X1522145Y86745D01*
G01X1522149Y86771D02*
X1522148Y86757D01*
G01X1522145Y83595D02*
X1522146Y83583D01*
G01X1522148Y83608D02*
X1522145Y83595D01*
G01X1522149Y83622D02*
X1522148Y83608D01*
G01X1521200Y83813D02*
X1521201Y83806D01*
G01X1521200Y83817D02*
Y83813D01*
G01X1521199Y83811D02*
X1521200Y83817D01*
G01X1521214Y91251D02*
X1521238Y91260D01*
G01X1521203Y91237D02*
X1521214Y91251D01*
G01X1521201Y91230D02*
X1521203Y91237D01*
G01X1521214Y88102D02*
X1521238Y88110D01*
G01X1521203Y88087D02*
X1521214Y88102D01*
G01X1521201Y88080D02*
X1521203Y88087D01*
G01X1521214Y84952D02*
X1521238Y84961D01*
G01X1521203Y84937D02*
X1521214Y84952D01*
G01X1521201Y84931D02*
X1521203Y84937D01*
G01X1522185Y91227D02*
Y91234D01*
G01Y91222D02*
Y91227D01*
G01X1522184Y91220D02*
X1522185Y91222D01*
G01Y88077D02*
Y88084D01*
G01Y88072D02*
Y88077D01*
G01X1522184Y88071D02*
X1522185Y88072D01*
G01Y84928D02*
Y84935D01*
G01Y84923D02*
Y84928D01*
G01X1522184Y84921D02*
X1522185Y84923D01*
G01X1521200Y93262D02*
X1521201Y93254D01*
G01X1521200Y93266D02*
Y93262D01*
G01X1521198Y93263D02*
X1521200Y93266D01*
G01Y86963D02*
X1521201Y86955D01*
G01X1521200Y86967D02*
Y86963D01*
G01X1521198Y86965D02*
X1521200Y86967D01*
G01X1522146Y91265D02*
Y91271D01*
G01X1522145Y91261D02*
X1522146Y91265D01*
G01X1522144Y91260D02*
X1522145Y91261D01*
G01X1522146Y88115D02*
Y88121D01*
G01X1522145Y88111D02*
X1522146Y88115D01*
G01X1522144Y88110D02*
X1522145Y88111D01*
G01X1522146Y84966D02*
Y84972D01*
G01X1522145Y84962D02*
X1522146Y84966D01*
G01X1522144Y84961D02*
X1522145Y84962D01*
G01X1521200Y91226D02*
X1521201Y91234D01*
G01X1521200Y91222D02*
Y91226D01*
G01X1521198Y91220D02*
X1521200Y91222D01*
G01Y88077D02*
X1521201Y88084D01*
G01X1521200Y88072D02*
Y88077D01*
G01X1521198Y88071D02*
X1521200Y88072D01*
G01Y84927D02*
X1521201Y84935D01*
G01X1521200Y84923D02*
Y84927D01*
G01X1521198Y84921D02*
X1521200Y84923D01*
G01X1522183Y93242D02*
X1522185Y93254D01*
G01X1522176Y93230D02*
X1522183Y93242D01*
G01X1522166Y93222D02*
X1522176Y93230D01*
G01X1522183Y90092D02*
X1522185Y90104D01*
G01X1522176Y90081D02*
X1522183Y90092D01*
G01X1522166Y90073D02*
X1522176Y90081D01*
G01X1522183Y86943D02*
X1522185Y86955D01*
G01X1522176Y86931D02*
X1522183Y86943D01*
G01X1522166Y86923D02*
X1522176Y86931D01*
G01X1522183Y83793D02*
X1522185Y83805D01*
G01X1522176Y83781D02*
X1522183Y83793D01*
G01X1522166Y83774D02*
X1522176Y83781D01*
G01X1521239Y91265D02*
Y91271D01*
G01Y91261D02*
Y91265D01*
G01X1521238Y91260D02*
X1521239Y91261D01*
G01Y88115D02*
Y88121D01*
G01Y88111D02*
Y88115D01*
G01X1521238Y88110D02*
X1521239Y88111D01*
G01Y84965D02*
Y84972D01*
G01Y84962D02*
Y84965D01*
G01X1521238Y84961D02*
X1521239Y84962D01*
G01X1521202Y91240D02*
X1521201Y91234D01*
G01X1521203Y91246D02*
X1521202Y91240D01*
G01X1521206Y91252D02*
X1521203Y91246D01*
G01X1521210Y91257D02*
X1521206Y91252D01*
G01X1521215Y91262D02*
X1521210Y91257D01*
G01X1521220Y91266D02*
X1521215Y91262D01*
G01X1521202Y88091D02*
X1521201Y88084D01*
G01X1521203Y88097D02*
X1521202Y88091D01*
G01X1521206Y88103D02*
X1521203Y88097D01*
G01X1521210Y88108D02*
X1521206Y88103D01*
G01X1521215Y88113D02*
X1521210Y88108D01*
G01X1521220Y88116D02*
X1521215Y88113D01*
G01X1521202Y84941D02*
X1521201Y84935D01*
G01X1521203Y84947D02*
X1521202Y84941D01*
G01X1521206Y84953D02*
X1521203Y84947D01*
G01X1521210Y84958D02*
X1521206Y84953D01*
G01X1521215Y84963D02*
X1521210Y84958D01*
G01X1521220Y84967D02*
X1521215Y84963D01*
G01X1522156Y93230D02*
X1522144Y93228D01*
G01X1522167Y93235D02*
X1522156Y93230D01*
G01Y90081D02*
X1522144Y90079D01*
G01X1522167Y90085D02*
X1522156Y90081D01*
G01Y86931D02*
X1522144Y86929D01*
G01X1522167Y86936D02*
X1522156Y86931D01*
G01Y83781D02*
X1522144Y83780D01*
G01X1522167Y83786D02*
X1522156Y83781D01*
G01X1526181Y25138D02*
G03X1526772Y24547I591J0D01*
G01X1528937Y28287D02*
G03Y26319I0J-984D01*
G01X1531220Y39508D02*
G03I-1102J0D01*
G01X1526378Y35413D02*
G03X1527559Y34232I1181J0D01*
G01X1531693Y39508D02*
G03I-1575J0D01*
G01X1519291Y25728D02*
G03X1521260Y23760I1969J1D01*
G01X1525591Y47500D02*
X1524409Y46319D01*
G01X1522638Y44823D02*
X1519291Y41476D01*
G01X1526627Y34688D02*
X1528937Y38917D01*
G01X1522185Y84923D02*
Y84935D01*
G01Y88073D02*
Y88084D01*
G01Y91222D02*
Y91234D01*
G01X1528937Y38917D02*
Y40610D01*
G01X1526378Y35413D02*
Y43957D01*
G01X1526181Y31240D02*
Y25138D01*
G01X1525591Y47500D02*
Y180138D01*
G01X1524409Y46319D02*
Y181319D01*
G01X1522638Y81614D02*
Y42579D01*
G01X1522185Y93070D02*
Y94567D01*
G01Y89921D02*
Y91417D01*
G01Y86771D02*
Y88268D01*
G01Y83622D02*
Y85118D01*
G01X1522146Y86918D02*
Y86771D01*
G01Y83768D02*
Y83621D01*
G01Y85119D02*
Y84972D01*
G01Y90067D02*
Y89920D01*
G01Y91418D02*
Y91271D01*
G01Y88268D02*
Y88121D01*
G01Y93217D02*
Y93070D01*
G01X1521240D02*
Y93217D01*
G01Y89920D02*
Y90067D01*
G01Y91271D02*
Y91418D01*
G01Y88121D02*
Y88268D01*
G01Y86771D02*
Y86918D01*
G01Y83621D02*
Y83768D01*
G01Y84972D02*
Y85119D01*
G01X1521201Y85118D02*
Y83622D01*
G01Y91417D02*
Y89921D01*
G01Y88268D02*
Y86772D01*
G01Y94567D02*
Y93071D01*
G01X1520020Y88110D02*
Y86929D01*
G01Y84961D02*
Y83780D01*
G01Y91260D02*
Y90079D01*
G01Y94409D02*
Y93228D01*
G01X1519685Y106024D02*
Y81614D01*
G01X1519291D02*
Y106024D01*
G01Y41476D02*
Y25728D01*
G01X1516260Y93228D02*
Y94409D01*
G01Y90079D02*
Y91260D01*
G01Y86929D02*
Y88110D01*
G01Y83780D02*
Y84961D01*
G01X1522185Y93254D02*
Y93265D01*
G01Y90105D02*
Y90115D01*
G01Y86955D02*
Y86966D01*
G01Y83806D02*
Y83816D01*
G01X1528937Y40610D02*
X1527633Y42579D01*
G01X1521198Y93263D02*
X1521087Y93268D01*
G01X1521198Y86965D02*
X1521087Y86969D01*
G01X1520454Y93268D02*
X1520020D01*
G01X1522183D02*
X1516260D01*
G01X1522144Y93228D02*
X1516260D01*
G01X1521201Y93071D02*
X1522185D01*
G01X1521240Y93031D02*
X1522146D01*
G01Y91457D02*
X1521240D01*
G01X1522185Y91417D02*
X1521201D01*
G01X1522144Y91260D02*
X1516260D01*
G01Y91220D02*
X1522184D01*
G01X1522183Y90118D02*
X1516260D01*
G01X1522144Y90079D02*
X1516260D01*
G01X1521201Y89921D02*
X1522185D01*
G01X1521240Y89882D02*
X1522146D01*
G01Y88307D02*
X1521240D01*
G01X1522185Y88268D02*
X1521201D01*
G01X1522144Y88110D02*
X1516260D01*
G01Y88071D02*
X1522184D01*
G01X1520454Y86969D02*
X1520020D01*
G01X1522183D02*
X1516260D01*
G01X1522144Y86929D02*
X1516260D01*
G01X1521201Y86772D02*
X1522185D01*
G01X1521240Y86732D02*
X1522146D01*
G01Y85157D02*
X1521240D01*
G01X1522185Y85118D02*
X1521201D01*
G01X1522144Y84961D02*
X1516260D01*
G01Y84921D02*
X1522184D01*
G01X1522183Y83819D02*
X1516260D01*
G01X1522144Y83780D02*
X1516260D01*
G01X1521201Y83622D02*
X1522185D01*
G01X1521240Y83583D02*
X1522146D01*
G01X1522638Y81614D02*
X1519291D01*
G01X1531102Y47500D02*
X1525591D01*
G01X1532283Y46319D02*
X1524409D01*
G01X1537598Y44823D02*
X1522638D01*
G01X1526378Y43957D02*
X1522638D01*
G01Y42579D02*
X1537008D01*
G01X1531299Y40610D02*
X1528937D01*
G01X1531299Y38917D02*
X1528937D01*
G01X1532677Y34232D02*
X1527559D01*
G01X1540945Y34193D02*
X1519291D01*
G01X1534055Y31240D02*
X1526181D01*
G01Y29665D02*
X1534055D01*
G01X1531299Y28287D02*
X1528937D01*
G01Y26319D02*
X1531299D01*
G01X1533465Y24547D02*
X1526772D01*
G01X1538976Y23760D02*
X1521260D01*
G01X1521204Y94390D02*
X1521198Y94370D01*
G01X1521218Y94404D02*
X1521204Y94390D01*
G01X1521238Y94409D02*
X1521218Y94404D01*
G01X1521204Y97539D02*
X1521198Y97520D01*
G01X1521218Y97554D02*
X1521204Y97539D01*
G01X1521238Y97559D02*
X1521218Y97554D01*
G01X1521204Y100689D02*
X1521198Y100669D01*
G01X1521218Y100703D02*
X1521204Y100689D01*
G01X1521238Y100709D02*
X1521218Y100703D01*
G01X1521204Y103839D02*
X1521198Y103819D01*
G01X1521218Y103853D02*
X1521204Y103839D01*
G01X1521238Y103858D02*
X1521218Y103853D01*
G01X1522178Y96398D02*
X1522183Y96417D01*
G01X1522164Y96383D02*
X1522178Y96398D01*
G01X1522144Y96378D02*
X1522164Y96383D01*
G01X1522178Y99547D02*
X1522183Y99567D01*
G01X1522164Y99533D02*
X1522178Y99547D01*
G01X1522144Y99528D02*
X1522164Y99533D01*
G01X1522178Y102697D02*
X1522183Y102717D01*
G01X1522164Y102682D02*
X1522178Y102697D01*
G01X1522144Y102677D02*
X1522164Y102682D01*
G01X1522184Y99546D02*
X1522185Y99553D01*
G01X1522182Y99539D02*
X1522184Y99546D01*
G01X1522178Y99533D02*
X1522182Y99539D01*
G01X1522174Y99527D02*
X1522178Y99533D01*
G01X1522167Y99522D02*
X1522174Y99527D01*
G01X1522161Y99519D02*
X1522167Y99522D01*
G01X1522154Y99517D02*
X1522161Y99519D01*
G01X1522146Y99516D02*
X1522154Y99517D01*
G01X1521223Y94417D02*
X1521220Y94415D01*
G01X1521226Y94418D02*
X1521223Y94417D01*
G01X1521230Y94419D02*
X1521226Y94418D01*
G01X1521233Y94420D02*
X1521230Y94419D01*
G01X1521237Y94420D02*
X1521233D01*
G01X1521240D02*
X1521237D01*
G01X1522163Y96370D02*
X1522166Y96372D01*
G01X1522159Y96369D02*
X1522163Y96370D01*
G01X1522156Y96368D02*
X1522159Y96369D01*
G01X1522153Y96367D02*
X1522156Y96368D01*
G01X1522149Y96367D02*
X1522153D01*
G01X1522146D02*
X1522149D01*
G01X1521223Y97567D02*
X1521220Y97565D01*
G01X1521226Y97568D02*
X1521223Y97567D01*
G01X1521230Y97569D02*
X1521226Y97568D01*
G01X1521233Y97570D02*
X1521230Y97569D01*
G01X1521237Y97570D02*
X1521233D01*
G01X1521240D02*
X1521237D01*
G01X1521223Y100716D02*
X1521220Y100715D01*
G01X1521226Y100717D02*
X1521223Y100716D01*
G01X1521230Y100719D02*
X1521226Y100717D01*
G01X1521233Y100719D02*
X1521230D01*
G01X1521237Y100720D02*
X1521233Y100719D01*
G01X1521240Y100720D02*
X1521237D01*
G01X1522163Y102669D02*
X1522166Y102671D01*
G01X1522159Y102668D02*
X1522163Y102669D01*
G01X1522156Y102667D02*
X1522159Y102668D01*
G01X1522153Y102667D02*
X1522156D01*
G01X1522149Y102666D02*
X1522153Y102667D01*
G01X1522146Y102666D02*
X1522149D01*
G01X1521223Y103866D02*
X1521220Y103864D01*
G01X1521226Y103867D02*
X1521223Y103866D01*
G01X1521230Y103868D02*
X1521226Y103867D01*
G01X1521233Y103869D02*
X1521230Y103868D01*
G01X1521237Y103869D02*
X1521233D01*
G01X1521240D02*
X1521237D01*
G01X1522176Y94408D02*
X1522180Y94402D01*
G01X1522171Y94412D02*
X1522176Y94408D01*
G01X1522165Y94416D02*
X1522171Y94412D01*
G01X1522159Y94419D02*
X1522165Y94416D01*
G01X1522152Y94420D02*
X1522159Y94419D01*
G01X1522146Y94420D02*
X1522152D01*
G01X1522176Y97557D02*
X1522180Y97552D01*
G01X1522171Y97562D02*
X1522176Y97557D01*
G01X1522165Y97565D02*
X1522171Y97562D01*
G01X1522159Y97568D02*
X1522165Y97565D01*
G01X1522152Y97570D02*
X1522159Y97568D01*
G01X1522146Y97570D02*
X1522152D01*
G01X1522176Y100707D02*
X1522180Y100702D01*
G01X1522171Y100711D02*
X1522176Y100707D01*
G01X1522165Y100715D02*
X1522171Y100711D01*
G01X1522159Y100718D02*
X1522165Y100715D01*
G01X1522152Y100719D02*
X1522159Y100718D01*
G01X1522146Y100720D02*
X1522152Y100719D01*
G01X1522176Y103857D02*
X1522180Y103851D01*
G01X1522171Y103861D02*
X1522176Y103857D01*
G01X1522165Y103865D02*
X1522171Y103861D01*
G01X1522159Y103867D02*
X1522165Y103865D01*
G01X1522152Y103869D02*
X1522159Y103867D01*
G01X1522146Y103869D02*
X1522152D01*
G01X1521202Y96396D02*
X1521201Y96404D01*
G01X1521204Y96389D02*
X1521202Y96396D01*
G01X1521207Y96383D02*
X1521204Y96389D01*
G01X1521212Y96378D02*
X1521207Y96383D01*
G01X1521219Y96373D02*
X1521212Y96378D01*
G01X1521225Y96369D02*
X1521219Y96373D01*
G01X1521233Y96367D02*
X1521225Y96369D01*
G01X1521240Y96367D02*
X1521233D01*
G01X1521202Y99546D02*
X1521201Y99553D01*
G01X1521204Y99539D02*
X1521202Y99546D01*
G01X1521207Y99533D02*
X1521204Y99539D01*
G01X1521212Y99527D02*
X1521207Y99533D01*
G01X1521219Y99522D02*
X1521212Y99527D01*
G01X1521225Y99519D02*
X1521219Y99522D01*
G01X1521233Y99517D02*
X1521225Y99519D01*
G01X1521240Y99516D02*
X1521233Y99517D01*
G01X1521202Y102696D02*
X1521201Y102703D01*
G01X1521204Y102689D02*
X1521202Y102696D01*
G01X1521207Y102682D02*
X1521204Y102689D01*
G01X1521212Y102677D02*
X1521207Y102682D01*
G01X1521219Y102672D02*
X1521212Y102677D01*
G01X1521225Y102669D02*
X1521219Y102672D01*
G01X1521233Y102667D02*
X1521225Y102669D01*
G01X1521240Y102666D02*
X1521233Y102667D01*
G01X1522155Y94408D02*
X1522164Y94404D01*
G01X1522144Y94409D02*
X1522155Y94408D01*
G01Y97557D02*
X1522164Y97554D01*
G01X1522144Y97559D02*
X1522155Y97557D01*
G01Y100707D02*
X1522164Y100703D01*
G01X1522144Y100709D02*
X1522155Y100707D01*
G01Y103857D02*
X1522164Y103853D01*
G01X1522144Y103858D02*
X1522155Y103857D01*
G01X1521201Y96407D02*
Y96404D01*
G01X1521202Y96401D02*
X1521201Y96407D01*
G01X1521214Y96386D02*
X1521202Y96401D01*
G01X1521238Y96378D02*
X1521214Y96386D01*
G01X1521201Y99557D02*
Y99553D01*
G01X1521202Y99551D02*
X1521201Y99557D01*
G01X1521214Y99536D02*
X1521202Y99551D01*
G01X1521238Y99528D02*
X1521214Y99536D01*
G01X1521201Y102707D02*
Y102703D01*
G01X1521202Y102701D02*
X1521201Y102707D01*
G01X1521214Y102685D02*
X1521202Y102701D01*
G01X1521238Y102677D02*
X1521214Y102685D01*
G01X1522154Y94408D02*
X1522144Y94409D01*
G01X1522163Y94405D02*
X1522154Y94408D01*
G01X1522170Y94400D02*
X1522163Y94405D01*
G01X1522154Y97558D02*
X1522144Y97559D01*
G01X1522163Y97555D02*
X1522154Y97558D01*
G01X1522170Y97549D02*
X1522163Y97555D01*
G01X1522154Y100707D02*
X1522144Y100709D01*
G01X1522163Y100704D02*
X1522154Y100707D01*
G01X1522170Y100699D02*
X1522163Y100704D01*
G01X1522154Y103857D02*
X1522144Y103858D01*
G01X1522163Y103854D02*
X1522154Y103857D01*
G01X1522170Y103848D02*
X1522163Y103854D01*
G01X1521240Y96373D02*
Y96367D01*
G01X1521239Y96377D02*
X1521240Y96373D01*
G01X1521238Y96378D02*
X1521239Y96377D01*
G01X1521240Y99522D02*
Y99516D01*
G01X1521239Y99526D02*
X1521240Y99522D01*
G01X1521238Y99528D02*
X1521239Y99526D01*
G01X1521240Y102672D02*
Y102666D01*
G01X1521239Y102676D02*
X1521240Y102672D01*
G01X1521238Y102677D02*
X1521239Y102676D01*
G01X1521224Y96380D02*
X1521238Y96378D01*
G01X1521212Y96388D02*
X1521224Y96380D01*
G01X1521200Y96406D02*
X1521212Y96388D01*
G01X1521223Y99530D02*
X1521238Y99528D01*
G01X1521211Y99538D02*
X1521223Y99530D01*
G01X1521199Y99558D02*
X1521211Y99538D01*
G01X1522185Y96411D02*
Y96404D01*
G01X1522184Y96416D02*
X1522185Y96411D01*
G01X1522183Y96417D02*
X1522184Y96416D01*
G01X1522185Y99561D02*
Y99553D01*
G01X1522184Y99565D02*
X1522185Y99561D01*
G01X1522183Y99567D02*
X1522184Y99565D01*
G01X1522185Y102711D02*
Y102703D01*
G01X1522184Y102715D02*
X1522185Y102711D01*
G01X1522183Y102717D02*
X1522184Y102715D01*
G01X1521223Y102680D02*
X1521238Y102677D01*
G01X1521211Y102688D02*
X1521223Y102680D01*
G01X1521199Y102708D02*
X1521211Y102688D01*
G01X1522184Y94390D02*
X1522185Y94383D01*
G01X1522183Y94396D02*
X1522184Y94390D01*
G01X1522180Y94402D02*
X1522183Y94396D01*
G01X1522184Y97540D02*
X1522185Y97533D01*
G01X1522183Y97546D02*
X1522184Y97540D01*
G01X1522180Y97552D02*
X1522183Y97546D01*
G01X1522184Y100689D02*
X1522185Y100683D01*
G01X1522183Y100696D02*
X1522184Y100689D01*
G01X1522180Y100702D02*
X1522183Y100696D01*
G01X1522184Y103839D02*
X1522185Y103832D01*
G01X1522183Y103845D02*
X1522184Y103839D01*
G01X1522180Y103851D02*
X1522183Y103845D01*
G01X1522146Y96373D02*
Y96367D01*
G01X1522145Y96376D02*
X1522146Y96373D01*
G01X1522144Y96378D02*
X1522145Y96376D01*
G01X1522146Y102672D02*
Y102666D01*
G01X1522145Y102676D02*
X1522146Y102672D01*
G01X1522144Y102677D02*
X1522145Y102676D01*
G01X1522178Y94391D02*
X1522170Y94400D01*
G01X1522182Y94381D02*
X1522178Y94391D01*
G01X1522184Y94370D02*
X1522182Y94381D01*
G01X1522178Y97541D02*
X1522170Y97549D01*
G01X1522182Y97531D02*
X1522178Y97541D01*
G01X1522184Y97520D02*
X1522182Y97531D01*
G01X1522178Y100691D02*
X1522170Y100699D01*
G01X1522182Y100680D02*
X1522178Y100691D01*
G01X1522184Y100669D02*
X1522182Y100680D01*
G01X1522178Y103840D02*
X1522170Y103848D01*
G01X1522182Y103830D02*
X1522178Y103840D01*
G01X1522184Y103819D02*
X1522182Y103830D01*
G01X1521200Y96411D02*
X1521201Y96404D01*
G01X1521200Y96416D02*
Y96411D01*
G01Y96406D02*
Y96416D01*
G01X1521241Y104043D02*
X1521240Y104055D01*
G01X1521238Y104030D02*
X1521241Y104043D01*
G01X1521238Y104016D02*
Y104030D01*
G01X1521241Y100893D02*
X1521240Y100906D01*
G01X1521238Y100880D02*
X1521241Y100893D01*
G01X1521238Y100866D02*
Y100880D01*
G01X1521241Y97743D02*
X1521240Y97756D01*
G01X1521238Y97730D02*
X1521241Y97743D01*
G01X1521238Y97717D02*
Y97730D01*
G01X1521241Y94594D02*
X1521240Y94606D01*
G01X1521238Y94581D02*
X1521241Y94594D01*
G01X1521238Y94567D02*
Y94581D01*
G01X1521200Y102711D02*
X1521201Y102703D01*
G01X1521200Y102715D02*
Y102711D01*
G01Y102707D02*
Y102715D01*
G01X1521238Y102506D02*
X1521237Y102519D01*
G01X1521241Y102493D02*
X1521238Y102506D01*
G01X1521240Y102480D02*
X1521241Y102493D01*
G01X1521238Y99356D02*
X1521237Y99370D01*
G01X1521241Y99343D02*
X1521238Y99356D01*
G01X1521240Y99331D02*
X1521241Y99343D01*
G01X1521238Y96206D02*
X1521237Y96220D01*
G01X1521241Y96194D02*
X1521238Y96206D01*
G01X1521240Y96181D02*
X1521241Y96194D01*
G01X1522148Y104030D02*
X1522149Y104016D01*
G01X1522145Y104043D02*
X1522148Y104030D01*
G01X1522146Y104055D02*
X1522145Y104043D01*
G01X1522148Y100880D02*
X1522149Y100866D01*
G01X1522145Y100893D02*
X1522148Y100880D01*
G01X1522146Y100906D02*
X1522145Y100893D01*
G01X1522148Y97730D02*
X1522149Y97717D01*
G01X1522145Y97743D02*
X1522148Y97730D01*
G01X1522146Y97756D02*
X1522145Y97743D01*
G01X1522148Y94581D02*
X1522149Y94567D01*
G01X1522145Y94594D02*
X1522148Y94581D01*
G01X1522146Y94606D02*
X1522145Y94594D01*
G01X1521200Y99561D02*
X1521201Y99554D01*
G01X1521200Y99565D02*
Y99561D01*
G01X1521199Y99558D02*
X1521200Y99565D01*
G01X1522145Y102493D02*
X1522146Y102480D01*
G01X1522148Y102506D02*
X1522145Y102493D01*
G01X1522149Y102519D02*
X1522148Y102506D01*
G01X1522145Y99343D02*
X1522146Y99331D01*
G01X1522148Y99356D02*
X1522145Y99343D01*
G01X1522149Y99370D02*
X1522148Y99356D01*
G01X1522145Y96194D02*
X1522146Y96181D01*
G01X1522148Y96206D02*
X1522145Y96194D01*
G01X1522149Y96220D02*
X1522148Y96206D01*
G01X1521214Y103850D02*
X1521238Y103858D01*
G01X1521203Y103835D02*
X1521214Y103850D01*
G01X1521201Y103828D02*
X1521203Y103835D01*
G01X1521214Y100700D02*
X1521238Y100709D01*
G01X1521203Y100685D02*
X1521214Y100700D01*
G01X1521201Y100679D02*
X1521203Y100685D01*
G01X1521214Y97550D02*
X1521238Y97559D01*
G01X1521203Y97536D02*
X1521214Y97550D01*
G01X1521201Y97529D02*
X1521203Y97536D01*
G01X1521214Y94401D02*
X1521238Y94409D01*
G01X1521203Y94386D02*
X1521214Y94401D01*
G01X1521201Y94380D02*
X1521203Y94386D01*
G01X1522185Y103825D02*
Y103832D01*
G01Y103820D02*
Y103825D01*
G01X1522184Y103819D02*
X1522185Y103820D01*
G01Y100676D02*
Y100683D01*
G01Y100671D02*
Y100676D01*
G01X1522184Y100669D02*
X1522185Y100671D01*
G01Y97526D02*
Y97533D01*
G01Y97521D02*
Y97526D01*
G01X1522184Y97520D02*
X1522185Y97521D01*
G01Y94376D02*
Y94383D01*
G01Y94372D02*
Y94376D01*
G01X1522184Y94370D02*
X1522185Y94372D01*
G01X1522146Y103863D02*
Y103869D01*
G01X1522145Y103859D02*
X1522146Y103863D01*
G01X1522144Y103858D02*
X1522145Y103859D01*
G01X1522146Y100714D02*
Y100720D01*
G01X1522145Y100710D02*
X1522146Y100714D01*
G01X1522144Y100709D02*
X1522145Y100710D01*
G01X1522146Y97564D02*
Y97570D01*
G01X1522145Y97560D02*
X1522146Y97564D01*
G01X1522144Y97559D02*
X1522145Y97560D01*
G01X1522146Y94415D02*
Y94420D01*
G01X1522145Y94411D02*
X1522146Y94415D01*
G01X1522144Y94409D02*
X1522145Y94411D01*
G01X1521200Y103825D02*
X1521201Y103832D01*
G01X1521200Y103820D02*
Y103825D01*
G01X1521198Y103819D02*
X1521200Y103820D01*
G01Y100675D02*
X1521201Y100683D01*
G01X1521200Y100671D02*
Y100675D01*
G01X1521198Y100669D02*
X1521200Y100671D01*
G01Y97526D02*
X1521201Y97533D01*
G01X1521200Y97521D02*
Y97526D01*
G01X1521198Y97520D02*
X1521200Y97521D01*
G01Y94376D02*
X1521201Y94383D01*
G01X1521200Y94372D02*
Y94376D01*
G01X1521198Y94370D02*
X1521200Y94372D01*
G01X1522183Y102691D02*
X1522185Y102703D01*
G01X1522176Y102679D02*
X1522183Y102691D01*
G01X1522166Y102671D02*
X1522176Y102679D01*
G01X1522183Y96391D02*
X1522185Y96404D01*
G01X1522176Y96380D02*
X1522183Y96391D01*
G01X1522166Y96372D02*
X1522176Y96380D01*
G01X1521239Y103863D02*
Y103869D01*
G01Y103859D02*
Y103863D01*
G01X1521238Y103858D02*
X1521239Y103859D01*
G01Y100713D02*
Y100720D01*
G01Y100710D02*
Y100713D01*
G01X1521238Y100709D02*
X1521239Y100710D01*
G01Y97564D02*
Y97570D01*
G01Y97560D02*
Y97564D01*
G01X1521238Y97559D02*
X1521239Y97560D01*
G01Y94414D02*
Y94420D01*
G01Y94411D02*
Y94414D01*
G01X1521238Y94409D02*
X1521239Y94411D01*
G01X1521202Y103839D02*
X1521201Y103832D01*
G01X1521203Y103845D02*
X1521202Y103839D01*
G01X1521206Y103851D02*
X1521203Y103845D01*
G01X1521210Y103856D02*
X1521206Y103851D01*
G01X1521215Y103861D02*
X1521210Y103856D01*
G01X1521220Y103864D02*
X1521215Y103861D01*
G01X1521202Y100689D02*
X1521201Y100683D01*
G01X1521203Y100695D02*
X1521202Y100689D01*
G01X1521206Y100701D02*
X1521203Y100695D01*
G01X1521210Y100706D02*
X1521206Y100701D01*
G01X1521215Y100711D02*
X1521210Y100706D01*
G01X1521220Y100715D02*
X1521215Y100711D01*
G01X1521202Y97539D02*
X1521201Y97533D01*
G01X1521203Y97546D02*
X1521202Y97539D01*
G01X1521206Y97552D02*
X1521203Y97546D01*
G01X1521210Y97557D02*
X1521206Y97552D01*
G01X1521215Y97561D02*
X1521210Y97557D01*
G01X1521220Y97565D02*
X1521215Y97561D01*
G01X1521202Y94390D02*
X1521201Y94383D01*
G01X1521203Y94396D02*
X1521202Y94390D01*
G01X1521206Y94402D02*
X1521203Y94396D01*
G01X1521210Y94407D02*
X1521206Y94402D01*
G01X1521215Y94412D02*
X1521210Y94407D01*
G01X1521220Y94415D02*
X1521215Y94412D01*
G01X1522156Y102679D02*
X1522144Y102677D01*
G01X1522167Y102684D02*
X1522156Y102679D01*
G01Y99530D02*
X1522144Y99528D01*
G01X1522167Y99534D02*
X1522156Y99530D01*
G01Y96380D02*
X1522144Y96378D01*
G01X1522167Y96385D02*
X1522156Y96380D01*
G01X1532008Y188130D02*
G03I-1890J0D01*
G01X1532480D02*
G03I-2362J0D01*
G01X1527633Y185059D02*
X1528937Y187028D01*
G01X1522185Y94372D02*
Y94383D01*
G01Y97522D02*
Y97533D01*
G01Y100671D02*
Y100683D01*
G01Y103821D02*
Y103832D01*
G01X1528937Y187028D02*
Y188720D01*
G01X1526378Y183681D02*
Y192224D01*
G01X1522638Y185059D02*
Y106024D01*
G01X1522185Y102519D02*
Y104016D01*
G01Y99370D02*
Y100866D01*
G01Y96220D02*
Y97717D01*
G01X1522146Y96367D02*
Y96220D01*
G01Y94567D02*
Y94420D01*
G01Y99516D02*
Y99369D01*
G01Y100867D02*
Y100720D01*
G01Y97717D02*
Y97570D01*
G01Y102666D02*
Y102519D01*
G01Y104016D02*
Y103869D01*
G01X1521240Y102519D02*
Y102666D01*
G01Y103869D02*
Y104016D01*
G01Y99369D02*
Y99516D01*
G01Y100720D02*
Y100867D01*
G01Y97570D02*
Y97717D01*
G01Y96220D02*
Y96367D01*
G01Y94420D02*
Y94567D01*
G01X1521201Y100866D02*
Y99370D01*
G01Y97717D02*
Y96220D01*
G01Y104016D02*
Y102520D01*
G01X1520020Y97559D02*
Y96378D01*
G01Y100709D02*
Y99528D01*
G01Y103858D02*
Y102677D01*
G01X1519291Y201909D02*
Y186161D01*
G01X1516260Y102677D02*
Y103858D01*
G01Y99528D02*
Y100709D01*
G01Y96378D02*
Y97559D01*
G01X1522185Y102703D02*
Y102714D01*
G01Y99554D02*
Y99564D01*
G01Y96404D02*
Y96415D01*
G01X1522144Y99528D02*
X1522148Y99516D01*
G01X1528937Y188720D02*
X1526627Y192950D01*
G01X1524409Y181319D02*
X1525591Y180138D01*
G01X1522638Y182815D02*
X1519291Y186161D01*
G01X1521087Y102717D02*
X1521199Y102708D01*
G01X1528937Y187028D02*
X1531299D01*
G01X1522638Y185059D02*
X1537008D01*
G01X1522638Y183681D02*
X1526378D01*
G01X1522638Y182815D02*
X1537598D01*
G01X1524409Y181319D02*
X1532283D01*
G01X1525591Y180138D02*
X1531102D01*
G01X1521198Y96414D02*
X1521087Y96417D01*
G01X1522638Y106024D02*
X1519291D01*
G01X1522146Y104055D02*
X1521240D01*
G01X1522185Y104016D02*
X1521201D01*
G01X1522144Y103858D02*
X1516260D01*
G01Y103819D02*
X1522184D01*
G01X1522183Y102717D02*
X1516260D01*
G01X1522144Y102677D02*
X1516260D01*
G01X1521201Y102520D02*
X1522185D01*
G01X1521240Y102480D02*
X1522146D01*
G01Y100906D02*
X1521240D01*
G01X1522185Y100866D02*
X1521201D01*
G01X1522144Y100709D02*
X1516260D01*
G01Y100669D02*
X1522184D01*
G01X1522183Y99567D02*
X1516260D01*
G01X1522144Y99528D02*
X1516260D01*
G01X1521201Y99370D02*
X1522185D01*
G01X1521240Y99331D02*
X1522146D01*
G01Y97756D02*
X1521240D01*
G01X1522185Y97717D02*
X1521201D01*
G01X1522144Y97559D02*
X1516260D01*
G01Y97520D02*
X1522184D01*
G01X1520454Y96417D02*
X1520020D01*
G01X1522183D02*
X1516260D01*
G01X1522144Y96378D02*
X1516260D01*
G01X1521201Y96220D02*
X1522185D01*
G01X1521240Y96181D02*
X1522146D01*
G01Y94606D02*
X1521240D01*
G01X1522185Y94567D02*
X1521201D01*
G01X1522144Y94409D02*
X1516260D01*
G01Y94370D02*
X1522184D01*
G01X1532996Y264712D02*
G03X1566807I16906J-13531D01*
G01X1490157Y260630D02*
G03X1491339I591J0D01*
G01Y254331D02*
G03X1490157I-591J0D01*
G01X1488189D02*
G03X1487008I-591J0D01*
G01Y260630D02*
G03X1488189I591J0D01*
G01X1490157D02*
G03X1491339I591J0D01*
G01Y254331D02*
G03X1490157I-591J0D01*
G01X1488189D02*
G03X1487008I-591J0D01*
G01Y260630D02*
G03X1488189I591J0D01*
G01X1532996Y264712D02*
G03X1566807I16906J-13531D01*
G01X1526772Y203091D02*
G03X1526181Y202500I0J-591D01*
G01X1528937Y201319D02*
G03Y199350I0J-985D01*
G01X1527559Y193406D02*
G03X1526378Y192224I0J-1181D01*
G01X1521260Y203878D02*
G03X1519291Y201909I0J-1969D01*
G01X1526181Y196398D02*
Y202500D01*
G01X1492126Y254331D02*
Y260630D01*
G01Y254331D02*
Y260630D01*
G01X1486220Y254331D02*
Y260630D01*
G01D02*
Y254331D01*
G01X1490157Y260630D02*
X1488189D01*
G01X1487008D02*
X1486220D01*
G01X1490157D02*
X1488189D01*
G01X1487008D02*
X1486220D01*
G01X1492126D02*
X1491339D01*
G01X1492126D02*
X1491339D01*
G01X1492126Y259646D02*
X1486220D01*
G01Y259449D02*
X1492126D01*
G01X1486220Y255512D02*
X1492126D01*
G01Y255315D02*
X1486220D01*
G01X1491339Y254331D02*
X1492126D01*
G01X1491339D02*
X1492126D01*
G01X1488189D02*
X1490157D01*
G01X1486220D02*
X1487008D01*
G01X1488189D02*
X1490157D01*
G01X1486220D02*
X1487008D01*
G01X1538976Y203878D02*
X1521260D01*
G01X1533465Y203091D02*
X1526772D01*
G01X1531299Y201319D02*
X1528937D01*
G01Y199350D02*
X1531299D01*
G01X1534055Y197972D02*
X1526181D01*
G01Y196398D02*
X1534055D01*
G01X1540945Y193445D02*
X1519291D01*
G01X1527559Y193406D02*
X1532677D01*
G01X1528937Y188720D02*
X1531299D01*
G01X1521204Y537697D02*
X1521198Y537677D01*
G01X1521218Y537711D02*
X1521204Y537697D01*
G01X1521238Y537717D02*
X1521218Y537711D01*
G01X1521204Y540846D02*
X1521198Y540827D01*
G01X1521218Y540861D02*
X1521204Y540846D01*
G01X1521238Y540866D02*
X1521218Y540861D01*
G01X1521204Y543996D02*
X1521198Y543976D01*
G01X1521218Y544010D02*
X1521204Y543996D01*
G01X1521238Y544016D02*
X1521218Y544010D01*
G01X1521204Y547146D02*
X1521198Y547126D01*
G01X1521218Y547160D02*
X1521204Y547146D01*
G01X1521238Y547165D02*
X1521218Y547160D01*
G01X1521204Y550295D02*
X1521198Y550276D01*
G01X1521218Y550309D02*
X1521204Y550295D01*
G01X1521238Y550315D02*
X1521218Y550309D01*
G01X1521204Y553445D02*
X1521198Y553425D01*
G01X1521218Y553459D02*
X1521204Y553445D01*
G01X1521238Y553465D02*
X1521218Y553459D01*
G01X1521204Y556594D02*
X1521198Y556575D01*
G01X1521218Y556609D02*
X1521204Y556594D01*
G01X1521238Y556614D02*
X1521218Y556609D01*
G01X1522178Y536555D02*
X1522183Y536575D01*
G01X1522164Y536541D02*
X1522178Y536555D01*
G01X1522144Y536535D02*
X1522164Y536541D01*
G01X1522178Y539705D02*
X1522183Y539724D01*
G01X1522164Y539690D02*
X1522178Y539705D01*
G01X1522144Y539685D02*
X1522164Y539690D01*
G01X1522178Y542854D02*
X1522183Y542874D01*
G01X1522164Y542840D02*
X1522178Y542854D01*
G01X1522144Y542835D02*
X1522164Y542840D01*
G01X1522178Y546004D02*
X1522183Y546024D01*
G01X1522164Y545989D02*
X1522178Y546004D01*
G01X1522144Y545984D02*
X1522164Y545989D01*
G01X1522178Y549154D02*
X1522183Y549173D01*
G01X1522164Y549139D02*
X1522178Y549154D01*
G01X1522144Y549134D02*
X1522164Y549139D01*
G01X1522178Y552303D02*
X1522183Y552323D01*
G01X1522164Y552289D02*
X1522178Y552303D01*
G01X1522144Y552283D02*
X1522164Y552289D01*
G01X1522178Y555453D02*
X1522183Y555472D01*
G01X1522164Y555438D02*
X1522178Y555453D01*
G01X1522144Y555433D02*
X1522164Y555438D01*
G01X1522184Y552302D02*
X1522185Y552309D01*
G01X1522182Y552295D02*
X1522184Y552302D01*
G01X1522178Y552289D02*
X1522182Y552295D01*
G01X1522174Y552283D02*
X1522178Y552289D01*
G01X1522167Y552278D02*
X1522174Y552283D01*
G01X1522161Y552275D02*
X1522167Y552278D01*
G01X1522154Y552273D02*
X1522161Y552275D01*
G01X1522146Y552272D02*
X1522154Y552273D01*
G01X1522163Y536528D02*
X1522166Y536530D01*
G01X1522159Y536526D02*
X1522163Y536528D01*
G01X1522156Y536526D02*
X1522159D01*
G01X1522153Y536525D02*
X1522156Y536526D01*
G01X1522149Y536524D02*
X1522153Y536525D01*
G01X1522146Y536524D02*
X1522149D01*
G01X1521223Y537724D02*
X1521220Y537722D01*
G01X1521226Y537725D02*
X1521223Y537724D01*
G01X1521230Y537726D02*
X1521226Y537725D01*
G01X1521233Y537727D02*
X1521230Y537726D01*
G01X1521237Y537728D02*
X1521233Y537727D01*
G01X1521240Y537728D02*
X1521237D01*
G01X1522163Y539677D02*
X1522166Y539679D01*
G01X1522159Y539676D02*
X1522163Y539677D01*
G01X1522156Y539675D02*
X1522159Y539676D01*
G01X1522153Y539674D02*
X1522156Y539675D01*
G01X1522149Y539674D02*
X1522153D01*
G01X1522146D02*
X1522149D01*
G01X1521223Y540874D02*
X1521220Y540872D01*
G01X1521226Y540875D02*
X1521223Y540874D01*
G01X1521230Y540876D02*
X1521226Y540875D01*
G01X1521233Y540877D02*
X1521230Y540876D01*
G01X1521237Y540877D02*
X1521233D01*
G01X1521240D02*
X1521237D01*
G01X1522163Y542827D02*
X1522166Y542829D01*
G01X1522159Y542826D02*
X1522163Y542827D01*
G01X1522156Y542825D02*
X1522159Y542826D01*
G01X1522153Y542824D02*
X1522156Y542825D01*
G01X1522149Y542824D02*
X1522153D01*
G01X1522146Y542823D02*
X1522149Y542824D01*
G01X1521223Y544023D02*
X1521220Y544022D01*
G01X1521226Y544024D02*
X1521223Y544023D01*
G01X1521230Y544026D02*
X1521226Y544024D01*
G01X1521233Y544026D02*
X1521230D01*
G01X1521237Y544027D02*
X1521233Y544026D01*
G01X1521240Y544027D02*
X1521237D01*
G01X1522163Y545976D02*
X1522166Y545978D01*
G01X1522159Y545975D02*
X1522163Y545976D01*
G01X1522156Y545974D02*
X1522159Y545975D01*
G01X1522153Y545974D02*
X1522156D01*
G01X1522149Y545973D02*
X1522153Y545974D01*
G01X1522146Y545973D02*
X1522149D01*
G01X1521223Y547173D02*
X1521220Y547171D01*
G01X1521226Y547174D02*
X1521223Y547173D01*
G01X1521230Y547175D02*
X1521226Y547174D01*
G01X1521233Y547176D02*
X1521230Y547175D01*
G01X1521237Y547176D02*
X1521233D01*
G01X1521240D02*
X1521237D01*
G01X1522163Y549126D02*
X1522166Y549128D01*
G01X1522159Y549125D02*
X1522163Y549126D01*
G01X1522156Y549124D02*
X1522159Y549125D01*
G01X1522153Y549123D02*
X1522156Y549124D01*
G01X1522149Y549123D02*
X1522153D01*
G01X1522146Y549122D02*
X1522149Y549123D01*
G01X1521223Y550322D02*
X1521220Y550321D01*
G01X1521226Y550324D02*
X1521223Y550322D01*
G01X1521230Y550325D02*
X1521226Y550324D01*
G01X1521233Y550326D02*
X1521230Y550325D01*
G01X1521237Y550326D02*
X1521233D01*
G01X1521240D02*
X1521237D01*
G01X1521223Y553472D02*
X1521220Y553470D01*
G01X1521226Y553473D02*
X1521223Y553472D01*
G01X1521230Y553474D02*
X1521226Y553473D01*
G01X1521233Y553475D02*
X1521230Y553474D01*
G01X1521237Y553476D02*
X1521233Y553475D01*
G01X1521240Y553476D02*
X1521237D01*
G01X1522163Y555425D02*
X1522166Y555427D01*
G01X1522159Y555424D02*
X1522163Y555425D01*
G01X1522156Y555423D02*
X1522159Y555424D01*
G01X1522153Y555422D02*
X1522156Y555423D01*
G01X1522149Y555422D02*
X1522153D01*
G01X1522146D02*
X1522149D01*
G01X1521223Y556622D02*
X1521220Y556620D01*
G01X1521226Y556623D02*
X1521223Y556622D01*
G01X1521230Y556624D02*
X1521226Y556623D01*
G01X1521233Y556625D02*
X1521230Y556624D01*
G01X1521237Y556625D02*
X1521233D01*
G01X1521240D02*
X1521237D01*
G01X1522176Y537715D02*
X1522180Y537709D01*
G01X1522171Y537719D02*
X1522176Y537715D01*
G01X1522165Y537723D02*
X1522171Y537719D01*
G01X1522159Y537726D02*
X1522165Y537723D01*
G01X1522152Y537727D02*
X1522159Y537726D01*
G01X1522146Y537728D02*
X1522152Y537727D01*
G01X1522176Y540865D02*
X1522180Y540859D01*
G01X1522171Y540869D02*
X1522176Y540865D01*
G01X1522165Y540872D02*
X1522171Y540869D01*
G01X1522159Y540875D02*
X1522165Y540872D01*
G01X1522152Y540877D02*
X1522159Y540875D01*
G01X1522146Y540877D02*
X1522152D01*
G01X1522176Y544014D02*
X1522180Y544009D01*
G01X1522171Y544019D02*
X1522176Y544014D01*
G01X1522165Y544022D02*
X1522171Y544019D01*
G01X1522159Y544025D02*
X1522165Y544022D01*
G01X1522152Y544026D02*
X1522159Y544025D01*
G01X1522146Y544027D02*
X1522152Y544026D01*
G01X1522176Y547164D02*
X1522180Y547158D01*
G01X1522171Y547168D02*
X1522176Y547164D01*
G01X1522165Y547172D02*
X1522171Y547168D01*
G01X1522159Y547174D02*
X1522165Y547172D01*
G01X1522152Y547176D02*
X1522159Y547174D01*
G01X1522146Y547176D02*
X1522152D01*
G01X1522176Y550313D02*
X1522180Y550308D01*
G01X1522171Y550318D02*
X1522176Y550313D01*
G01X1522165Y550321D02*
X1522171Y550318D01*
G01X1522159Y550324D02*
X1522165Y550321D01*
G01X1522152Y550326D02*
X1522159Y550324D01*
G01X1522146Y550326D02*
X1522152D01*
G01X1522176Y553463D02*
X1522180Y553457D01*
G01X1522171Y553467D02*
X1522176Y553463D01*
G01X1522165Y553471D02*
X1522171Y553467D01*
G01X1522159Y553474D02*
X1522165Y553471D01*
G01X1522152Y553475D02*
X1522159Y553474D01*
G01X1522146Y553476D02*
X1522152Y553475D01*
G01X1522176Y556613D02*
X1522180Y556607D01*
G01X1522171Y556617D02*
X1522176Y556613D01*
G01X1522165Y556620D02*
X1522171Y556617D01*
G01X1522159Y556623D02*
X1522165Y556620D01*
G01X1522152Y556625D02*
X1522159Y556623D01*
G01X1522146Y556625D02*
X1522152D01*
G01X1521202Y536554D02*
X1521201Y536561D01*
G01X1521204Y536547D02*
X1521202Y536554D01*
G01X1521207Y536541D02*
X1521204Y536547D01*
G01X1521212Y536535D02*
X1521207Y536541D01*
G01X1521219Y536530D02*
X1521212Y536535D01*
G01X1521225Y536527D02*
X1521219Y536530D01*
G01X1521233Y536525D02*
X1521225Y536527D01*
G01X1521240Y536524D02*
X1521233Y536525D01*
G01X1521202Y539704D02*
X1521201Y539711D01*
G01X1521204Y539696D02*
X1521202Y539704D01*
G01X1521207Y539690D02*
X1521204Y539696D01*
G01X1521212Y539685D02*
X1521207Y539690D01*
G01X1521219Y539680D02*
X1521212Y539685D01*
G01X1521225Y539676D02*
X1521219Y539680D01*
G01X1521233Y539674D02*
X1521225Y539676D01*
G01X1521240Y539674D02*
X1521233D01*
G01X1521202Y542853D02*
X1521201Y542860D01*
G01X1521204Y542846D02*
X1521202Y542853D01*
G01X1521207Y542840D02*
X1521204Y542846D01*
G01X1521212Y542834D02*
X1521207Y542840D01*
G01X1521219Y542830D02*
X1521212Y542834D01*
G01X1521225Y542826D02*
X1521219Y542830D01*
G01X1521233Y542824D02*
X1521225Y542826D01*
G01X1521240Y542823D02*
X1521233Y542824D01*
G01X1521202Y546003D02*
X1521201Y546010D01*
G01X1521204Y545996D02*
X1521202Y546003D01*
G01X1521207Y545989D02*
X1521204Y545996D01*
G01X1521212Y545984D02*
X1521207Y545989D01*
G01X1521219Y545979D02*
X1521212Y545984D01*
G01X1521225Y545976D02*
X1521219Y545979D01*
G01X1521233Y545974D02*
X1521225Y545976D01*
G01X1521240Y545973D02*
X1521233Y545974D01*
G01X1521202Y549152D02*
X1521201Y549159D01*
G01X1521204Y549145D02*
X1521202Y549152D01*
G01X1521207Y549139D02*
X1521204Y549145D01*
G01X1521212Y549133D02*
X1521207Y549139D01*
G01X1521219Y549129D02*
X1521212Y549133D01*
G01X1521225Y549125D02*
X1521219Y549129D01*
G01X1521233Y549123D02*
X1521225Y549125D01*
G01X1521240Y549122D02*
X1521233Y549123D01*
G01X1521202Y552302D02*
X1521201Y552309D01*
G01X1521204Y552295D02*
X1521202Y552302D01*
G01X1521207Y552289D02*
X1521204Y552295D01*
G01X1521212Y552283D02*
X1521207Y552289D01*
G01X1521219Y552278D02*
X1521212Y552283D01*
G01X1521225Y552275D02*
X1521219Y552278D01*
G01X1521233Y552273D02*
X1521225Y552275D01*
G01X1521240Y552272D02*
X1521233Y552273D01*
G01X1521202Y555452D02*
X1521201Y555459D01*
G01X1521204Y555444D02*
X1521202Y555452D01*
G01X1521207Y555438D02*
X1521204Y555444D01*
G01X1521212Y555433D02*
X1521207Y555438D01*
G01X1521219Y555428D02*
X1521212Y555433D01*
G01X1521225Y555424D02*
X1521219Y555428D01*
G01X1521233Y555422D02*
X1521225Y555424D01*
G01X1521240Y555422D02*
X1521233D01*
G01X1522155Y537715D02*
X1522164Y537711D01*
G01X1522144Y537717D02*
X1522155Y537715D01*
G01Y540865D02*
X1522164Y540861D01*
G01X1522144Y540866D02*
X1522155Y540865D01*
G01Y544014D02*
X1522164Y544010D01*
G01X1522144Y544016D02*
X1522155Y544014D01*
G01Y547164D02*
X1522164Y547160D01*
G01X1522144Y547165D02*
X1522155Y547164D01*
G01Y550313D02*
X1522164Y550309D01*
G01X1522144Y550315D02*
X1522155Y550313D01*
G01Y553463D02*
X1522164Y553459D01*
G01X1522144Y553465D02*
X1522155Y553463D01*
G01Y556613D02*
X1522164Y556609D01*
G01X1522144Y556614D02*
X1522155Y556613D01*
G01X1521201Y539715D02*
Y539711D01*
G01X1521202Y539708D02*
X1521201Y539715D01*
G01X1521214Y539693D02*
X1521202Y539708D01*
G01X1521239Y539685D02*
X1521214Y539693D01*
G01X1521201Y542864D02*
Y542860D01*
G01X1521202Y542858D02*
X1521201Y542864D01*
G01X1521214Y542843D02*
X1521202Y542858D01*
G01X1521238Y542835D02*
X1521214Y542843D01*
G01X1521201Y549163D02*
Y549159D01*
G01X1521202Y549157D02*
X1521201Y549163D01*
G01X1521214Y549142D02*
X1521202Y549157D01*
G01X1521238Y549134D02*
X1521214Y549142D01*
G01X1521201Y552313D02*
Y552309D01*
G01X1521202Y552307D02*
X1521201Y552313D01*
G01X1521214Y552292D02*
X1521202Y552307D01*
G01X1521238Y552283D02*
X1521214Y552292D01*
G01X1521201Y536565D02*
Y536561D01*
G01X1521202Y536559D02*
X1521201Y536565D01*
G01X1521214Y536544D02*
X1521202Y536559D01*
G01X1521238Y536535D02*
X1521214Y536544D01*
G01X1521201Y555463D02*
Y555459D01*
G01X1521202Y555457D02*
X1521201Y555463D01*
G01X1521214Y555441D02*
X1521202Y555457D01*
G01X1521238Y555433D02*
X1521214Y555441D01*
G01X1521201Y546014D02*
Y546010D01*
G01X1521202Y546008D02*
X1521201Y546014D01*
G01X1521213Y545994D02*
X1521202Y546008D01*
G01X1521235Y545984D02*
X1521213Y545994D01*
G01X1522154Y544015D02*
X1522144Y544016D01*
G01X1522162Y544011D02*
X1522154Y544015D01*
G01X1522170Y544006D02*
X1522162Y544011D01*
G01X1522154Y537715D02*
X1522144Y537717D01*
G01X1522163Y537712D02*
X1522154Y537715D01*
G01X1522170Y537707D02*
X1522163Y537712D01*
G01X1522154Y540865D02*
X1522144Y540866D01*
G01X1522163Y540862D02*
X1522154Y540865D01*
G01X1522170Y540856D02*
X1522163Y540862D01*
G01X1522154Y547164D02*
X1522144Y547165D01*
G01X1522163Y547161D02*
X1522154Y547164D01*
G01X1522170Y547156D02*
X1522163Y547161D01*
G01X1522154Y550314D02*
X1522144Y550315D01*
G01X1522163Y550311D02*
X1522154Y550314D01*
G01X1522170Y550305D02*
X1522163Y550311D01*
G01X1522154Y553463D02*
X1522144Y553465D01*
G01X1522163Y553460D02*
X1522154Y553463D01*
G01X1522170Y553455D02*
X1522163Y553460D01*
G01X1522154Y556613D02*
X1522144Y556614D01*
G01X1522163Y556610D02*
X1522154Y556613D01*
G01X1522170Y556604D02*
X1522163Y556610D01*
G01X1521240Y536530D02*
Y536524D01*
G01X1521239Y536534D02*
X1521240Y536530D01*
G01X1521238Y536535D02*
X1521239Y536534D01*
G01X1521240Y539680D02*
Y539674D01*
G01X1521239Y539684D02*
X1521240Y539680D01*
G01X1521238Y539685D02*
X1521239Y539684D01*
G01X1521240Y542830D02*
Y542823D01*
G01X1521239Y542833D02*
X1521240Y542830D01*
G01X1521238Y542835D02*
X1521239Y542833D01*
G01X1521240Y545979D02*
Y545973D01*
G01X1521239Y545983D02*
X1521240Y545979D01*
G01X1521238Y545984D02*
X1521239Y545983D01*
G01X1521240Y549129D02*
Y549122D01*
G01X1521239Y549133D02*
X1521240Y549129D01*
G01X1521238Y549134D02*
X1521239Y549133D01*
G01X1521240Y552278D02*
Y552272D01*
G01X1521239Y552282D02*
X1521240Y552278D01*
G01X1521238Y552283D02*
X1521239Y552282D01*
G01X1521240Y555428D02*
Y555422D01*
G01X1521239Y555432D02*
X1521240Y555428D01*
G01X1521238Y555433D02*
X1521239Y555432D01*
G01X1521224Y539687D02*
X1521238Y539685D01*
G01X1521212Y539694D02*
X1521224Y539687D01*
G01X1521200Y539713D02*
X1521212Y539694D01*
G01X1521224Y549136D02*
X1521238Y549134D01*
G01X1521212Y549144D02*
X1521224Y549136D01*
G01X1521200Y549162D02*
X1521212Y549144D01*
G01X1521223Y542837D02*
X1521238Y542835D01*
G01X1521211Y542845D02*
X1521223Y542837D01*
G01X1521199Y542865D02*
X1521211Y542845D01*
G01X1521223Y552286D02*
X1521238Y552283D01*
G01X1521211Y552294D02*
X1521223Y552286D01*
G01X1521199Y552314D02*
X1521211Y552294D01*
G01X1522185Y536569D02*
Y536561D01*
G01X1522184Y536573D02*
X1522185Y536569D01*
G01X1522183Y536575D02*
X1522184Y536573D01*
G01X1522185Y539719D02*
Y539711D01*
G01X1522184Y539723D02*
X1522185Y539719D01*
G01X1522183Y539724D02*
X1522184Y539723D01*
G01X1522185Y542868D02*
Y542860D01*
G01X1522184Y542872D02*
X1522185Y542868D01*
G01X1522183Y542874D02*
X1522184Y542872D01*
G01X1522185Y546018D02*
Y546010D01*
G01X1522184Y546022D02*
X1522185Y546018D01*
G01X1522183Y546024D02*
X1522184Y546022D01*
G01X1522185Y549167D02*
Y549159D01*
G01X1522184Y549172D02*
X1522185Y549167D01*
G01X1522183Y549173D02*
X1522184Y549172D01*
G01X1522185Y552317D02*
Y552309D01*
G01X1522184Y552321D02*
X1522185Y552317D01*
G01X1522183Y552323D02*
X1522184Y552321D01*
G01X1522185Y555467D02*
Y555459D01*
G01X1522184Y555471D02*
X1522185Y555467D01*
G01X1522183Y555472D02*
X1522184Y555471D01*
G01X1521223Y555436D02*
X1521238Y555433D01*
G01X1521211Y555444D02*
X1521223Y555436D01*
G01X1521199Y555464D02*
X1521211Y555444D01*
G01X1521223Y536538D02*
X1521238Y536535D01*
G01X1521210Y536547D02*
X1521223Y536538D01*
G01X1521199Y536567D02*
X1521210Y536547D01*
G01X1522184Y537697D02*
X1522185Y537691D01*
G01X1522183Y537704D02*
X1522184Y537697D01*
G01X1522180Y537709D02*
X1522183Y537704D01*
G01X1522184Y540847D02*
X1522185Y540840D01*
G01X1522183Y540853D02*
X1522184Y540847D01*
G01X1522180Y540859D02*
X1522183Y540853D01*
G01X1522184Y543996D02*
X1522185Y543990D01*
G01X1522183Y544003D02*
X1522184Y543996D01*
G01X1522180Y544009D02*
X1522183Y544003D01*
G01X1522184Y547146D02*
X1522185Y547139D01*
G01X1522183Y547152D02*
X1522184Y547146D01*
G01X1522180Y547158D02*
X1522183Y547152D01*
G01X1522184Y550296D02*
X1522185Y550289D01*
G01X1522183Y550302D02*
X1522184Y550296D01*
G01X1522180Y550308D02*
X1522183Y550302D01*
G01X1522184Y553445D02*
X1522185Y553439D01*
G01X1522183Y553452D02*
X1522184Y553445D01*
G01X1522180Y553457D02*
X1522183Y553452D01*
G01X1522184Y556595D02*
X1522185Y556588D01*
G01X1522183Y556601D02*
X1522184Y556595D01*
G01X1522180Y556607D02*
X1522183Y556601D01*
G01X1522146Y536530D02*
Y536524D01*
G01X1522145Y536534D02*
X1522146Y536530D01*
G01X1522144Y536535D02*
X1522145Y536534D01*
G01X1522146Y539680D02*
Y539674D01*
G01X1522145Y539683D02*
X1522146Y539680D01*
G01X1522144Y539685D02*
X1522145Y539683D01*
G01X1522146Y542830D02*
Y542823D01*
G01X1522145Y542833D02*
X1522146Y542830D01*
G01X1522144Y542835D02*
X1522145Y542833D01*
G01X1522146Y545979D02*
Y545973D01*
G01X1522145Y545983D02*
X1522146Y545979D01*
G01X1522144Y545984D02*
X1522145Y545983D01*
G01X1522146Y549129D02*
Y549122D01*
G01X1522145Y549132D02*
X1522146Y549129D01*
G01X1522144Y549134D02*
X1522145Y549132D01*
G01X1522146Y555428D02*
Y555422D01*
G01X1522145Y555431D02*
X1522146Y555428D01*
G01X1522144Y555433D02*
X1522145Y555431D01*
G01X1521239Y556619D02*
Y556625D01*
G01Y556615D02*
Y556619D01*
G01X1521238Y556614D02*
X1521239Y556615D01*
G01Y553469D02*
Y553476D01*
G01Y553466D02*
Y553469D01*
G01X1521238Y553465D02*
X1521239Y553466D01*
G01Y550320D02*
Y550326D01*
G01Y550316D02*
Y550320D01*
G01X1521238Y550315D02*
X1521239Y550316D01*
G01Y547170D02*
Y547176D01*
G01Y547167D02*
Y547170D01*
G01X1521238Y547165D02*
X1521239Y547167D01*
G01Y544020D02*
Y544027D01*
G01Y544017D02*
Y544020D01*
G01X1521238Y544016D02*
X1521239Y544017D01*
G01Y540871D02*
Y540877D01*
G01Y540867D02*
Y540871D01*
G01X1521238Y540866D02*
X1521239Y540867D01*
G01X1521202Y556594D02*
X1521201Y556588D01*
G01X1521203Y556601D02*
X1521202Y556594D01*
G01X1521206Y556607D02*
X1521203Y556601D01*
G01X1521210Y556612D02*
X1521206Y556607D01*
G01X1521215Y556617D02*
X1521210Y556612D01*
G01X1521220Y556620D02*
X1521215Y556617D01*
G01X1521202Y553445D02*
X1521201Y553439D01*
G01X1521203Y553451D02*
X1521202Y553445D01*
G01X1521206Y553457D02*
X1521203Y553451D01*
G01X1521210Y553462D02*
X1521206Y553457D01*
G01X1521215Y553467D02*
X1521210Y553462D01*
G01X1521220Y553470D02*
X1521215Y553467D01*
G01X1521202Y550295D02*
X1521201Y550289D01*
G01X1521203Y550302D02*
X1521202Y550295D01*
G01X1521206Y550307D02*
X1521203Y550302D01*
G01X1521210Y550313D02*
X1521206Y550307D01*
G01X1521215Y550317D02*
X1521210Y550313D01*
G01X1521220Y550321D02*
X1521215Y550317D01*
G01X1521202Y547146D02*
X1521201Y547139D01*
G01X1521203Y547152D02*
X1521202Y547146D01*
G01X1521206Y547158D02*
X1521203Y547152D01*
G01X1521210Y547163D02*
X1521206Y547158D01*
G01X1521215Y547168D02*
X1521210Y547163D01*
G01X1521220Y547171D02*
X1521215Y547168D01*
G01X1521202Y543996D02*
X1521201Y543990D01*
G01X1521203Y544002D02*
X1521202Y543996D01*
G01X1521206Y544008D02*
X1521203Y544002D01*
G01X1521210Y544013D02*
X1521206Y544008D01*
G01X1521215Y544018D02*
X1521210Y544013D01*
G01X1521220Y544022D02*
X1521215Y544018D01*
G01X1521202Y540846D02*
X1521201Y540840D01*
G01X1521203Y540853D02*
X1521202Y540846D01*
G01X1521206Y540859D02*
X1521203Y540853D01*
G01X1521210Y540864D02*
X1521206Y540859D01*
G01X1521215Y540869D02*
X1521210Y540864D01*
G01X1521220Y540872D02*
X1521215Y540869D01*
G01X1521202Y537697D02*
X1521201Y537691D01*
G01X1521203Y537703D02*
X1521202Y537697D01*
G01X1521206Y537709D02*
X1521203Y537703D01*
G01X1521210Y537714D02*
X1521206Y537709D01*
G01X1521215Y537719D02*
X1521210Y537714D01*
G01X1521220Y537722D02*
X1521215Y537719D01*
G01X1522156Y555435D02*
X1522144Y555433D01*
G01X1522167Y555440D02*
X1522156Y555435D01*
G01Y552285D02*
X1522144Y552283D01*
G01X1522167Y552290D02*
X1522156Y552285D01*
G01Y549136D02*
X1522144Y549134D01*
G01X1522167Y549141D02*
X1522156Y549136D01*
G01Y545986D02*
X1522144Y545984D01*
G01X1522167Y545991D02*
X1522156Y545986D01*
G01Y542837D02*
X1522144Y542835D01*
G01X1522167Y542841D02*
X1522156Y542837D01*
G01Y539687D02*
X1522144Y539685D01*
G01X1522167Y539692D02*
X1522156Y539687D01*
G01Y536537D02*
X1522144Y536535D01*
G01X1522167Y536542D02*
X1522156Y536537D01*
G01X1521219Y545989D02*
X1521238Y545984D01*
G01X1521205Y546002D02*
X1521219Y545989D01*
G01X1521198Y546019D02*
X1521205Y546002D01*
G01X1521200Y549167D02*
X1521201Y549160D01*
G01X1521200Y549172D02*
Y549167D01*
G01Y549162D02*
Y549172D01*
G01X1521241Y556798D02*
X1521240Y556811D01*
G01X1521238Y556785D02*
X1521241Y556798D01*
G01X1521238Y556772D02*
Y556785D01*
G01X1521241Y553649D02*
X1521240Y553661D01*
G01X1521238Y553636D02*
X1521241Y553649D01*
G01X1521238Y553622D02*
Y553636D01*
G01X1521241Y550499D02*
X1521240Y550512D01*
G01X1521238Y550486D02*
X1521241Y550499D01*
G01X1521238Y550472D02*
Y550486D01*
G01X1521241Y547350D02*
X1521240Y547362D01*
G01X1521238Y547337D02*
X1521241Y547350D01*
G01X1521238Y547323D02*
Y547337D01*
G01X1521241Y544200D02*
X1521240Y544213D01*
G01X1521238Y544187D02*
X1521241Y544200D01*
G01X1521238Y544173D02*
Y544187D01*
G01X1521241Y541050D02*
X1521240Y541063D01*
G01X1521238Y541037D02*
X1521241Y541050D01*
G01X1521238Y541024D02*
Y541037D01*
G01X1521241Y537901D02*
X1521240Y537913D01*
G01X1521238Y537888D02*
X1521241Y537901D01*
G01X1521238Y537874D02*
Y537888D01*
G01X1521200Y555467D02*
X1521201Y555459D01*
G01X1521200Y555471D02*
Y555467D01*
G01Y555463D02*
Y555471D01*
G01X1521238Y555261D02*
X1521237Y555275D01*
G01X1521241Y555249D02*
X1521238Y555261D01*
G01X1521240Y555236D02*
X1521241Y555249D01*
G01X1521238Y552112D02*
X1521237Y552126D01*
G01X1521241Y552099D02*
X1521238Y552112D01*
G01X1521240Y552087D02*
X1521241Y552099D01*
G01X1521238Y548962D02*
X1521237Y548976D01*
G01X1521241Y548950D02*
X1521238Y548962D01*
G01X1521240Y548937D02*
X1521241Y548950D01*
G01X1521238Y545813D02*
X1521237Y545826D01*
G01X1521241Y545800D02*
X1521238Y545813D01*
G01X1521240Y545787D02*
X1521241Y545800D01*
G01X1521238Y542663D02*
X1521237Y542677D01*
G01X1521241Y542650D02*
X1521238Y542663D01*
G01X1521240Y542638D02*
X1521241Y542650D01*
G01X1521238Y539513D02*
X1521237Y539527D01*
G01X1521241Y539501D02*
X1521238Y539513D01*
G01X1521240Y539488D02*
X1521241Y539501D01*
G01X1521238Y536364D02*
X1521237Y536378D01*
G01X1521241Y536351D02*
X1521238Y536364D01*
G01X1521240Y536339D02*
X1521241Y536351D01*
G01X1522148Y556785D02*
X1522149Y556772D01*
G01X1522145Y556798D02*
X1522148Y556785D01*
G01X1522146Y556811D02*
X1522145Y556798D01*
G01X1522148Y553636D02*
X1522149Y553622D01*
G01X1522145Y553649D02*
X1522148Y553636D01*
G01X1522146Y553661D02*
X1522145Y553649D01*
G01X1522148Y550486D02*
X1522149Y550472D01*
G01X1522145Y550499D02*
X1522148Y550486D01*
G01X1522146Y550512D02*
X1522145Y550499D01*
G01X1522148Y547337D02*
X1522149Y547323D01*
G01X1522145Y547350D02*
X1522148Y547337D01*
G01X1522146Y547362D02*
X1522145Y547350D01*
G01X1522148Y544187D02*
X1522149Y544173D01*
G01X1522145Y544200D02*
X1522148Y544187D01*
G01X1522146Y544213D02*
X1522145Y544200D01*
G01X1522148Y541037D02*
X1522149Y541024D01*
G01X1522145Y541050D02*
X1522148Y541037D01*
G01X1522146Y541063D02*
X1522145Y541050D01*
G01X1522148Y537888D02*
X1522149Y537874D01*
G01X1522145Y537901D02*
X1522148Y537888D01*
G01X1522146Y537913D02*
X1522145Y537901D01*
G01X1521200Y542868D02*
X1521201Y542861D01*
G01X1521200Y542872D02*
Y542868D01*
G01X1521199Y542865D02*
X1521200Y542872D01*
G01Y552317D02*
X1521201Y552309D01*
G01X1521200Y552321D02*
Y552317D01*
G01X1521199Y552314D02*
X1521200Y552321D01*
G01X1522145Y555249D02*
X1522146Y555236D01*
G01X1522148Y555261D02*
X1522145Y555249D01*
G01X1522149Y555275D02*
X1522148Y555261D01*
G01X1522145Y552099D02*
X1522146Y552087D01*
G01X1522148Y552112D02*
X1522145Y552099D01*
G01X1522149Y552126D02*
X1522148Y552112D01*
G01X1522145Y548950D02*
X1522146Y548937D01*
G01X1522148Y548962D02*
X1522145Y548950D01*
G01X1522149Y548976D02*
X1522148Y548962D01*
G01X1522145Y545800D02*
X1522146Y545787D01*
G01X1522148Y545813D02*
X1522145Y545800D01*
G01X1522149Y545826D02*
X1522148Y545813D01*
G01X1522145Y542650D02*
X1522146Y542638D01*
G01X1522148Y542663D02*
X1522145Y542650D01*
G01X1522149Y542677D02*
X1522148Y542663D01*
G01X1522145Y539501D02*
X1522146Y539488D01*
G01X1522148Y539513D02*
X1522145Y539501D01*
G01X1522149Y539527D02*
X1522148Y539513D01*
G01X1522145Y536351D02*
X1522146Y536339D01*
G01X1522148Y536364D02*
X1522145Y536351D01*
G01X1522149Y536378D02*
X1522148Y536364D01*
G01X1521200Y536569D02*
X1521201Y536561D01*
G01X1521200Y536573D02*
Y536569D01*
G01X1521199Y536567D02*
X1521200Y536573D01*
G01X1522146Y556619D02*
Y556625D01*
G01X1522145Y556615D02*
X1522146Y556619D01*
G01X1522144Y556614D02*
X1522145Y556615D01*
G01X1522146Y553470D02*
Y553476D01*
G01X1522145Y553466D02*
X1522146Y553470D01*
G01X1522144Y553465D02*
X1522145Y553466D01*
G01X1522146Y550320D02*
Y550326D01*
G01X1522145Y550316D02*
X1522146Y550320D01*
G01X1522144Y550315D02*
X1522145Y550316D01*
G01X1522146Y547170D02*
Y547176D01*
G01X1522145Y547167D02*
X1522146Y547170D01*
G01X1522144Y547165D02*
X1522145Y547167D01*
G01X1522146Y544021D02*
Y544027D01*
G01X1522145Y544017D02*
X1522146Y544021D01*
G01X1522144Y544016D02*
X1522145Y544017D01*
G01X1521200Y556581D02*
X1521201Y556588D01*
G01X1521200Y556576D02*
Y556581D01*
G01X1521198Y556575D02*
X1521200Y556576D01*
G01Y553431D02*
X1521201Y553439D01*
G01X1521200Y553427D02*
Y553431D01*
G01X1521198Y553425D02*
X1521200Y553427D01*
G01Y550281D02*
X1521201Y550289D01*
G01X1521200Y550277D02*
Y550281D01*
G01X1521198Y550276D02*
X1521200Y550277D01*
G01Y547132D02*
X1521201Y547139D01*
G01X1521200Y547128D02*
Y547132D01*
G01X1521198Y547126D02*
X1521200Y547128D01*
G01Y543982D02*
X1521201Y543990D01*
G01X1521200Y543978D02*
Y543982D01*
G01X1521198Y543976D02*
X1521200Y543978D01*
G01Y540833D02*
X1521201Y540840D01*
G01X1521200Y540828D02*
Y540833D01*
G01X1521198Y540827D02*
X1521200Y540828D01*
G01Y537683D02*
X1521201Y537691D01*
G01X1521200Y537679D02*
Y537683D01*
G01X1521198Y537677D02*
X1521200Y537679D01*
G01X1522183Y555446D02*
X1522185Y555459D01*
G01X1522176Y555435D02*
X1522183Y555446D01*
G01X1522166Y555427D02*
X1522176Y555435D01*
G01X1522183Y549147D02*
X1522185Y549159D01*
G01X1522176Y549136D02*
X1522183Y549147D01*
G01X1522166Y549128D02*
X1522176Y549136D01*
G01X1522183Y545998D02*
X1522185Y546010D01*
G01X1522176Y545986D02*
X1522183Y545998D01*
G01X1522166Y545978D02*
X1522176Y545986D01*
G01X1522183Y542848D02*
X1522185Y542860D01*
G01X1522176Y542837D02*
X1522183Y542848D01*
G01X1522166Y542829D02*
X1522176Y542837D01*
G01X1522183Y539698D02*
X1522185Y539711D01*
G01X1522176Y539687D02*
X1522183Y539698D01*
G01X1522166Y539679D02*
X1522176Y539687D01*
G01X1522183Y536549D02*
X1522185Y536561D01*
G01X1522176Y536537D02*
X1522183Y536549D01*
G01X1522166Y536530D02*
X1522176Y536537D01*
G01X1521239Y537721D02*
Y537728D01*
G01Y537718D02*
Y537721D01*
G01X1521238Y537717D02*
X1521239Y537718D01*
G01X1522178Y543998D02*
X1522170Y544006D01*
G01X1522182Y543987D02*
X1522178Y543998D01*
G01X1522184Y543976D02*
X1522182Y543987D01*
G01X1522178Y537698D02*
X1522170Y537707D01*
G01X1522182Y537688D02*
X1522178Y537698D01*
G01X1522184Y537677D02*
X1522182Y537688D01*
G01X1522178Y540848D02*
X1522170Y540856D01*
G01X1522182Y540838D02*
X1522178Y540848D01*
G01X1522184Y540827D02*
X1522182Y540838D01*
G01X1522178Y547147D02*
X1522170Y547156D01*
G01X1522182Y547137D02*
X1522178Y547147D01*
G01X1522184Y547126D02*
X1522182Y547137D01*
G01X1522178Y550297D02*
X1522170Y550305D01*
G01X1522182Y550287D02*
X1522178Y550297D01*
G01X1522184Y550276D02*
X1522182Y550287D01*
G01X1522178Y553446D02*
X1522170Y553455D01*
G01X1522182Y553436D02*
X1522178Y553446D01*
G01X1522184Y553425D02*
X1522182Y553436D01*
G01X1522178Y556596D02*
X1522170Y556604D01*
G01X1522182Y556586D02*
X1522178Y556596D01*
G01X1522184Y556575D02*
X1522182Y556586D01*
G01X1521214Y556606D02*
X1521238Y556614D01*
G01X1521203Y556591D02*
X1521214Y556606D01*
G01X1521201Y556584D02*
X1521203Y556591D01*
G01X1521214Y553456D02*
X1521238Y553465D01*
G01X1521203Y553441D02*
X1521214Y553456D01*
G01X1521201Y553435D02*
X1521203Y553441D01*
G01X1521214Y550306D02*
X1521238Y550315D01*
G01X1521203Y550292D02*
X1521214Y550306D01*
G01X1521201Y550285D02*
X1521203Y550292D01*
G01X1521214Y547157D02*
X1521238Y547165D01*
G01X1521203Y547142D02*
X1521214Y547157D01*
G01X1521201Y547135D02*
X1521203Y547142D01*
G01X1521214Y544007D02*
X1521238Y544016D01*
G01X1521203Y543993D02*
X1521214Y544007D01*
G01X1521201Y543986D02*
X1521203Y543993D01*
G01X1521214Y540857D02*
X1521238Y540866D01*
G01X1521203Y540843D02*
X1521214Y540857D01*
G01X1521201Y540836D02*
X1521203Y540843D01*
G01X1521214Y537708D02*
X1521238Y537717D01*
G01X1521203Y537693D02*
X1521214Y537708D01*
G01X1521201Y537687D02*
X1521203Y537693D01*
G01X1522185Y556581D02*
Y556588D01*
G01Y556576D02*
Y556581D01*
G01X1522184Y556575D02*
X1522185Y556576D01*
G01Y553431D02*
Y553439D01*
G01Y553427D02*
Y553431D01*
G01X1522184Y553425D02*
X1522185Y553427D01*
G01Y550282D02*
Y550289D01*
G01Y550277D02*
Y550282D01*
G01X1522184Y550276D02*
X1522185Y550277D01*
G01Y547132D02*
Y547139D01*
G01Y547128D02*
Y547132D01*
G01X1522184Y547126D02*
X1522185Y547128D01*
G01Y543983D02*
Y543990D01*
G01Y543978D02*
Y543983D01*
G01X1522184Y543976D02*
X1522185Y543978D01*
G01Y540833D02*
Y540840D01*
G01Y540828D02*
Y540833D01*
G01X1522184Y540827D02*
X1522185Y540828D01*
G01Y537683D02*
Y537691D01*
G01Y537679D02*
Y537683D01*
G01X1522184Y537677D02*
X1522185Y537679D01*
G01X1521200Y546018D02*
X1521201Y546010D01*
G01X1521200Y546022D02*
Y546018D01*
G01X1521198Y546019D02*
X1521200Y546022D01*
G01Y539719D02*
X1521201Y539711D01*
G01X1521200Y539723D02*
Y539719D01*
G01X1521198Y539721D02*
X1521200Y539723D01*
G01X1522146Y540871D02*
Y540877D01*
G01X1522145Y540867D02*
X1522146Y540871D01*
G01X1522144Y540866D02*
X1522145Y540867D01*
G01X1522146Y537722D02*
Y537728D01*
G01X1522145Y537718D02*
X1522146Y537722D01*
G01X1522144Y537717D02*
X1522145Y537718D01*
G01X1531220Y492264D02*
G03I-1102J0D01*
G01X1526378Y488169D02*
G03X1527559Y486988I1181J0D01*
G01X1531693Y492264D02*
G03I-1575J0D01*
G01X1526181Y477894D02*
G03X1526772Y477303I591J0D01*
G01X1528937Y481043D02*
G03Y479075I0J-984D01*
G01X1519291Y478484D02*
G03X1521260Y476516I1969J1D01*
G01X1526627Y487444D02*
X1528937Y491673D01*
G01X1525591Y500256D02*
X1524409Y499075D01*
G01X1522638Y497579D02*
X1519291Y494232D01*
G01X1522185Y537679D02*
Y537691D01*
G01Y540829D02*
Y540840D01*
G01Y543978D02*
Y543990D01*
G01Y547128D02*
Y547139D01*
G01Y550278D02*
Y550289D01*
G01Y553427D02*
Y553439D01*
G01Y556577D02*
Y556588D01*
G01X1528937Y491673D02*
Y493366D01*
G01X1526378Y488169D02*
Y496713D01*
G01X1526181Y483996D02*
Y477894D01*
G01X1525591Y500256D02*
Y632894D01*
G01X1524409Y499075D02*
Y634075D01*
G01X1522638Y534370D02*
Y495335D01*
G01Y637815D02*
Y558780D01*
G01X1522185Y555275D02*
Y556772D01*
G01Y552126D02*
Y553622D01*
G01Y548976D02*
Y550472D01*
G01Y545826D02*
Y547323D01*
G01Y542677D02*
Y544173D01*
G01Y539527D02*
Y541024D01*
G01Y536378D02*
Y537874D01*
G01X1522146Y536524D02*
Y536377D01*
G01Y539674D02*
Y539527D01*
G01Y541024D02*
Y540877D01*
G01Y537874D02*
Y537728D01*
G01Y545973D02*
Y545826D01*
G01Y542823D02*
Y542676D01*
G01Y544174D02*
Y544027D01*
G01Y549122D02*
Y548976D01*
G01Y550473D02*
Y550326D01*
G01Y547323D02*
Y547176D01*
G01Y555422D02*
Y555275D01*
G01Y552272D02*
Y552125D01*
G01Y553622D02*
Y553476D01*
G01Y556772D02*
Y556625D01*
G01X1521240D02*
Y556772D01*
G01Y555275D02*
Y555422D01*
G01Y552125D02*
Y552272D01*
G01Y553476D02*
Y553622D01*
G01Y548976D02*
Y549122D01*
G01Y550326D02*
Y550473D01*
G01Y547176D02*
Y547323D01*
G01Y545826D02*
Y545973D01*
G01Y542676D02*
Y542823D01*
G01Y544027D02*
Y544174D01*
G01Y539527D02*
Y539674D01*
G01Y540877D02*
Y541024D01*
G01Y537728D02*
Y537874D01*
G01Y536377D02*
Y536524D01*
G01X1521201Y541024D02*
Y539528D01*
G01Y537874D02*
Y536378D01*
G01Y544173D02*
Y542677D01*
G01Y550472D02*
Y548976D01*
G01Y547323D02*
Y545827D01*
G01Y553622D02*
Y552126D01*
G01Y556772D02*
Y555276D01*
G01X1520020Y537717D02*
Y536535D01*
G01Y540866D02*
Y539685D01*
G01Y547165D02*
Y545984D01*
G01Y544016D02*
Y542835D01*
G01Y550315D02*
Y549134D01*
G01Y556614D02*
Y555433D01*
G01Y553465D02*
Y552283D01*
G01X1519685Y558780D02*
Y534370D01*
G01X1519291D02*
Y558780D01*
G01Y494232D02*
Y478484D01*
G01X1516260Y555433D02*
Y556614D01*
G01Y552283D02*
Y553465D01*
G01Y549134D02*
Y550315D01*
G01Y545984D02*
Y547165D01*
G01Y542835D02*
Y544016D01*
G01Y539685D02*
Y540866D01*
G01Y536535D02*
Y537717D01*
G01X1522185Y555459D02*
Y555470D01*
G01Y552309D02*
Y552320D01*
G01Y549160D02*
Y549170D01*
G01Y546010D02*
Y546021D01*
G01Y542861D02*
Y542871D01*
G01Y539711D02*
Y539722D01*
G01Y536561D02*
Y536572D01*
G01X1522144Y552283D02*
X1522148Y552272D01*
G01X1528937Y493366D02*
X1527633Y495335D01*
G01X1521087Y555472D02*
X1521199Y555464D01*
G01X1521198Y546019D02*
X1521087Y546024D01*
G01X1521198Y539721D02*
X1521087Y539724D01*
G01X1521198Y549170D02*
X1521087Y549173D01*
G01X1522638Y558780D02*
X1519291D01*
G01X1522146Y556811D02*
X1521240D01*
G01X1522185Y556772D02*
X1521201D01*
G01X1522144Y556614D02*
X1516260D01*
G01Y556575D02*
X1522184D01*
G01X1522183Y555472D02*
X1516260D01*
G01X1522144Y555433D02*
X1516260D01*
G01X1521201Y555276D02*
X1522185D01*
G01X1521240Y555236D02*
X1522146D01*
G01Y553661D02*
X1521240D01*
G01X1522185Y553622D02*
X1521201D01*
G01X1522144Y553465D02*
X1516260D01*
G01Y553425D02*
X1522184D01*
G01X1522183Y552323D02*
X1516260D01*
G01X1522144Y552283D02*
X1516260D01*
G01X1521201Y552126D02*
X1522185D01*
G01X1521240Y552087D02*
X1522146D01*
G01Y550512D02*
X1521240D01*
G01X1522185Y550472D02*
X1521201D01*
G01X1522144Y550315D02*
X1516260D01*
G01Y550276D02*
X1522184D01*
G01X1520454Y549173D02*
X1520020D01*
G01X1522183D02*
X1516260D01*
G01X1522144Y549134D02*
X1516260D01*
G01X1521201Y548976D02*
X1522185D01*
G01X1521240Y548937D02*
X1522146D01*
G01Y547362D02*
X1521240D01*
G01X1522185Y547323D02*
X1521201D01*
G01X1522144Y547165D02*
X1516260D01*
G01Y547126D02*
X1522184D01*
G01X1520454Y546024D02*
X1520020D01*
G01X1522183D02*
X1516260D01*
G01X1522144Y545984D02*
X1516260D01*
G01X1521201Y545827D02*
X1522185D01*
G01X1521240Y545787D02*
X1522146D01*
G01Y544213D02*
X1521240D01*
G01X1522185Y544173D02*
X1521201D01*
G01X1522144Y544016D02*
X1516260D01*
G01Y543976D02*
X1522184D01*
G01X1522183Y542874D02*
X1516260D01*
G01X1522144Y542835D02*
X1516260D01*
G01X1521201Y542677D02*
X1522185D01*
G01X1521240Y542638D02*
X1522146D01*
G01Y541063D02*
X1521240D01*
G01X1522185Y541024D02*
X1521201D01*
G01X1522144Y540866D02*
X1516260D01*
G01Y540827D02*
X1522184D01*
G01X1520454Y539724D02*
X1520020D01*
G01X1522183D02*
X1516260D01*
G01X1522144Y539685D02*
X1516260D01*
G01X1521201Y539528D02*
X1522185D01*
G01X1521240Y539488D02*
X1522146D01*
G01Y537913D02*
X1521240D01*
G01X1522185Y537874D02*
X1521201D01*
G01X1522144Y537717D02*
X1516260D01*
G01Y537677D02*
X1522184D01*
G01X1522183Y536575D02*
X1516260D01*
G01X1522144Y536535D02*
X1516260D01*
G01X1521201Y536378D02*
X1522185D01*
G01X1521240Y536339D02*
X1522146D01*
G01X1522638Y534370D02*
X1519291D01*
G01X1531102Y500256D02*
X1525591D01*
G01X1532283Y499075D02*
X1524409D01*
G01X1537598Y497579D02*
X1522638D01*
G01X1526378Y496713D02*
X1522638D01*
G01Y495335D02*
X1537008D01*
G01X1531299Y493366D02*
X1528937D01*
G01X1531299Y491673D02*
X1528937D01*
G01X1532677Y486988D02*
X1527559D01*
G01X1540945Y486949D02*
X1519291D01*
G01X1534055Y483996D02*
X1526181D01*
G01Y482421D02*
X1534055D01*
G01X1531299Y481043D02*
X1528937D01*
G01Y479075D02*
X1531299D01*
G01X1533465Y477303D02*
X1526772D01*
G01X1538976Y476516D02*
X1521260D01*
G01X1526772Y655846D02*
G03X1526181Y655256I-1J-590D01*
G01X1528937Y654075D02*
G03Y652106I0J-985D01*
G01X1527559Y646161D02*
G03X1526378Y644980I0J-1181D01*
G01X1532008Y640886D02*
G03I-1890J0D01*
G01X1521260Y656634D02*
G03X1519291Y654665I0J-1969D01*
G01X1532480Y640886D02*
G03I-2362J0D01*
G01X1527633Y637815D02*
X1528937Y639783D01*
G01D02*
Y641476D01*
G01X1526378Y636437D02*
Y644980D01*
G01X1526181Y649154D02*
Y655256D01*
G01X1519291Y654665D02*
Y638917D01*
G01X1528937Y641476D02*
X1526627Y645706D01*
G01X1524409Y634075D02*
X1525591Y632894D01*
G01X1519291Y638917D02*
X1522638Y635571D01*
G01X1538976Y656634D02*
X1521260D01*
G01X1533465Y655846D02*
X1526772D01*
G01X1531299Y654075D02*
X1528937D01*
G01Y652106D02*
X1531299D01*
G01X1534055Y650728D02*
X1526181D01*
G01Y649154D02*
X1534055D01*
G01X1540945Y646201D02*
X1519291D01*
G01X1527559Y646161D02*
X1532677D01*
G01X1528937Y641476D02*
X1531299D01*
G01X1528937Y639783D02*
X1531299D01*
G01X1522638Y637815D02*
X1537008D01*
G01X1522638Y636437D02*
X1526378D01*
G01X1522638Y635571D02*
X1537598D01*
G01X1524409Y634075D02*
X1532283D01*
G01X1525591Y632894D02*
X1531102D01*
G01X1532996Y717468D02*
G03X1566807I16906J-13531D01*
G01X1490157Y713386D02*
G03X1491339I591J0D01*
G01Y707087D02*
G03X1490157I-591J0D01*
G01X1488189D02*
G03X1487008I-591J0D01*
G01Y713386D02*
G03X1488189I591J0D01*
G01X1490157D02*
G03X1491339I591J0D01*
G01Y707087D02*
G03X1490157I-591J0D01*
G01X1488189D02*
G03X1487008I-591J0D01*
G01Y713386D02*
G03X1488189I591J0D01*
G01X1532996Y717468D02*
G03X1566807I16906J-13531D01*
G01X1492126Y707087D02*
Y713386D01*
G01Y707087D02*
Y713386D01*
G01X1486220Y707087D02*
Y713386D01*
G01D02*
Y707087D01*
G01X1490157Y713386D02*
X1488189D01*
G01X1487008D02*
X1486220D01*
G01X1490157D02*
X1488189D01*
G01X1487008D02*
X1486220D01*
G01X1492126D02*
X1491339D01*
G01X1492126D02*
X1491339D01*
G01X1492126Y712402D02*
X1486220D01*
G01Y712205D02*
X1492126D01*
G01X1486220Y708268D02*
X1492126D01*
G01Y708071D02*
X1486220D01*
G01X1491339Y707087D02*
X1492126D01*
G01X1491339D02*
X1492126D01*
G01X1488189D02*
X1490157D01*
G01X1486220D02*
X1487008D01*
G01X1488189D02*
X1490157D01*
G01X1486220D02*
X1487008D01*
G01X1531220Y945020D02*
G03I-1102J0D01*
G01X1526378Y940925D02*
G03X1527559Y939744I1181J0D01*
G01X1531693Y945020D02*
G03I-1575J0D01*
G01X1526181Y930650D02*
G03X1526772Y930059I591J0D01*
G01X1528937Y933799D02*
G03Y931831I0J-984D01*
G01X1519291Y931240D02*
G03X1521260Y929272I1968J0D01*
G01X1528937Y946122D02*
X1527633Y948091D01*
G01X1528937Y944429D02*
Y946122D01*
G01X1526378Y940925D02*
Y949469D01*
G01X1526181Y936752D02*
Y930650D01*
G01X1524409Y951831D02*
Y1086831D01*
G01X1522638Y987126D02*
Y948091D01*
G01X1519291Y946988D02*
Y931240D01*
G01X1526627Y940200D02*
X1528937Y944429D01*
G01X1525591Y953012D02*
X1524409Y951831D01*
G01X1522638Y950335D02*
X1519291Y946988D01*
G01X1532283Y951831D02*
X1524409D01*
G01X1537598Y950335D02*
X1522638D01*
G01X1526378Y949469D02*
X1522638D01*
G01Y948091D02*
X1537008D01*
G01X1531299Y946122D02*
X1528937D01*
G01X1531299Y944429D02*
X1528937D01*
G01X1532677Y939744D02*
X1527559D01*
G01X1540945Y939705D02*
X1519291D01*
G01X1534055Y936752D02*
X1526181D01*
G01Y935177D02*
X1534055D01*
G01X1531299Y933799D02*
X1528937D01*
G01Y931831D02*
X1531299D01*
G01X1533465Y930059D02*
X1526772D01*
G01X1538976Y929272D02*
X1521260D01*
G01X1522156Y1008191D02*
X1522144Y1008189D01*
G01X1522167Y1008196D02*
X1522156Y1008191D01*
G01Y1005041D02*
X1522144Y1005039D01*
G01X1522167Y1005046D02*
X1522156Y1005041D01*
G01Y1001892D02*
X1522144Y1001890D01*
G01X1522167Y1001896D02*
X1522156Y1001892D01*
G01Y998742D02*
X1522144Y998740D01*
G01X1522167Y998747D02*
X1522156Y998742D01*
G01Y995593D02*
X1522144Y995591D01*
G01X1522167Y995597D02*
X1522156Y995593D01*
G01Y992443D02*
X1522144Y992441D01*
G01X1522167Y992448D02*
X1522156Y992443D01*
G01Y989293D02*
X1522144Y989291D01*
G01X1522167Y989298D02*
X1522156Y989293D01*
G01X1521204Y990453D02*
X1521198Y990433D01*
G01X1521218Y990467D02*
X1521204Y990453D01*
G01X1521238Y990472D02*
X1521218Y990467D01*
G01X1521204Y993602D02*
X1521198Y993583D01*
G01X1521218Y993617D02*
X1521204Y993602D01*
G01X1521238Y993622D02*
X1521218Y993617D01*
G01X1521204Y996752D02*
X1521198Y996732D01*
G01X1521218Y996766D02*
X1521204Y996752D01*
G01X1521238Y996772D02*
X1521218Y996766D01*
G01X1521204Y999902D02*
X1521198Y999882D01*
G01X1521218Y999916D02*
X1521204Y999902D01*
G01X1521238Y999921D02*
X1521218Y999916D01*
G01X1521204Y1003051D02*
X1521198Y1003031D01*
G01X1521218Y1003065D02*
X1521204Y1003051D01*
G01X1521238Y1003071D02*
X1521218Y1003065D01*
G01X1521204Y1006201D02*
X1521198Y1006181D01*
G01X1521218Y1006215D02*
X1521204Y1006201D01*
G01X1521238Y1006220D02*
X1521218Y1006215D01*
G01X1522178Y989311D02*
X1522183Y989331D01*
G01X1522164Y989296D02*
X1522178Y989311D01*
G01X1522144Y989291D02*
X1522164Y989296D01*
G01X1522178Y992461D02*
X1522183Y992480D01*
G01X1522164Y992446D02*
X1522178Y992461D01*
G01X1522144Y992441D02*
X1522164Y992446D01*
G01X1522178Y995610D02*
X1522183Y995630D01*
G01X1522164Y995596D02*
X1522178Y995610D01*
G01X1522144Y995591D02*
X1522164Y995596D01*
G01X1522178Y998760D02*
X1522183Y998780D01*
G01X1522164Y998745D02*
X1522178Y998760D01*
G01X1522144Y998740D02*
X1522164Y998745D01*
G01X1522178Y1001909D02*
X1522183Y1001929D01*
G01X1522164Y1001895D02*
X1522178Y1001909D01*
G01X1522144Y1001890D02*
X1522164Y1001895D01*
G01X1522178Y1005059D02*
X1522183Y1005079D01*
G01X1522164Y1005044D02*
X1522178Y1005059D01*
G01X1522144Y1005039D02*
X1522164Y1005044D01*
G01X1522178Y1008209D02*
X1522183Y1008228D01*
G01X1522164Y1008194D02*
X1522178Y1008209D01*
G01X1522144Y1008189D02*
X1522164Y1008194D01*
G01X1522183Y1008202D02*
X1522185Y1008215D01*
G01X1522176Y1008191D02*
X1522183Y1008202D01*
G01X1522166Y1008183D02*
X1522176Y1008191D01*
G01X1522183Y1001903D02*
X1522185Y1001915D01*
G01X1522176Y1001892D02*
X1522183Y1001903D01*
G01X1522166Y1001884D02*
X1522176Y1001892D01*
G01X1522183Y998754D02*
X1522185Y998766D01*
G01X1522176Y998742D02*
X1522183Y998754D01*
G01X1522166Y998734D02*
X1522176Y998742D01*
G01X1522183Y995604D02*
X1522185Y995616D01*
G01X1522176Y995593D02*
X1522183Y995604D01*
G01X1522166Y995585D02*
X1522176Y995593D01*
G01X1522183Y992454D02*
X1522185Y992467D01*
G01X1522176Y992443D02*
X1522183Y992454D01*
G01X1522166Y992435D02*
X1522176Y992443D01*
G01X1522183Y989305D02*
X1522185Y989317D01*
G01X1522176Y989293D02*
X1522183Y989305D01*
G01X1522166Y989285D02*
X1522176Y989293D01*
G01X1521239Y1009375D02*
Y1009381D01*
G01Y1009371D02*
Y1009375D01*
G01X1521238Y1009370D02*
X1521239Y1009371D01*
G01Y1006225D02*
Y1006231D01*
G01Y1006222D02*
Y1006225D01*
G01X1521238Y1006220D02*
X1521239Y1006222D01*
G01Y1003076D02*
Y1003082D01*
G01Y1003072D02*
Y1003076D01*
G01X1521238Y1003071D02*
X1521239Y1003072D01*
G01Y999926D02*
Y999932D01*
G01Y999922D02*
Y999926D01*
G01X1521238Y999921D02*
X1521239Y999922D01*
G01Y996776D02*
Y996783D01*
G01Y996773D02*
Y996776D01*
G01X1521238Y996772D02*
X1521239Y996773D01*
G01Y993627D02*
Y993633D01*
G01Y993623D02*
Y993627D01*
G01X1521238Y993622D02*
X1521239Y993623D01*
G01Y990477D02*
Y990483D01*
G01Y990474D02*
Y990477D01*
G01X1521238Y990472D02*
X1521239Y990474D01*
G01X1521202Y1009350D02*
X1521201Y1009344D01*
G01X1521203Y1009357D02*
X1521202Y1009350D01*
G01X1521206Y1009363D02*
X1521203Y1009357D01*
G01X1521210Y1009368D02*
X1521206Y1009363D01*
G01X1521215Y1009372D02*
X1521210Y1009368D01*
G01X1521220Y1009376D02*
X1521215Y1009372D01*
G01X1521202Y1006201D02*
X1521201Y1006194D01*
G01X1521203Y1006207D02*
X1521202Y1006201D01*
G01X1521206Y1006213D02*
X1521203Y1006207D01*
G01X1521210Y1006218D02*
X1521206Y1006213D01*
G01X1521215Y1006223D02*
X1521210Y1006218D01*
G01X1521220Y1006226D02*
X1521215Y1006223D01*
G01X1521202Y1003051D02*
X1521201Y1003045D01*
G01X1521203Y1003057D02*
X1521202Y1003051D01*
G01X1521206Y1003063D02*
X1521203Y1003057D01*
G01X1521210Y1003069D02*
X1521206Y1003063D01*
G01X1521215Y1003073D02*
X1521210Y1003069D01*
G01X1521220Y1003077D02*
X1521215Y1003073D01*
G01X1521202Y999902D02*
X1521201Y999895D01*
G01X1521203Y999908D02*
X1521202Y999902D01*
G01X1521206Y999914D02*
X1521203Y999908D01*
G01X1521210Y999919D02*
X1521206Y999914D01*
G01X1521215Y999924D02*
X1521210Y999919D01*
G01X1521220Y999927D02*
X1521215Y999924D01*
G01X1521202Y996752D02*
X1521201Y996746D01*
G01X1521203Y996758D02*
X1521202Y996752D01*
G01X1521206Y996764D02*
X1521203Y996758D01*
G01X1521210Y996769D02*
X1521206Y996764D01*
G01X1521215Y996774D02*
X1521210Y996769D01*
G01X1521220Y996778D02*
X1521215Y996774D01*
G01X1521202Y993602D02*
X1521201Y993596D01*
G01X1521203Y993609D02*
X1521202Y993602D01*
G01X1521206Y993615D02*
X1521203Y993609D01*
G01X1521210Y993620D02*
X1521206Y993615D01*
G01X1521215Y993624D02*
X1521210Y993620D01*
G01X1521220Y993628D02*
X1521215Y993624D01*
G01X1521202Y990453D02*
X1521201Y990446D01*
G01X1521203Y990459D02*
X1521202Y990453D01*
G01X1521206Y990465D02*
X1521203Y990459D01*
G01X1521210Y990470D02*
X1521206Y990465D01*
G01X1521215Y990475D02*
X1521210Y990470D01*
G01X1521220Y990478D02*
X1521215Y990475D01*
G01X1521204Y1009350D02*
X1521198Y1009331D01*
G01X1521218Y1009365D02*
X1521204Y1009350D01*
G01X1521238Y1009370D02*
X1521218Y1009365D01*
G01X1521200Y1009337D02*
X1521201Y1009344D01*
G01X1521200Y1009332D02*
Y1009337D01*
G01X1521198Y1009331D02*
X1521200Y1009332D01*
G01Y1006187D02*
X1521201Y1006194D01*
G01X1521200Y1006183D02*
Y1006187D01*
G01X1521198Y1006181D02*
X1521200Y1006183D01*
G01Y1003037D02*
X1521201Y1003045D01*
G01X1521200Y1003033D02*
Y1003037D01*
G01X1521198Y1003031D02*
X1521200Y1003033D01*
G01Y999888D02*
X1521201Y999895D01*
G01X1521200Y999883D02*
Y999888D01*
G01X1521198Y999882D02*
X1521200Y999883D01*
G01Y996738D02*
X1521201Y996746D01*
G01X1521200Y996734D02*
Y996738D01*
G01X1521198Y996732D02*
X1521200Y996734D01*
G01Y993589D02*
X1521201Y993596D01*
G01X1521200Y993584D02*
Y993589D01*
G01X1521198Y993583D02*
X1521200Y993584D01*
G01Y990439D02*
X1521201Y990446D01*
G01X1521200Y990435D02*
Y990439D01*
G01X1521198Y990433D02*
X1521200Y990435D01*
G01X1522184Y1005058D02*
X1522185Y1005065D01*
G01X1522182Y1005051D02*
X1522184Y1005058D01*
G01X1522178Y1005044D02*
X1522182Y1005051D01*
G01X1522174Y1005039D02*
X1522178Y1005044D01*
G01X1522167Y1005034D02*
X1522174Y1005039D01*
G01X1522161Y1005031D02*
X1522167Y1005034D01*
G01X1522154Y1005029D02*
X1522161Y1005031D01*
G01X1522146Y1005028D02*
X1522154Y1005029D01*
G01X1522163Y989283D02*
X1522166Y989285D01*
G01X1522159Y989282D02*
X1522163Y989283D01*
G01X1522156Y989281D02*
X1522159Y989282D01*
G01X1522153Y989281D02*
X1522156D01*
G01X1522149Y989280D02*
X1522153Y989281D01*
G01X1522146Y989280D02*
X1522149D01*
G01X1521223Y990480D02*
X1521220Y990478D01*
G01X1521226Y990481D02*
X1521223Y990480D01*
G01X1521230Y990482D02*
X1521226Y990481D01*
G01X1521233Y990483D02*
X1521230Y990482D01*
G01X1521237Y990483D02*
X1521233D01*
G01X1521240D02*
X1521237D01*
G01X1522163Y992433D02*
X1522166Y992435D01*
G01X1522159Y992432D02*
X1522163Y992433D01*
G01X1522156Y992431D02*
X1522159Y992432D01*
G01X1522153Y992430D02*
X1522156Y992431D01*
G01X1522149Y992430D02*
X1522153D01*
G01X1522146D02*
X1522149D01*
G01X1521223Y993630D02*
X1521220Y993628D01*
G01X1521226Y993631D02*
X1521223Y993630D01*
G01X1521230Y993632D02*
X1521226Y993631D01*
G01X1521233Y993633D02*
X1521230Y993632D01*
G01X1521237Y993633D02*
X1521233D01*
G01X1521240D02*
X1521237D01*
G01X1522163Y995583D02*
X1522166Y995585D01*
G01X1522159Y995581D02*
X1522163Y995583D01*
G01X1522156Y995581D02*
X1522159D01*
G01X1522153Y995580D02*
X1522156Y995581D01*
G01X1522149Y995580D02*
X1522153D01*
G01X1522146Y995579D02*
X1522149Y995580D01*
G01X1521223Y996779D02*
X1521220Y996778D01*
G01X1521226Y996780D02*
X1521223Y996779D01*
G01X1521230Y996781D02*
X1521226Y996780D01*
G01X1521233Y996782D02*
X1521230Y996781D01*
G01X1521237Y996783D02*
X1521233Y996782D01*
G01X1521240Y996783D02*
X1521237D01*
G01X1522163Y998732D02*
X1522166Y998734D01*
G01X1522159Y998731D02*
X1522163Y998732D01*
G01X1522156Y998730D02*
X1522159Y998731D01*
G01X1522153Y998730D02*
X1522156D01*
G01X1522149Y998729D02*
X1522153Y998730D01*
G01X1522146Y998729D02*
X1522149D01*
G01X1521223Y999929D02*
X1521220Y999927D01*
G01X1521226Y999930D02*
X1521223Y999929D01*
G01X1521230Y999931D02*
X1521226Y999930D01*
G01X1521233Y999932D02*
X1521230Y999931D01*
G01X1521237Y999932D02*
X1521233D01*
G01X1521240D02*
X1521237D01*
G01X1522163Y1001882D02*
X1522166Y1001884D01*
G01X1522159Y1001881D02*
X1522163Y1001882D01*
G01X1522156Y1001880D02*
X1522159Y1001881D01*
G01X1522153Y1001879D02*
X1522156Y1001880D01*
G01X1522149Y1001879D02*
X1522153D01*
G01X1522146Y1001878D02*
X1522149Y1001879D01*
G01X1521223Y1003078D02*
X1521220Y1003077D01*
G01X1521226Y1003080D02*
X1521223Y1003078D01*
G01X1521230Y1003081D02*
X1521226Y1003080D01*
G01X1521233Y1003081D02*
X1521230D01*
G01X1521237Y1003082D02*
X1521233Y1003081D01*
G01X1521240Y1003082D02*
X1521237D01*
G01X1521223Y1006228D02*
X1521220Y1006226D01*
G01X1521226Y1006229D02*
X1521223Y1006228D01*
G01X1521230Y1006230D02*
X1521226Y1006229D01*
G01X1521233Y1006231D02*
X1521230Y1006230D01*
G01X1521237Y1006231D02*
X1521233D01*
G01X1521240D02*
X1521237D01*
G01X1522163Y1008181D02*
X1522166Y1008183D01*
G01X1522159Y1008180D02*
X1522163Y1008181D01*
G01X1522156Y1008179D02*
X1522159Y1008180D01*
G01X1522153Y1008178D02*
X1522156Y1008179D01*
G01X1522149Y1008178D02*
X1522153D01*
G01X1522146D02*
X1522149D01*
G01X1521223Y1009378D02*
X1521220Y1009376D01*
G01X1521226Y1009379D02*
X1521223Y1009378D01*
G01X1521230Y1009380D02*
X1521226Y1009379D01*
G01X1521233Y1009381D02*
X1521230Y1009380D01*
G01X1521237Y1009381D02*
X1521233D01*
G01X1521240D02*
X1521237D01*
G01X1522146Y1009375D02*
Y1009381D01*
G01X1522145Y1009371D02*
X1522146Y1009375D01*
G01X1522144Y1009370D02*
X1522145Y1009371D01*
G01X1522146Y1006226D02*
Y1006231D01*
G01X1522145Y1006222D02*
X1522146Y1006226D01*
G01X1522144Y1006220D02*
X1522145Y1006222D01*
G01X1522146Y1003076D02*
Y1003082D01*
G01X1522145Y1003072D02*
X1522146Y1003076D01*
G01X1522144Y1003071D02*
X1522145Y1003072D01*
G01X1522146Y999926D02*
Y999932D01*
G01X1522145Y999922D02*
X1522146Y999926D01*
G01X1522144Y999921D02*
X1522145Y999922D01*
G01X1522146Y996777D02*
Y996783D01*
G01X1522145Y996773D02*
X1522146Y996777D01*
G01X1522144Y996772D02*
X1522145Y996773D01*
G01X1522176Y990471D02*
X1522180Y990465D01*
G01X1522171Y990475D02*
X1522176Y990471D01*
G01X1522165Y990479D02*
X1522171Y990475D01*
G01X1522159Y990481D02*
X1522165Y990479D01*
G01X1522152Y990483D02*
X1522159Y990481D01*
G01X1522146Y990483D02*
X1522152D01*
G01X1522176Y993620D02*
X1522180Y993615D01*
G01X1522171Y993625D02*
X1522176Y993620D01*
G01X1522165Y993628D02*
X1522171Y993625D01*
G01X1522159Y993631D02*
X1522165Y993628D01*
G01X1522152Y993633D02*
X1522159Y993631D01*
G01X1522146Y993633D02*
X1522152D01*
G01X1522176Y996770D02*
X1522180Y996765D01*
G01X1522171Y996774D02*
X1522176Y996770D01*
G01X1522165Y996778D02*
X1522171Y996774D01*
G01X1522159Y996781D02*
X1522165Y996778D01*
G01X1522152Y996782D02*
X1522159Y996781D01*
G01X1522146Y996783D02*
X1522152Y996782D01*
G01X1522176Y999920D02*
X1522180Y999914D01*
G01X1522171Y999924D02*
X1522176Y999920D01*
G01X1522165Y999928D02*
X1522171Y999924D01*
G01X1522159Y999930D02*
X1522165Y999928D01*
G01X1522152Y999932D02*
X1522159Y999930D01*
G01X1522146Y999932D02*
X1522152D01*
G01X1522176Y1003069D02*
X1522180Y1003064D01*
G01X1522171Y1003074D02*
X1522176Y1003069D01*
G01X1522165Y1003077D02*
X1522171Y1003074D01*
G01X1522159Y1003080D02*
X1522165Y1003077D01*
G01X1522152Y1003081D02*
X1522159Y1003080D01*
G01X1522146Y1003082D02*
X1522152Y1003081D01*
G01X1522176Y1006219D02*
X1522180Y1006213D01*
G01X1522171Y1006223D02*
X1522176Y1006219D01*
G01X1522165Y1006227D02*
X1522171Y1006223D01*
G01X1522159Y1006230D02*
X1522165Y1006227D01*
G01X1522152Y1006231D02*
X1522159Y1006230D01*
G01X1522146Y1006231D02*
X1522152D01*
G01X1522176Y1009369D02*
X1522180Y1009363D01*
G01X1522171Y1009373D02*
X1522176Y1009369D01*
G01X1522165Y1009376D02*
X1522171Y1009373D01*
G01X1522159Y1009379D02*
X1522165Y1009376D01*
G01X1522152Y1009381D02*
X1522159Y1009379D01*
G01X1522146Y1009381D02*
X1522152D01*
G01X1521202Y989310D02*
X1521201Y989317D01*
G01X1521204Y989303D02*
X1521202Y989310D01*
G01X1521207Y989296D02*
X1521204Y989303D01*
G01X1521212Y989291D02*
X1521207Y989296D01*
G01X1521219Y989286D02*
X1521212Y989291D01*
G01X1521225Y989283D02*
X1521219Y989286D01*
G01X1521233Y989281D02*
X1521225Y989283D01*
G01X1521240Y989280D02*
X1521233Y989281D01*
G01X1521202Y992459D02*
X1521201Y992467D01*
G01X1521204Y992452D02*
X1521202Y992459D01*
G01X1521207Y992446D02*
X1521204Y992452D01*
G01X1521212Y992441D02*
X1521207Y992446D01*
G01X1521219Y992436D02*
X1521212Y992441D01*
G01X1521225Y992432D02*
X1521219Y992436D01*
G01X1521233Y992430D02*
X1521225Y992432D01*
G01X1521240Y992430D02*
X1521233D01*
G01X1521202Y995609D02*
X1521201Y995616D01*
G01X1521204Y995602D02*
X1521202Y995609D01*
G01X1521207Y995596D02*
X1521204Y995602D01*
G01X1521212Y995590D02*
X1521207Y995596D01*
G01X1521219Y995585D02*
X1521212Y995590D01*
G01X1521225Y995582D02*
X1521219Y995585D01*
G01X1521233Y995580D02*
X1521225Y995582D01*
G01X1521240Y995579D02*
X1521233Y995580D01*
G01X1521202Y998759D02*
X1521201Y998766D01*
G01X1521204Y998752D02*
X1521202Y998759D01*
G01X1521207Y998745D02*
X1521204Y998752D01*
G01X1521212Y998740D02*
X1521207Y998745D01*
G01X1521219Y998735D02*
X1521212Y998740D01*
G01X1521225Y998731D02*
X1521219Y998735D01*
G01X1521233Y998730D02*
X1521225Y998731D01*
G01X1521240Y998729D02*
X1521233Y998730D01*
G01X1521202Y1001908D02*
X1521201Y1001915D01*
G01X1521204Y1001901D02*
X1521202Y1001908D01*
G01X1521207Y1001895D02*
X1521204Y1001901D01*
G01X1521212Y1001889D02*
X1521207Y1001895D01*
G01X1521219Y1001885D02*
X1521212Y1001889D01*
G01X1521225Y1001881D02*
X1521219Y1001885D01*
G01X1521233Y1001879D02*
X1521225Y1001881D01*
G01X1521240Y1001878D02*
X1521233Y1001879D01*
G01X1521202Y1005058D02*
X1521201Y1005065D01*
G01X1521204Y1005051D02*
X1521202Y1005058D01*
G01X1521207Y1005044D02*
X1521204Y1005051D01*
G01X1521212Y1005039D02*
X1521207Y1005044D01*
G01X1521219Y1005034D02*
X1521212Y1005039D01*
G01X1521225Y1005031D02*
X1521219Y1005034D01*
G01X1521233Y1005029D02*
X1521225Y1005031D01*
G01X1521240Y1005028D02*
X1521233Y1005029D01*
G01X1521202Y1008207D02*
X1521201Y1008215D01*
G01X1521204Y1008200D02*
X1521202Y1008207D01*
G01X1521207Y1008194D02*
X1521204Y1008200D01*
G01X1521212Y1008189D02*
X1521207Y1008194D01*
G01X1521219Y1008184D02*
X1521212Y1008189D01*
G01X1521225Y1008180D02*
X1521219Y1008184D01*
G01X1521233Y1008178D02*
X1521225Y1008180D01*
G01X1521240Y1008178D02*
X1521233D01*
G01X1522155Y990471D02*
X1522164Y990467D01*
G01X1522144Y990472D02*
X1522155Y990471D01*
G01Y993620D02*
X1522164Y993617D01*
G01X1522144Y993622D02*
X1522155Y993620D01*
G01Y996770D02*
X1522164Y996766D01*
G01X1522144Y996772D02*
X1522155Y996770D01*
G01Y999920D02*
X1522164Y999916D01*
G01X1522144Y999921D02*
X1522155Y999920D01*
G01Y1003069D02*
X1522164Y1003065D01*
G01X1522144Y1003071D02*
X1522155Y1003069D01*
G01Y1006219D02*
X1522164Y1006215D01*
G01X1522144Y1006220D02*
X1522155Y1006219D01*
G01Y1009369D02*
X1522164Y1009365D01*
G01X1522144Y1009370D02*
X1522155Y1009369D01*
G01X1522185Y1009337D02*
Y1009344D01*
G01Y1009332D02*
Y1009337D01*
G01X1522184Y1009331D02*
X1522185Y1009332D01*
G01Y1006187D02*
Y1006194D01*
G01Y1006183D02*
Y1006187D01*
G01X1522184Y1006181D02*
X1522185Y1006183D01*
G01Y1003038D02*
Y1003045D01*
G01Y1003033D02*
Y1003038D01*
G01X1522184Y1003031D02*
X1522185Y1003033D01*
G01Y999888D02*
Y999895D01*
G01Y999883D02*
Y999888D01*
G01X1522184Y999882D02*
X1522185Y999883D01*
G01Y996739D02*
Y996746D01*
G01Y996734D02*
Y996739D01*
G01X1522184Y996732D02*
X1522185Y996734D01*
G01Y993589D02*
Y993596D01*
G01Y993584D02*
Y993589D01*
G01X1522184Y993583D02*
X1522185Y993584D01*
G01Y990439D02*
Y990446D01*
G01Y990435D02*
Y990439D01*
G01X1522184Y990433D02*
X1522185Y990435D01*
G01X1521200Y998774D02*
X1521201Y998766D01*
G01X1521200Y998778D02*
Y998774D01*
G01X1521198Y998775D02*
X1521200Y998778D01*
G01Y992474D02*
X1521201Y992467D01*
G01X1521200Y992479D02*
Y992474D01*
G01X1521198Y992477D02*
X1521200Y992479D01*
G01X1522146Y993627D02*
Y993633D01*
G01X1522145Y993623D02*
X1522146Y993627D01*
G01X1522144Y993622D02*
X1522145Y993623D01*
G01X1522146Y990478D02*
Y990483D01*
G01X1522145Y990474D02*
X1522146Y990478D01*
G01X1522144Y990472D02*
X1522145Y990474D01*
G01X1521201Y992470D02*
Y992467D01*
G01X1521202Y992464D02*
X1521201Y992470D01*
G01X1521214Y992449D02*
X1521202Y992464D01*
G01X1521239Y992441D02*
X1521214Y992449D01*
G01X1521201Y995620D02*
Y995616D01*
G01X1521202Y995614D02*
X1521201Y995620D01*
G01X1521214Y995599D02*
X1521202Y995614D01*
G01X1521238Y995591D02*
X1521214Y995599D01*
G01X1521201Y1001919D02*
Y1001915D01*
G01X1521202Y1001913D02*
X1521201Y1001919D01*
G01X1521214Y1001898D02*
X1521202Y1001913D01*
G01X1521238Y1001890D02*
X1521214Y1001898D01*
G01X1521201Y1005069D02*
Y1005065D01*
G01X1521202Y1005063D02*
X1521201Y1005069D01*
G01X1521214Y1005048D02*
X1521202Y1005063D01*
G01X1521238Y1005039D02*
X1521214Y1005048D01*
G01X1521201Y989321D02*
Y989317D01*
G01X1521202Y989315D02*
X1521201Y989321D01*
G01X1521214Y989300D02*
X1521202Y989315D01*
G01X1521238Y989291D02*
X1521214Y989300D01*
G01X1521201Y1008219D02*
Y1008215D01*
G01X1521202Y1008213D02*
X1521201Y1008219D01*
G01X1521214Y1008197D02*
X1521202Y1008213D01*
G01X1521238Y1008189D02*
X1521214Y1008197D01*
G01Y1009361D02*
X1521238Y1009370D01*
G01X1521203Y1009347D02*
X1521214Y1009361D01*
G01X1521201Y1009340D02*
X1521203Y1009347D01*
G01X1521214Y1006212D02*
X1521238Y1006220D01*
G01X1521203Y1006197D02*
X1521214Y1006212D01*
G01X1521201Y1006191D02*
X1521203Y1006197D01*
G01X1521214Y1003062D02*
X1521238Y1003071D01*
G01X1521203Y1003048D02*
X1521214Y1003062D01*
G01X1521201Y1003041D02*
X1521203Y1003048D01*
G01X1521214Y999913D02*
X1521238Y999921D01*
G01X1521203Y999898D02*
X1521214Y999913D01*
G01X1521201Y999891D02*
X1521203Y999898D01*
G01X1521214Y996763D02*
X1521238Y996772D01*
G01X1521203Y996748D02*
X1521214Y996763D01*
G01X1521201Y996742D02*
X1521203Y996748D01*
G01X1521214Y993613D02*
X1521238Y993622D01*
G01X1521203Y993599D02*
X1521214Y993613D01*
G01X1521201Y993592D02*
X1521203Y993599D01*
G01X1521214Y990464D02*
X1521238Y990472D01*
G01X1521203Y990449D02*
X1521214Y990464D01*
G01X1521201Y990443D02*
X1521203Y990449D01*
G01X1521201Y998770D02*
Y998766D01*
G01X1521202Y998764D02*
X1521201Y998770D01*
G01X1521213Y998750D02*
X1521202Y998764D01*
G01X1521235Y998740D02*
X1521213Y998750D01*
G01X1522154Y990471D02*
X1522144Y990472D01*
G01X1522163Y990468D02*
X1522154Y990471D01*
G01X1522170Y990463D02*
X1522163Y990468D01*
G01X1522154Y993621D02*
X1522144Y993622D01*
G01X1522163Y993618D02*
X1522154Y993621D01*
G01X1522170Y993612D02*
X1522163Y993618D01*
G01X1521200Y1001923D02*
X1521201Y1001916D01*
G01X1521200Y1001928D02*
Y1001923D01*
G01Y1001918D02*
Y1001928D01*
G01X1521241Y1009554D02*
X1521240Y1009567D01*
G01X1521238Y1009541D02*
X1521241Y1009554D01*
G01X1521238Y1009528D02*
Y1009541D01*
G01X1521241Y1006405D02*
X1521240Y1006417D01*
G01X1521238Y1006392D02*
X1521241Y1006405D01*
G01X1521238Y1006378D02*
Y1006392D01*
G01X1521241Y1003255D02*
X1521240Y1003268D01*
G01X1521238Y1003242D02*
X1521241Y1003255D01*
G01X1521238Y1003228D02*
Y1003242D01*
G01X1521241Y1000106D02*
X1521240Y1000118D01*
G01X1521238Y1000093D02*
X1521241Y1000106D01*
G01X1521238Y1000079D02*
Y1000093D01*
G01X1521241Y996956D02*
X1521240Y996969D01*
G01X1521238Y996943D02*
X1521241Y996956D01*
G01X1521238Y996929D02*
Y996943D01*
G01X1521241Y993806D02*
X1521240Y993819D01*
G01X1521238Y993793D02*
X1521241Y993806D01*
G01X1521238Y993780D02*
Y993793D01*
G01X1521241Y990657D02*
X1521240Y990669D01*
G01X1521238Y990644D02*
X1521241Y990657D01*
G01X1521238Y990630D02*
Y990644D01*
G01X1521200Y1008222D02*
X1521201Y1008215D01*
G01X1521200Y1008227D02*
Y1008222D01*
G01Y1008219D02*
Y1008227D01*
G01X1521238Y1008017D02*
X1521237Y1008031D01*
G01X1521241Y1008005D02*
X1521238Y1008017D01*
G01X1521240Y1007992D02*
X1521241Y1008005D01*
G01X1521238Y1004868D02*
X1521237Y1004881D01*
G01X1521241Y1004855D02*
X1521238Y1004868D01*
G01X1521240Y1004843D02*
X1521241Y1004855D01*
G01X1521238Y1001718D02*
X1521237Y1001732D01*
G01X1521241Y1001706D02*
X1521238Y1001718D01*
G01X1521240Y1001693D02*
X1521241Y1001706D01*
G01X1521238Y998569D02*
X1521237Y998582D01*
G01X1521241Y998556D02*
X1521238Y998569D01*
G01X1521240Y998543D02*
X1521241Y998556D01*
G01X1521238Y995419D02*
X1521237Y995433D01*
G01X1521241Y995406D02*
X1521238Y995419D01*
G01X1521240Y995394D02*
X1521241Y995406D01*
G01X1521238Y992269D02*
X1521237Y992283D01*
G01X1521241Y992257D02*
X1521238Y992269D01*
G01X1521240Y992244D02*
X1521241Y992257D01*
G01X1521238Y989120D02*
X1521237Y989133D01*
G01X1521241Y989107D02*
X1521238Y989120D01*
G01X1521240Y989094D02*
X1521241Y989107D01*
G01X1522148Y1009541D02*
X1522149Y1009528D01*
G01X1522145Y1009554D02*
X1522148Y1009541D01*
G01X1522146Y1009567D02*
X1522145Y1009554D01*
G01X1522148Y1006392D02*
X1522149Y1006378D01*
G01X1522145Y1006405D02*
X1522148Y1006392D01*
G01X1522146Y1006417D02*
X1522145Y1006405D01*
G01X1522148Y1003242D02*
X1522149Y1003228D01*
G01X1522145Y1003255D02*
X1522148Y1003242D01*
G01X1522146Y1003268D02*
X1522145Y1003255D01*
G01X1522148Y1000093D02*
X1522149Y1000079D01*
G01X1522145Y1000106D02*
X1522148Y1000093D01*
G01X1522146Y1000118D02*
X1522145Y1000106D01*
G01X1522148Y996943D02*
X1522149Y996929D01*
G01X1522145Y996956D02*
X1522148Y996943D01*
G01X1522146Y996969D02*
X1522145Y996956D01*
G01X1522148Y993793D02*
X1522149Y993780D01*
G01X1522145Y993806D02*
X1522148Y993793D01*
G01X1522146Y993819D02*
X1522145Y993806D01*
G01X1522148Y990644D02*
X1522149Y990630D01*
G01X1522145Y990657D02*
X1522148Y990644D01*
G01X1522146Y990669D02*
X1522145Y990657D01*
G01X1521200Y995624D02*
X1521201Y995617D01*
G01X1521200Y995628D02*
Y995624D01*
G01X1521199Y995621D02*
X1521200Y995628D01*
G01Y1005073D02*
X1521201Y1005065D01*
G01X1521200Y1005077D02*
Y1005073D01*
G01X1521199Y1005070D02*
X1521200Y1005077D01*
G01X1522145Y1008005D02*
X1522146Y1007992D01*
G01X1522148Y1008017D02*
X1522145Y1008005D01*
G01X1522149Y1008031D02*
X1522148Y1008017D01*
G01X1522145Y1004855D02*
X1522146Y1004843D01*
G01X1522148Y1004868D02*
X1522145Y1004855D01*
G01X1522149Y1004881D02*
X1522148Y1004868D01*
G01X1522145Y1001706D02*
X1522146Y1001693D01*
G01X1522148Y1001718D02*
X1522145Y1001706D01*
G01X1522149Y1001732D02*
X1522148Y1001718D01*
G01X1522145Y998556D02*
X1522146Y998543D01*
G01X1522148Y998569D02*
X1522145Y998556D01*
G01X1522149Y998582D02*
X1522148Y998569D01*
G01X1522145Y995406D02*
X1522146Y995394D01*
G01X1522148Y995419D02*
X1522145Y995406D01*
G01X1522149Y995433D02*
X1522148Y995419D01*
G01X1522145Y992257D02*
X1522146Y992244D01*
G01X1522148Y992269D02*
X1522145Y992257D01*
G01X1522149Y992283D02*
X1522148Y992269D01*
G01X1522145Y989107D02*
X1522146Y989094D01*
G01X1522148Y989120D02*
X1522145Y989107D01*
G01X1522149Y989133D02*
X1522148Y989120D01*
G01X1521200Y989325D02*
X1521201Y989317D01*
G01X1521200Y989329D02*
Y989325D01*
G01X1521199Y989323D02*
X1521200Y989329D01*
G01X1522154Y996770D02*
X1522144Y996772D01*
G01X1522162Y996767D02*
X1522154Y996770D01*
G01X1522170Y996762D02*
X1522162Y996767D01*
G01X1522154Y999920D02*
X1522144Y999921D01*
G01X1522163Y999917D02*
X1522154Y999920D01*
G01X1522170Y999911D02*
X1522163Y999917D01*
G01X1522154Y1003070D02*
X1522144Y1003071D01*
G01X1522163Y1003067D02*
X1522154Y1003070D01*
G01X1522170Y1003061D02*
X1522163Y1003067D01*
G01X1522154Y1006219D02*
X1522144Y1006220D01*
G01X1522163Y1006216D02*
X1522154Y1006219D01*
G01X1522170Y1006211D02*
X1522163Y1006216D01*
G01X1522154Y1009369D02*
X1522144Y1009370D01*
G01X1522163Y1009366D02*
X1522154Y1009369D01*
G01X1522170Y1009360D02*
X1522163Y1009366D01*
G01X1521240Y989286D02*
Y989280D01*
G01X1521239Y989290D02*
X1521240Y989286D01*
G01X1521238Y989291D02*
X1521239Y989290D01*
G01X1521240Y992436D02*
Y992430D01*
G01X1521239Y992440D02*
X1521240Y992436D01*
G01X1521238Y992441D02*
X1521239Y992440D01*
G01X1521240Y995585D02*
Y995579D01*
G01X1521239Y995589D02*
X1521240Y995585D01*
G01X1521238Y995591D02*
X1521239Y995589D01*
G01X1521240Y998735D02*
Y998729D01*
G01X1521239Y998739D02*
X1521240Y998735D01*
G01X1521238Y998740D02*
X1521239Y998739D01*
G01X1521240Y1001885D02*
Y1001878D01*
G01X1521239Y1001889D02*
X1521240Y1001885D01*
G01X1521238Y1001890D02*
X1521239Y1001889D01*
G01X1521240Y1005034D02*
Y1005028D01*
G01X1521239Y1005038D02*
X1521240Y1005034D01*
G01X1521238Y1005039D02*
X1521239Y1005038D01*
G01X1521240Y1008184D02*
Y1008178D01*
G01X1521239Y1008188D02*
X1521240Y1008184D01*
G01X1521238Y1008189D02*
X1521239Y1008188D01*
G01X1522178Y996754D02*
X1522170Y996762D01*
G01X1522182Y996743D02*
X1522178Y996754D01*
G01X1522184Y996732D02*
X1522182Y996743D01*
G01X1522178Y990454D02*
X1522170Y990463D01*
G01X1522182Y990444D02*
X1522178Y990454D01*
G01X1522184Y990433D02*
X1522182Y990444D01*
G01X1522178Y993604D02*
X1522170Y993612D01*
G01X1522182Y993594D02*
X1522178Y993604D01*
G01X1522184Y993583D02*
X1522182Y993594D01*
G01X1522178Y999903D02*
X1522170Y999911D01*
G01X1522182Y999893D02*
X1522178Y999903D01*
G01X1522184Y999882D02*
X1522182Y999893D01*
G01X1522178Y1003053D02*
X1522170Y1003061D01*
G01X1522182Y1003043D02*
X1522178Y1003053D01*
G01X1522184Y1003031D02*
X1522182Y1003043D01*
G01X1522178Y1006202D02*
X1522170Y1006211D01*
G01X1522182Y1006192D02*
X1522178Y1006202D01*
G01X1522184Y1006181D02*
X1522182Y1006192D01*
G01X1522178Y1009352D02*
X1522170Y1009360D01*
G01X1522182Y1009342D02*
X1522178Y1009352D01*
G01X1522184Y1009331D02*
X1522182Y1009342D01*
G01X1521224Y992443D02*
X1521238Y992441D01*
G01X1521212Y992450D02*
X1521224Y992443D01*
G01X1521200Y992469D02*
X1521212Y992450D01*
G01X1521224Y1001892D02*
X1521238Y1001890D01*
G01X1521212Y1001900D02*
X1521224Y1001892D01*
G01X1521200Y1001918D02*
X1521212Y1001900D01*
G01X1521223Y995593D02*
X1521238Y995591D01*
G01X1521211Y995601D02*
X1521223Y995593D01*
G01X1521199Y995621D02*
X1521211Y995601D01*
G01X1521223Y1005042D02*
X1521238Y1005039D01*
G01X1521211Y1005050D02*
X1521223Y1005042D01*
G01X1521199Y1005070D02*
X1521211Y1005050D01*
G01X1522185Y989325D02*
Y989317D01*
G01X1522184Y989329D02*
X1522185Y989325D01*
G01X1522183Y989331D02*
X1522184Y989329D01*
G01X1522185Y992474D02*
Y992467D01*
G01X1522184Y992479D02*
X1522185Y992474D01*
G01X1522183Y992480D02*
X1522184Y992479D01*
G01X1522185Y995624D02*
Y995616D01*
G01X1522184Y995628D02*
X1522185Y995624D01*
G01X1522183Y995630D02*
X1522184Y995628D01*
G01X1522185Y998774D02*
Y998766D01*
G01X1522184Y998778D02*
X1522185Y998774D01*
G01X1522183Y998780D02*
X1522184Y998778D01*
G01X1522185Y1001923D02*
Y1001915D01*
G01X1522184Y1001928D02*
X1522185Y1001923D01*
G01X1522183Y1001929D02*
X1522184Y1001928D01*
G01X1522185Y1005073D02*
Y1005065D01*
G01X1522184Y1005077D02*
X1522185Y1005073D01*
G01X1522183Y1005079D02*
X1522184Y1005077D01*
G01X1522185Y1008222D02*
Y1008215D01*
G01X1522184Y1008227D02*
X1522185Y1008222D01*
G01X1522183Y1008228D02*
X1522184Y1008227D01*
G01X1521223Y1008192D02*
X1521238Y1008189D01*
G01X1521211Y1008200D02*
X1521223Y1008192D01*
G01X1521199Y1008220D02*
X1521211Y1008200D01*
G01X1521223Y989294D02*
X1521238Y989291D01*
G01X1521210Y989303D02*
X1521223Y989294D01*
G01X1521199Y989323D02*
X1521210Y989303D01*
G01X1522184Y990453D02*
X1522185Y990446D01*
G01X1522183Y990459D02*
X1522184Y990453D01*
G01X1522180Y990465D02*
X1522183Y990459D01*
G01X1522184Y993603D02*
X1522185Y993596D01*
G01X1522183Y993609D02*
X1522184Y993603D01*
G01X1522180Y993615D02*
X1522183Y993609D01*
G01X1522184Y996752D02*
X1522185Y996746D01*
G01X1522183Y996759D02*
X1522184Y996752D01*
G01X1522180Y996765D02*
X1522183Y996759D01*
G01X1522184Y999902D02*
X1522185Y999895D01*
G01X1522183Y999908D02*
X1522184Y999902D01*
G01X1522180Y999914D02*
X1522183Y999908D01*
G01X1522184Y1003052D02*
X1522185Y1003045D01*
G01X1522183Y1003058D02*
X1522184Y1003052D01*
G01X1522180Y1003064D02*
X1522183Y1003058D01*
G01X1522184Y1006201D02*
X1522185Y1006194D01*
G01X1522183Y1006207D02*
X1522184Y1006201D01*
G01X1522180Y1006213D02*
X1522183Y1006207D01*
G01X1522184Y1009351D02*
X1522185Y1009344D01*
G01X1522183Y1009357D02*
X1522184Y1009351D01*
G01X1522180Y1009363D02*
X1522183Y1009357D01*
G01X1522146Y989286D02*
Y989280D01*
G01X1522145Y989290D02*
X1522146Y989286D01*
G01X1522144Y989291D02*
X1522145Y989290D01*
G01X1522146Y992436D02*
Y992430D01*
G01X1522145Y992439D02*
X1522146Y992436D01*
G01X1522144Y992441D02*
X1522145Y992439D01*
G01X1522146Y995585D02*
Y995579D01*
G01X1522145Y995589D02*
X1522146Y995585D01*
G01X1522144Y995591D02*
X1522145Y995589D01*
G01X1522146Y998735D02*
Y998729D01*
G01X1522145Y998739D02*
X1522146Y998735D01*
G01X1522144Y998740D02*
X1522145Y998739D01*
G01X1522146Y1001885D02*
Y1001878D01*
G01X1522145Y1001888D02*
X1522146Y1001885D01*
G01X1522144Y1001890D02*
X1522145Y1001888D01*
G01X1522146Y1008184D02*
Y1008178D01*
G01X1522145Y1008187D02*
X1522146Y1008184D01*
G01X1522144Y1008189D02*
X1522145Y1008187D01*
G01X1521219Y998745D02*
X1521238Y998740D01*
G01X1521205Y998757D02*
X1521219Y998745D01*
G01X1521198Y998775D02*
X1521205Y998757D01*
G01X1522144Y1005039D02*
X1522148Y1005028D01*
G01X1522185Y990435D02*
Y990446D01*
G01Y993585D02*
Y993596D01*
G01Y996734D02*
Y996746D01*
G01Y999884D02*
Y999895D01*
G01Y1003033D02*
Y1003045D01*
G01Y1006183D02*
Y1006194D01*
G01Y1009333D02*
Y1009344D01*
G01X1525591Y953012D02*
Y1085650D01*
G01X1522638Y1090571D02*
Y1011535D01*
G01X1522185Y1008031D02*
Y1009528D01*
G01Y1004881D02*
Y1006378D01*
G01Y1001732D02*
Y1003228D01*
G01Y998582D02*
Y1000079D01*
G01Y995433D02*
Y996929D01*
G01Y992283D02*
Y993780D01*
G01Y989133D02*
Y990630D01*
G01X1522146Y989280D02*
Y989133D01*
G01Y990630D02*
Y990483D01*
G01Y995579D02*
Y995432D01*
G01Y992430D02*
Y992283D01*
G01Y993780D02*
Y993633D01*
G01Y998729D02*
Y998582D01*
G01Y1000079D02*
Y999932D01*
G01Y996930D02*
Y996783D01*
G01Y1001878D02*
Y1001731D01*
G01Y1003229D02*
Y1003082D01*
G01Y1008178D02*
Y1008031D01*
G01Y1009528D02*
Y1009381D01*
G01Y1005028D02*
Y1004881D01*
G01Y1006378D02*
Y1006231D01*
G01X1521240Y1008031D02*
Y1008178D01*
G01Y1009381D02*
Y1009528D01*
G01Y1004881D02*
Y1005028D01*
G01Y1006231D02*
Y1006378D01*
G01Y1001731D02*
Y1001878D01*
G01Y1003082D02*
Y1003229D01*
G01Y998582D02*
Y998729D01*
G01Y999932D02*
Y1000079D01*
G01Y996783D02*
Y996930D01*
G01Y995432D02*
Y995579D01*
G01Y992283D02*
Y992430D01*
G01Y993633D02*
Y993780D01*
G01Y989133D02*
Y989280D01*
G01Y990483D02*
Y990630D01*
G01X1521201D02*
Y989134D01*
G01Y993780D02*
Y992283D01*
G01Y1000079D02*
Y998583D01*
G01Y996929D02*
Y995433D01*
G01Y1003228D02*
Y1001732D01*
G01Y1009528D02*
Y1008031D01*
G01Y1006378D02*
Y1004882D01*
G01X1520020Y990472D02*
Y989291D01*
G01Y996772D02*
Y995591D01*
G01Y993622D02*
Y992441D01*
G01Y999921D02*
Y998740D01*
G01Y1003071D02*
Y1001890D01*
G01Y1009370D02*
Y1008189D01*
G01Y1006220D02*
Y1005039D01*
G01X1519685Y1011535D02*
Y987126D01*
G01X1519291D02*
Y1011535D01*
G01X1516260Y1008189D02*
Y1009370D01*
G01Y1005039D02*
Y1006220D01*
G01Y1001890D02*
Y1003071D01*
G01Y998740D02*
Y999921D01*
G01Y995591D02*
Y996772D01*
G01Y992441D02*
Y993622D01*
G01Y989291D02*
Y990472D01*
G01X1522185Y1008215D02*
Y1008226D01*
G01Y1005065D02*
Y1005076D01*
G01Y1001916D02*
Y1001926D01*
G01Y998766D02*
Y998777D01*
G01Y995617D02*
Y995627D01*
G01Y992467D02*
Y992478D01*
G01Y989317D02*
Y989328D01*
G01X1521087Y1008228D02*
X1521199Y1008220D01*
G01X1521198Y998775D02*
X1521087Y998780D01*
G01X1521198Y992477D02*
X1521087Y992480D01*
G01X1521198Y1001926D02*
X1521087Y1001929D01*
G01X1522638Y1011535D02*
X1519291D01*
G01X1522146Y1009567D02*
X1521240D01*
G01X1522185Y1009528D02*
X1521201D01*
G01X1522144Y1009370D02*
X1516260D01*
G01Y1009331D02*
X1522184D01*
G01X1522183Y1008228D02*
X1516260D01*
G01X1522144Y1008189D02*
X1516260D01*
G01X1521201Y1008031D02*
X1522185D01*
G01X1521240Y1007992D02*
X1522146D01*
G01Y1006417D02*
X1521240D01*
G01X1522185Y1006378D02*
X1521201D01*
G01X1522144Y1006220D02*
X1516260D01*
G01Y1006181D02*
X1522184D01*
G01X1522183Y1005079D02*
X1516260D01*
G01X1522144Y1005039D02*
X1516260D01*
G01X1521201Y1004882D02*
X1522185D01*
G01X1521240Y1004843D02*
X1522146D01*
G01Y1003268D02*
X1521240D01*
G01X1522185Y1003228D02*
X1521201D01*
G01X1522144Y1003071D02*
X1516260D01*
G01Y1003031D02*
X1522184D01*
G01X1520454Y1001929D02*
X1520020D01*
G01X1522183D02*
X1516260D01*
G01X1522144Y1001890D02*
X1516260D01*
G01X1521201Y1001732D02*
X1522185D01*
G01X1521240Y1001693D02*
X1522146D01*
G01Y1000118D02*
X1521240D01*
G01X1522185Y1000079D02*
X1521201D01*
G01X1522144Y999921D02*
X1516260D01*
G01Y999882D02*
X1522184D01*
G01X1520454Y998780D02*
X1520020D01*
G01X1522183D02*
X1516260D01*
G01X1522144Y998740D02*
X1516260D01*
G01X1521201Y998583D02*
X1522185D01*
G01X1521240Y998543D02*
X1522146D01*
G01Y996969D02*
X1521240D01*
G01X1522185Y996929D02*
X1521201D01*
G01X1522144Y996772D02*
X1516260D01*
G01Y996732D02*
X1522184D01*
G01X1522183Y995630D02*
X1516260D01*
G01X1522144Y995591D02*
X1516260D01*
G01X1521201Y995433D02*
X1522185D01*
G01X1521240Y995394D02*
X1522146D01*
G01Y993819D02*
X1521240D01*
G01X1522185Y993780D02*
X1521201D01*
G01X1522144Y993622D02*
X1516260D01*
G01Y993583D02*
X1522184D01*
G01X1520454Y992480D02*
X1520020D01*
G01X1522183D02*
X1516260D01*
G01X1522144Y992441D02*
X1516260D01*
G01X1521201Y992283D02*
X1522185D01*
G01X1521240Y992244D02*
X1522146D01*
G01Y990669D02*
X1521240D01*
G01X1522185Y990630D02*
X1521201D01*
G01X1522144Y990472D02*
X1516260D01*
G01Y990433D02*
X1522184D01*
G01X1522183Y989331D02*
X1516260D01*
G01X1522144Y989291D02*
X1516260D01*
G01X1521201Y989134D02*
X1522185D01*
G01X1521240Y989094D02*
X1522146D01*
G01X1522638Y987126D02*
X1519291D01*
G01X1531102Y953012D02*
X1525591D01*
G01X1526772Y1108602D02*
G03X1526181Y1108012I0J-591D01*
G01X1528937Y1106831D02*
G03Y1104862I0J-985D01*
G01X1521260Y1109390D02*
G03X1519291Y1107421I0J-1969D01*
G01X1527559Y1098917D02*
G03X1526378Y1097736I0J-1181D01*
G01X1532008Y1093642D02*
G03I-1890J0D01*
G01X1532480D02*
G03I-2362J0D01*
G01X1528937Y1094232D02*
X1526627Y1098461D01*
G01X1524409Y1086831D02*
X1525591Y1085650D01*
G01X1519291Y1091673D02*
X1522638Y1088327D01*
G01X1528937Y1092539D02*
Y1094232D01*
G01X1526378Y1089193D02*
Y1097736D01*
G01X1526181Y1101909D02*
Y1108012D01*
G01X1519291Y1107421D02*
Y1091673D01*
G01X1538976Y1109390D02*
X1521260D01*
G01X1533465Y1108602D02*
X1526772D01*
G01X1531299Y1106831D02*
X1528937D01*
G01Y1104862D02*
X1531299D01*
G01X1534055Y1103484D02*
X1526181D01*
G01Y1101909D02*
X1534055D01*
G01X1540945Y1098957D02*
X1519291D01*
G01X1527559Y1098917D02*
X1532677D01*
G01X1528937Y1094232D02*
X1531299D01*
G01X1528937Y1092539D02*
X1531299D01*
G01X1522638Y1090571D02*
X1537008D01*
G01X1522638Y1089193D02*
X1526378D01*
G01X1522638Y1088327D02*
X1537598D01*
G01X1524409Y1086831D02*
X1532283D01*
G01X1525591Y1085650D02*
X1531102D01*
G01X1527633Y1090571D02*
X1528937Y1092539D01*
G01X1532996Y1170224D02*
G03X1566807I16906J-13531D01*
G01X1532996D02*
G03X1566807I16906J-13531D01*
G01X1443701Y1519685D02*
G03X1439764Y1515748I0J-3937D01*
G01X1469685Y1503937D02*
G03Y1496063I0J-3937D01*
G01X1451575D02*
G03Y1503937I0J3937D01*
G01X1443701Y1519685D02*
X1632677D01*
G01X1451575Y1503937D02*
X1439764D01*
G01X1606693D02*
X1469685D01*
G01X1439764Y1515748D02*
Y1503937D01*
G01X1606693D02*
X1469685D01*
G01X1451575D02*
X1439764D01*
G01X1443701Y1519685D02*
G03X1439764Y1515748I0J-3937D01*
G01X1469685Y1503937D02*
G03Y1496063I0J-3937D01*
G01X1451575D02*
G03Y1503937I0J3937D01*
G01X1640551Y1496063D02*
X1435827D01*
G01X1439764Y1515748D02*
Y1503937D01*
G01X1443701Y1519685D02*
X1632677D01*
G01X1640551Y1496063D02*
X1435827D01*
G01X1576613Y-369410D02*
Y-388347D01*
G01X1535598Y51999D02*
X1535609Y51984D01*
G01X1535573Y52008D02*
X1535598Y51999D01*
G01Y56999D02*
X1535609Y56984D01*
G01X1535573Y57008D02*
X1535598Y56999D01*
G01Y61999D02*
X1535609Y61984D01*
G01X1535573Y62008D02*
X1535598Y61999D01*
G01Y66999D02*
X1535609Y66984D01*
G01X1535573Y67008D02*
X1535598Y66999D01*
G01Y71999D02*
X1535609Y71984D01*
G01X1535573Y72008D02*
X1535598Y71999D01*
G01Y76999D02*
X1535609Y76984D01*
G01X1535573Y77008D02*
X1535598Y76999D01*
G01Y81999D02*
X1535609Y81984D01*
G01X1535573Y82008D02*
X1535598Y81999D01*
G01X1535611Y51975D02*
X1535610Y51982D01*
G01X1535611Y51970D02*
Y51975D01*
G01X1535613Y51969D02*
X1535611Y51970D01*
G01Y56975D02*
X1535610Y56982D01*
G01X1535611Y56970D02*
Y56975D01*
G01X1535613Y56969D02*
X1535611Y56970D01*
G01Y61975D02*
X1535610Y61982D01*
G01X1535611Y61970D02*
Y61975D01*
G01X1535613Y61969D02*
X1535611Y61970D01*
G01Y66975D02*
X1535610Y66982D01*
G01X1535611Y66970D02*
Y66975D01*
G01X1535613Y66969D02*
X1535611Y66970D01*
G01Y71975D02*
X1535610Y71982D01*
G01X1535611Y71970D02*
Y71975D01*
G01X1535613Y71969D02*
X1535611Y71970D01*
G01Y76975D02*
X1535610Y76982D01*
G01X1535611Y76970D02*
Y76975D01*
G01X1535613Y76969D02*
X1535611Y76970D01*
G01Y81975D02*
X1535610Y81982D01*
G01X1535611Y81970D02*
Y81975D01*
G01X1535613Y81969D02*
X1535611Y81970D01*
G01X1534626Y52015D02*
Y52024D01*
G01X1534627Y52009D02*
X1534626Y52015D01*
G01X1534628Y52008D02*
X1534627Y52009D01*
G01X1534626Y57015D02*
Y57024D01*
G01X1534627Y57009D02*
X1534626Y57015D01*
G01X1534628Y57008D02*
X1534627Y57009D01*
G01X1534626Y62015D02*
Y62024D01*
G01X1534627Y62009D02*
X1534626Y62015D01*
G01X1534628Y62008D02*
X1534627Y62009D01*
G01X1534626Y67015D02*
Y67024D01*
G01X1534627Y67009D02*
X1534626Y67015D01*
G01X1534628Y67008D02*
X1534627Y67009D01*
G01X1534626Y72015D02*
Y72024D01*
G01X1534627Y72009D02*
X1534626Y72015D01*
G01X1534628Y72008D02*
X1534627Y72009D01*
G01X1534626Y77015D02*
Y77024D01*
G01X1534627Y77009D02*
X1534626Y77015D01*
G01X1534628Y77008D02*
X1534627Y77009D01*
G01X1534626Y82015D02*
Y82024D01*
G01X1534627Y82009D02*
X1534626Y82015D01*
G01X1534628Y82008D02*
X1534627Y82009D01*
G01X1535602Y52152D02*
X1535610Y52125D01*
G01X1535593Y52178D02*
X1535602Y52152D01*
G01X1535581Y52205D02*
X1535593Y52178D01*
G01X1535602Y57152D02*
X1535610Y57125D01*
G01X1535593Y57178D02*
X1535602Y57152D01*
G01X1535581Y57205D02*
X1535593Y57178D01*
G01X1535602Y62152D02*
X1535610Y62125D01*
G01X1535593Y62178D02*
X1535602Y62152D01*
G01X1535581Y62205D02*
X1535593Y62178D01*
G01X1535602Y67152D02*
X1535610Y67125D01*
G01X1535593Y67178D02*
X1535602Y67152D01*
G01X1535581Y67205D02*
X1535593Y67178D01*
G01X1535602Y72152D02*
X1535610Y72125D01*
G01X1535593Y72178D02*
X1535602Y72152D01*
G01X1535581Y72205D02*
X1535593Y72178D01*
G01X1535602Y77152D02*
X1535610Y77125D01*
G01X1535593Y77178D02*
X1535602Y77152D01*
G01X1535581Y77205D02*
X1535593Y77178D01*
G01X1535602Y82152D02*
X1535610Y82125D01*
G01X1535593Y82178D02*
X1535602Y82152D01*
G01X1535581Y82205D02*
X1535593Y82178D01*
G01Y52003D02*
X1535574Y52008D01*
G01X1535607Y51988D02*
X1535593Y52003D01*
G01X1535613Y51969D02*
X1535607Y51988D01*
G01X1535593Y57003D02*
X1535574Y57008D01*
G01X1535607Y56988D02*
X1535593Y57003D01*
G01X1535613Y56969D02*
X1535607Y56988D01*
G01X1535593Y62003D02*
X1535574Y62008D01*
G01X1535607Y61988D02*
X1535593Y62003D01*
G01X1535613Y61969D02*
X1535607Y61988D01*
G01X1535593Y67003D02*
X1535574Y67008D01*
G01X1535607Y66988D02*
X1535593Y67003D01*
G01X1535613Y66969D02*
X1535607Y66988D01*
G01X1535593Y72003D02*
X1535574Y72008D01*
G01X1535607Y71988D02*
X1535593Y72003D01*
G01X1535613Y71969D02*
X1535607Y71988D01*
G01X1535593Y77003D02*
X1535574Y77008D01*
G01X1535607Y76988D02*
X1535593Y77003D01*
G01X1535613Y76969D02*
X1535607Y76988D01*
G01X1535593Y82003D02*
X1535574Y82008D01*
G01X1535607Y81988D02*
X1535593Y82003D01*
G01X1535613Y81969D02*
X1535607Y81988D01*
G01X1535577Y52106D02*
X1535581Y52205D01*
G01X1535572Y52034D02*
X1535577Y52106D01*
G01X1535574Y52008D02*
X1535572Y52034D01*
G01X1535577Y57106D02*
X1535581Y57205D01*
G01X1535572Y57034D02*
X1535577Y57106D01*
G01X1535574Y57008D02*
X1535572Y57034D01*
G01X1535577Y62106D02*
X1535581Y62205D01*
G01X1535572Y62034D02*
X1535577Y62106D01*
G01X1535574Y62008D02*
X1535572Y62034D01*
G01X1535577Y67106D02*
X1535581Y67205D01*
G01X1535572Y67034D02*
X1535577Y67106D01*
G01X1535574Y67008D02*
X1535572Y67034D01*
G01X1535577Y72106D02*
X1535581Y72205D01*
G01X1535572Y72034D02*
X1535577Y72106D01*
G01X1535574Y72008D02*
X1535572Y72034D01*
G01X1535577Y77106D02*
X1535581Y77205D01*
G01X1535572Y77034D02*
X1535577Y77106D01*
G01X1535574Y77008D02*
X1535572Y77034D01*
G01X1535577Y82106D02*
X1535581Y82205D01*
G01X1535572Y82034D02*
X1535577Y82106D01*
G01X1535574Y82008D02*
X1535572Y82034D01*
G01X1534627Y80628D02*
X1534628Y80630D01*
G01X1534626Y80622D02*
X1534627Y80628D01*
G01X1534626Y80614D02*
Y80622D01*
G01X1534627Y75628D02*
X1534628Y75630D01*
G01X1534626Y75622D02*
X1534627Y75628D01*
G01X1534626Y75614D02*
Y75622D01*
G01X1534627Y70628D02*
X1534628Y70630D01*
G01X1534626Y70622D02*
X1534627Y70628D01*
G01X1534626Y70614D02*
Y70622D01*
G01X1534627Y65628D02*
X1534628Y65630D01*
G01X1534626Y65622D02*
X1534627Y65628D01*
G01X1534626Y65614D02*
Y65622D01*
G01X1534627Y60628D02*
X1534628Y60630D01*
G01X1534626Y60622D02*
X1534627Y60628D01*
G01X1534626Y60614D02*
Y60622D01*
G01X1534627Y55628D02*
X1534628Y55630D01*
G01X1534626Y55622D02*
X1534627Y55628D01*
G01X1534626Y55614D02*
Y55622D01*
G01X1534627Y50628D02*
X1534628Y50630D01*
G01X1534626Y50622D02*
X1534627Y50628D01*
G01X1534626Y50614D02*
Y50622D01*
G01X1535611Y80622D02*
X1535610Y80613D01*
G01X1535611Y80628D02*
Y80622D01*
G01X1535613Y80630D02*
X1535611Y80628D01*
G01Y75622D02*
X1535610Y75613D01*
G01X1535611Y75628D02*
Y75622D01*
G01X1535613Y75630D02*
X1535611Y75628D01*
G01Y70622D02*
X1535610Y70613D01*
G01X1535611Y70628D02*
Y70622D01*
G01X1535613Y70630D02*
X1535611Y70628D01*
G01Y65622D02*
X1535610Y65613D01*
G01X1535611Y65628D02*
Y65622D01*
G01X1535613Y65630D02*
X1535611Y65628D01*
G01Y60622D02*
X1535610Y60613D01*
G01X1535611Y60628D02*
Y60622D01*
G01X1535613Y60630D02*
X1535611Y60628D01*
G01Y55622D02*
X1535610Y55613D01*
G01X1535611Y55628D02*
Y55622D01*
G01X1535613Y55630D02*
X1535611Y55628D01*
G01Y50622D02*
X1535610Y50613D01*
G01X1535611Y50628D02*
Y50622D01*
G01X1535613Y50630D02*
X1535611Y50628D01*
G01X1585138Y94488D02*
G03X1599115I6989J0D01*
G01X1599114D02*
G03I-6988J0D01*
G01X1533465Y24547D02*
G03X1534055Y25138I-1J591D01*
G01X1531299Y26319D02*
G03Y28287I0J984D01*
G01X1532677Y34232D02*
G03X1533858Y35413I0J1181D01*
G01X1538976Y23760D02*
G03X1540945Y25728I1J1968D01*
G01X1532603Y42579D02*
X1531299Y40610D01*
G01X1535610Y51982D02*
X1535611Y51991D01*
G01X1535610Y56982D02*
X1535611Y56991D01*
G01X1535610Y61982D02*
X1535611Y61991D01*
G01X1535610Y66982D02*
X1535611Y66991D01*
G01X1535610Y71982D02*
X1535611Y71991D01*
G01X1535610Y76982D02*
X1535611Y76991D01*
G01X1535610Y81982D02*
X1535611Y81991D01*
G01X1540945Y25728D02*
Y41476D01*
G01X1539961Y80630D02*
Y82008D01*
G01Y75630D02*
Y77008D01*
G01Y70630D02*
Y72008D01*
G01Y65630D02*
Y67008D01*
G01Y60630D02*
Y62008D01*
G01Y55630D02*
Y57008D01*
G01Y50630D02*
Y52008D01*
G01X1537598Y182815D02*
Y44823D01*
G01X1537008Y185059D02*
Y42579D01*
G01X1536791Y52008D02*
Y50630D01*
G01Y57008D02*
Y55630D01*
G01Y62008D02*
Y60630D01*
G01Y67008D02*
Y65630D01*
G01Y72008D02*
Y70630D01*
G01Y77008D02*
Y75630D01*
G01Y82008D02*
Y80630D01*
G01X1536220Y104862D02*
Y82776D01*
G01X1535610Y51982D02*
Y52125D01*
G01Y56982D02*
Y57125D01*
G01Y61982D02*
Y62125D01*
G01Y66982D02*
Y67125D01*
G01Y71982D02*
Y72125D01*
G01Y76982D02*
Y77125D01*
G01Y81982D02*
Y82125D01*
G01Y80138D02*
Y82500D01*
G01Y75138D02*
Y77500D01*
G01Y70138D02*
Y72500D01*
G01Y65138D02*
Y67500D01*
G01Y60138D02*
Y62500D01*
G01Y55138D02*
Y57500D01*
G01Y50138D02*
Y52500D01*
G01X1535039Y103681D02*
Y83957D01*
G01X1534626Y52500D02*
Y50138D01*
G01Y57500D02*
Y55138D01*
G01Y62500D02*
Y60138D01*
G01Y67500D02*
Y65138D01*
G01Y72500D02*
Y70138D01*
G01Y77500D02*
Y75138D01*
G01Y82500D02*
Y80138D01*
G01X1534055Y31240D02*
Y25138D01*
G01X1533858Y43957D02*
Y35413D01*
G01X1532283Y82776D02*
Y46319D01*
G01X1531299Y40610D02*
Y38917D01*
G01X1531102Y83957D02*
Y47500D01*
G01X1531299Y38917D02*
X1533609Y34688D01*
G01X1535039Y83957D02*
X1536220Y82776D01*
G01X1531102Y83957D02*
X1532283Y82776D01*
G01X1540945Y41476D02*
X1537598Y44823D01*
G01X1531102Y47500D02*
X1532283Y46319D01*
G01X1535039Y83957D02*
X1531102D01*
G01X1536220Y82776D02*
X1532283D01*
G01X1535610Y82500D02*
X1534626D01*
G01X1534628Y82008D02*
X1539961D01*
G01Y81969D02*
X1535613D01*
G01X1539961Y80630D02*
X1534628D01*
G01X1534626Y80138D02*
X1535610D01*
G01Y77500D02*
X1534626D01*
G01X1534628Y77008D02*
X1539961D01*
G01Y76969D02*
X1535613D01*
G01X1539961Y75630D02*
X1534628D01*
G01X1534626Y75138D02*
X1535610D01*
G01Y72500D02*
X1534626D01*
G01X1534628Y72008D02*
X1539961D01*
G01Y71969D02*
X1535613D01*
G01X1539961Y70630D02*
X1534628D01*
G01X1534626Y70138D02*
X1535610D01*
G01Y67500D02*
X1534626D01*
G01X1534628Y67008D02*
X1539961D01*
G01Y66969D02*
X1535613D01*
G01X1539961Y65630D02*
X1534628D01*
G01X1534626Y65138D02*
X1535610D01*
G01Y62500D02*
X1534626D01*
G01X1534628Y62008D02*
X1539961D01*
G01Y61969D02*
X1535613D01*
G01X1539961Y60630D02*
X1534628D01*
G01X1534626Y60138D02*
X1535610D01*
G01Y57500D02*
X1534626D01*
G01X1534628Y57008D02*
X1539961D01*
G01Y56969D02*
X1535613D01*
G01X1539961Y55630D02*
X1534628D01*
G01X1534626Y55138D02*
X1535610D01*
G01Y52500D02*
X1534626D01*
G01X1534628Y52008D02*
X1539961D01*
G01Y51969D02*
X1535613D01*
G01X1539961Y50630D02*
X1534628D01*
G01X1534626Y50138D02*
X1535610D01*
G01X1533858Y43957D02*
X1537008D01*
G01X1534626Y82204D02*
X1535581Y82205D01*
G01X1535610Y80434D02*
X1534626Y80433D01*
G01Y77204D02*
X1535581Y77205D01*
G01X1535610Y75434D02*
X1534626Y75433D01*
G01Y72204D02*
X1535581Y72205D01*
G01X1535610Y70434D02*
X1534626Y70433D01*
G01Y67204D02*
X1535581Y67205D01*
G01X1535610Y65434D02*
X1534626Y65433D01*
G01Y62204D02*
X1535581Y62205D01*
G01X1535610Y60434D02*
X1534626Y60433D01*
G01Y57204D02*
X1535581Y57205D01*
G01X1535610Y55434D02*
X1534626Y55433D01*
G01Y52204D02*
X1535581Y52205D01*
G01X1535610Y50434D02*
X1534626Y50433D01*
G01X1535598Y106999D02*
X1535609Y106984D01*
G01X1535573Y107008D02*
X1535598Y106999D01*
G01Y111999D02*
X1535609Y111984D01*
G01X1535573Y112008D02*
X1535598Y111999D01*
G01Y116999D02*
X1535609Y116984D01*
G01X1535573Y117008D02*
X1535598Y116999D01*
G01Y121999D02*
X1535609Y121984D01*
G01X1535573Y122008D02*
X1535598Y121999D01*
G01Y126999D02*
X1535609Y126984D01*
G01X1535573Y127008D02*
X1535598Y126999D01*
G01Y131999D02*
X1535609Y131984D01*
G01X1535573Y132008D02*
X1535598Y131999D01*
G01Y136999D02*
X1535609Y136984D01*
G01X1535573Y137008D02*
X1535598Y136999D01*
G01Y141999D02*
X1535609Y141984D01*
G01X1535573Y142008D02*
X1535598Y141999D01*
G01Y146999D02*
X1535609Y146984D01*
G01X1535573Y147008D02*
X1535598Y146999D01*
G01Y151999D02*
X1535609Y151984D01*
G01X1535573Y152008D02*
X1535598Y151999D01*
G01Y156999D02*
X1535609Y156984D01*
G01X1535573Y157008D02*
X1535598Y156999D01*
G01Y161999D02*
X1535609Y161984D01*
G01X1535573Y162008D02*
X1535598Y161999D01*
G01Y166999D02*
X1535609Y166984D01*
G01X1535573Y167008D02*
X1535598Y166999D01*
G01Y171999D02*
X1535609Y171984D01*
G01X1535573Y172008D02*
X1535598Y171999D01*
G01Y176999D02*
X1535609Y176984D01*
G01X1535573Y177008D02*
X1535598Y176999D01*
G01X1535611Y106975D02*
X1535610Y106982D01*
G01X1535611Y106970D02*
Y106975D01*
G01X1535613Y106969D02*
X1535611Y106970D01*
G01Y111975D02*
X1535610Y111982D01*
G01X1535611Y111970D02*
Y111975D01*
G01X1535613Y111969D02*
X1535611Y111970D01*
G01Y116975D02*
X1535610Y116982D01*
G01X1535611Y116970D02*
Y116975D01*
G01X1535613Y116969D02*
X1535611Y116970D01*
G01Y121975D02*
X1535610Y121982D01*
G01X1535611Y121970D02*
Y121975D01*
G01X1535613Y121969D02*
X1535611Y121970D01*
G01Y126975D02*
X1535610Y126982D01*
G01X1535611Y126970D02*
Y126975D01*
G01X1535613Y126969D02*
X1535611Y126970D01*
G01Y131975D02*
X1535610Y131982D01*
G01X1535611Y131970D02*
Y131975D01*
G01X1535613Y131969D02*
X1535611Y131970D01*
G01Y136975D02*
X1535610Y136982D01*
G01X1535611Y136970D02*
Y136975D01*
G01X1535613Y136969D02*
X1535611Y136970D01*
G01Y141975D02*
X1535610Y141982D01*
G01X1535611Y141970D02*
Y141975D01*
G01X1535613Y141969D02*
X1535611Y141970D01*
G01Y146975D02*
X1535610Y146982D01*
G01X1535611Y146970D02*
Y146975D01*
G01X1535613Y146969D02*
X1535611Y146970D01*
G01Y151975D02*
X1535610Y151982D01*
G01X1535611Y151970D02*
Y151975D01*
G01X1535613Y151969D02*
X1535611Y151970D01*
G01Y156975D02*
X1535610Y156982D01*
G01X1535611Y156970D02*
Y156975D01*
G01X1535613Y156969D02*
X1535611Y156970D01*
G01Y161975D02*
X1535610Y161982D01*
G01X1535611Y161970D02*
Y161975D01*
G01X1535613Y161969D02*
X1535611Y161970D01*
G01Y166975D02*
X1535610Y166982D01*
G01X1535611Y166970D02*
Y166975D01*
G01X1535613Y166969D02*
X1535611Y166970D01*
G01Y171975D02*
X1535610Y171982D01*
G01X1535611Y171970D02*
Y171975D01*
G01X1535613Y171969D02*
X1535611Y171970D01*
G01Y176975D02*
X1535610Y176982D01*
G01X1535611Y176970D02*
Y176975D01*
G01X1535613Y176969D02*
X1535611Y176970D01*
G01X1534626Y107015D02*
Y107024D01*
G01X1534627Y107009D02*
X1534626Y107015D01*
G01X1534628Y107008D02*
X1534627Y107009D01*
G01X1534626Y112015D02*
Y112024D01*
G01X1534627Y112009D02*
X1534626Y112015D01*
G01X1534628Y112008D02*
X1534627Y112009D01*
G01X1534626Y117015D02*
Y117024D01*
G01X1534627Y117009D02*
X1534626Y117015D01*
G01X1534628Y117008D02*
X1534627Y117009D01*
G01X1534626Y122015D02*
Y122024D01*
G01X1534627Y122009D02*
X1534626Y122015D01*
G01X1534628Y122008D02*
X1534627Y122009D01*
G01X1534626Y127015D02*
Y127024D01*
G01X1534627Y127009D02*
X1534626Y127015D01*
G01X1534628Y127008D02*
X1534627Y127009D01*
G01X1534626Y132015D02*
Y132024D01*
G01X1534627Y132009D02*
X1534626Y132015D01*
G01X1534628Y132008D02*
X1534627Y132009D01*
G01X1534626Y137015D02*
Y137024D01*
G01X1534627Y137009D02*
X1534626Y137015D01*
G01X1534628Y137008D02*
X1534627Y137009D01*
G01X1534626Y142015D02*
Y142024D01*
G01X1534627Y142009D02*
X1534626Y142015D01*
G01X1534628Y142008D02*
X1534627Y142009D01*
G01X1534626Y147015D02*
Y147024D01*
G01X1534627Y147009D02*
X1534626Y147015D01*
G01X1534628Y147008D02*
X1534627Y147009D01*
G01X1534626Y152015D02*
Y152024D01*
G01X1534627Y152009D02*
X1534626Y152015D01*
G01X1534628Y152008D02*
X1534627Y152009D01*
G01X1534626Y157015D02*
Y157024D01*
G01X1534627Y157009D02*
X1534626Y157015D01*
G01X1534628Y157008D02*
X1534627Y157009D01*
G01X1534626Y162015D02*
Y162024D01*
G01X1534627Y162009D02*
X1534626Y162015D01*
G01X1534628Y162008D02*
X1534627Y162009D01*
G01X1534626Y167015D02*
Y167024D01*
G01X1534627Y167009D02*
X1534626Y167015D01*
G01X1534628Y167008D02*
X1534627Y167009D01*
G01X1534626Y172015D02*
Y172024D01*
G01X1534627Y172009D02*
X1534626Y172015D01*
G01X1534628Y172008D02*
X1534627Y172009D01*
G01X1534626Y177015D02*
Y177024D01*
G01X1534627Y177009D02*
X1534626Y177015D01*
G01X1534628Y177008D02*
X1534627Y177009D01*
G01X1535602Y107152D02*
X1535610Y107125D01*
G01X1535593Y107178D02*
X1535602Y107152D01*
G01X1535581Y107205D02*
X1535593Y107178D01*
G01X1535602Y112152D02*
X1535610Y112125D01*
G01X1535593Y112178D02*
X1535602Y112152D01*
G01X1535581Y112205D02*
X1535593Y112178D01*
G01X1535602Y117152D02*
X1535610Y117125D01*
G01X1535593Y117178D02*
X1535602Y117152D01*
G01X1535581Y117205D02*
X1535593Y117178D01*
G01X1535602Y122152D02*
X1535610Y122125D01*
G01X1535593Y122178D02*
X1535602Y122152D01*
G01X1535581Y122205D02*
X1535593Y122178D01*
G01X1535602Y127152D02*
X1535610Y127125D01*
G01X1535593Y127178D02*
X1535602Y127152D01*
G01X1535581Y127205D02*
X1535593Y127178D01*
G01X1535602Y132152D02*
X1535610Y132125D01*
G01X1535593Y132178D02*
X1535602Y132152D01*
G01X1535581Y132205D02*
X1535593Y132178D01*
G01X1535602Y137152D02*
X1535610Y137125D01*
G01X1535593Y137178D02*
X1535602Y137152D01*
G01X1535581Y137205D02*
X1535593Y137178D01*
G01X1535602Y142152D02*
X1535610Y142125D01*
G01X1535593Y142178D02*
X1535602Y142152D01*
G01X1535581Y142205D02*
X1535593Y142178D01*
G01X1535602Y147152D02*
X1535610Y147125D01*
G01X1535593Y147178D02*
X1535602Y147152D01*
G01X1535581Y147205D02*
X1535593Y147178D01*
G01X1535602Y152152D02*
X1535610Y152125D01*
G01X1535593Y152178D02*
X1535602Y152152D01*
G01X1535581Y152205D02*
X1535593Y152178D01*
G01X1535602Y157152D02*
X1535610Y157125D01*
G01X1535593Y157178D02*
X1535602Y157152D01*
G01X1535581Y157205D02*
X1535593Y157178D01*
G01X1535602Y162152D02*
X1535610Y162125D01*
G01X1535593Y162178D02*
X1535602Y162152D01*
G01X1535581Y162205D02*
X1535593Y162178D01*
G01X1535602Y167152D02*
X1535610Y167125D01*
G01X1535593Y167178D02*
X1535602Y167152D01*
G01X1535581Y167205D02*
X1535593Y167178D01*
G01X1535602Y172152D02*
X1535610Y172125D01*
G01X1535593Y172178D02*
X1535602Y172152D01*
G01X1535581Y172205D02*
X1535593Y172178D01*
G01X1535602Y177152D02*
X1535610Y177125D01*
G01X1535593Y177178D02*
X1535602Y177152D01*
G01X1535581Y177205D02*
X1535593Y177178D01*
G01Y107003D02*
X1535574Y107008D01*
G01X1535607Y106988D02*
X1535593Y107003D01*
G01X1535613Y106969D02*
X1535607Y106988D01*
G01X1535593Y112003D02*
X1535574Y112008D01*
G01X1535607Y111988D02*
X1535593Y112003D01*
G01X1535613Y111969D02*
X1535607Y111988D01*
G01X1535593Y117003D02*
X1535574Y117008D01*
G01X1535607Y116988D02*
X1535593Y117003D01*
G01X1535613Y116969D02*
X1535607Y116988D01*
G01X1535593Y122003D02*
X1535574Y122008D01*
G01X1535607Y121988D02*
X1535593Y122003D01*
G01X1535613Y121969D02*
X1535607Y121988D01*
G01X1535593Y127003D02*
X1535574Y127008D01*
G01X1535607Y126988D02*
X1535593Y127003D01*
G01X1535613Y126969D02*
X1535607Y126988D01*
G01X1535593Y132003D02*
X1535574Y132008D01*
G01X1535607Y131988D02*
X1535593Y132003D01*
G01X1535613Y131969D02*
X1535607Y131988D01*
G01X1535593Y137003D02*
X1535574Y137008D01*
G01X1535607Y136988D02*
X1535593Y137003D01*
G01X1535613Y136969D02*
X1535607Y136988D01*
G01X1535593Y142003D02*
X1535574Y142008D01*
G01X1535607Y141988D02*
X1535593Y142003D01*
G01X1535613Y141969D02*
X1535607Y141988D01*
G01X1535593Y147003D02*
X1535574Y147008D01*
G01X1535607Y146988D02*
X1535593Y147003D01*
G01X1535613Y146969D02*
X1535607Y146988D01*
G01X1535593Y152003D02*
X1535574Y152008D01*
G01X1535607Y151988D02*
X1535593Y152003D01*
G01X1535613Y151969D02*
X1535607Y151988D01*
G01X1535593Y157003D02*
X1535574Y157008D01*
G01X1535607Y156988D02*
X1535593Y157003D01*
G01X1535613Y156969D02*
X1535607Y156988D01*
G01X1535593Y162003D02*
X1535574Y162008D01*
G01X1535607Y161988D02*
X1535593Y162003D01*
G01X1535613Y161969D02*
X1535607Y161988D01*
G01X1535593Y167003D02*
X1535574Y167008D01*
G01X1535607Y166988D02*
X1535593Y167003D01*
G01X1535613Y166969D02*
X1535607Y166988D01*
G01X1535593Y172003D02*
X1535574Y172008D01*
G01X1535607Y171988D02*
X1535593Y172003D01*
G01X1535613Y171969D02*
X1535607Y171988D01*
G01X1535593Y177003D02*
X1535574Y177008D01*
G01X1535607Y176988D02*
X1535593Y177003D01*
G01X1535613Y176969D02*
X1535607Y176988D01*
G01X1535577Y107106D02*
X1535581Y107205D01*
G01X1535572Y107034D02*
X1535577Y107106D01*
G01X1535574Y107008D02*
X1535572Y107034D01*
G01X1535577Y112106D02*
X1535581Y112205D01*
G01X1535572Y112034D02*
X1535577Y112106D01*
G01X1535574Y112008D02*
X1535572Y112034D01*
G01X1535577Y117106D02*
X1535581Y117205D01*
G01X1535572Y117034D02*
X1535577Y117106D01*
G01X1535574Y117008D02*
X1535572Y117034D01*
G01X1535577Y122106D02*
X1535581Y122205D01*
G01X1535572Y122034D02*
X1535577Y122106D01*
G01X1535574Y122008D02*
X1535572Y122034D01*
G01X1535577Y127106D02*
X1535581Y127205D01*
G01X1535572Y127034D02*
X1535577Y127106D01*
G01X1535574Y127008D02*
X1535572Y127034D01*
G01X1535577Y132106D02*
X1535581Y132205D01*
G01X1535572Y132034D02*
X1535577Y132106D01*
G01X1535574Y132008D02*
X1535572Y132034D01*
G01X1535577Y137106D02*
X1535581Y137205D01*
G01X1535572Y137034D02*
X1535577Y137106D01*
G01X1535574Y137008D02*
X1535572Y137034D01*
G01X1535577Y142106D02*
X1535581Y142205D01*
G01X1535572Y142034D02*
X1535577Y142106D01*
G01X1535574Y142008D02*
X1535572Y142034D01*
G01X1535577Y147106D02*
X1535581Y147205D01*
G01X1535572Y147034D02*
X1535577Y147106D01*
G01X1535574Y147008D02*
X1535572Y147034D01*
G01X1535577Y152106D02*
X1535581Y152205D01*
G01X1535572Y152034D02*
X1535577Y152106D01*
G01X1535574Y152008D02*
X1535572Y152034D01*
G01X1535577Y157106D02*
X1535581Y157205D01*
G01X1535572Y157034D02*
X1535577Y157106D01*
G01X1535574Y157008D02*
X1535572Y157034D01*
G01X1535577Y162106D02*
X1535581Y162205D01*
G01X1535572Y162034D02*
X1535577Y162106D01*
G01X1535574Y162008D02*
X1535572Y162034D01*
G01X1535577Y167106D02*
X1535581Y167205D01*
G01X1535572Y167034D02*
X1535577Y167106D01*
G01X1535574Y167008D02*
X1535572Y167034D01*
G01X1535577Y172106D02*
X1535581Y172205D01*
G01X1535572Y172034D02*
X1535577Y172106D01*
G01X1535574Y172008D02*
X1535572Y172034D01*
G01X1535577Y177106D02*
X1535581Y177205D01*
G01X1535572Y177034D02*
X1535577Y177106D01*
G01X1535574Y177008D02*
X1535572Y177034D01*
G01X1534627Y175628D02*
X1534628Y175630D01*
G01X1534626Y175622D02*
X1534627Y175628D01*
G01X1534626Y175614D02*
Y175622D01*
G01X1534627Y170628D02*
X1534628Y170630D01*
G01X1534626Y170622D02*
X1534627Y170628D01*
G01X1534626Y170614D02*
Y170622D01*
G01X1534627Y165628D02*
X1534628Y165630D01*
G01X1534626Y165622D02*
X1534627Y165628D01*
G01X1534626Y165614D02*
Y165622D01*
G01X1534627Y160628D02*
X1534628Y160630D01*
G01X1534626Y160622D02*
X1534627Y160628D01*
G01X1534626Y160614D02*
Y160622D01*
G01X1534627Y155628D02*
X1534628Y155630D01*
G01X1534626Y155622D02*
X1534627Y155628D01*
G01X1534626Y155614D02*
Y155622D01*
G01X1534627Y150628D02*
X1534628Y150630D01*
G01X1534626Y150622D02*
X1534627Y150628D01*
G01X1534626Y150614D02*
Y150622D01*
G01X1534627Y145628D02*
X1534628Y145630D01*
G01X1534626Y145622D02*
X1534627Y145628D01*
G01X1534626Y145614D02*
Y145622D01*
G01X1534627Y140628D02*
X1534628Y140630D01*
G01X1534626Y140622D02*
X1534627Y140628D01*
G01X1534626Y140614D02*
Y140622D01*
G01X1534627Y135628D02*
X1534628Y135630D01*
G01X1534626Y135622D02*
X1534627Y135628D01*
G01X1534626Y135614D02*
Y135622D01*
G01X1534627Y130628D02*
X1534628Y130630D01*
G01X1534626Y130622D02*
X1534627Y130628D01*
G01X1534626Y130614D02*
Y130622D01*
G01X1534627Y125628D02*
X1534628Y125630D01*
G01X1534626Y125622D02*
X1534627Y125628D01*
G01X1534626Y125614D02*
Y125622D01*
G01X1534627Y120628D02*
X1534628Y120630D01*
G01X1534626Y120622D02*
X1534627Y120628D01*
G01X1534626Y120614D02*
Y120622D01*
G01X1534627Y115628D02*
X1534628Y115630D01*
G01X1534626Y115622D02*
X1534627Y115628D01*
G01X1534626Y115614D02*
Y115622D01*
G01X1534627Y110628D02*
X1534628Y110630D01*
G01X1534626Y110622D02*
X1534627Y110628D01*
G01X1534626Y110614D02*
Y110622D01*
G01X1534627Y105628D02*
X1534628Y105630D01*
G01X1534626Y105622D02*
X1534627Y105628D01*
G01X1534626Y105614D02*
Y105622D01*
G01X1535611Y175622D02*
X1535610Y175613D01*
G01X1535611Y175628D02*
Y175622D01*
G01X1535613Y175630D02*
X1535611Y175628D01*
G01Y170622D02*
X1535610Y170613D01*
G01X1535611Y170628D02*
Y170622D01*
G01X1535613Y170630D02*
X1535611Y170628D01*
G01Y165622D02*
X1535610Y165613D01*
G01X1535611Y165628D02*
Y165622D01*
G01X1535613Y165630D02*
X1535611Y165628D01*
G01Y160622D02*
X1535610Y160613D01*
G01X1535611Y160628D02*
Y160622D01*
G01X1535613Y160630D02*
X1535611Y160628D01*
G01Y155622D02*
X1535610Y155613D01*
G01X1535611Y155628D02*
Y155622D01*
G01X1535613Y155630D02*
X1535611Y155628D01*
G01Y150622D02*
X1535610Y150613D01*
G01X1535611Y150628D02*
Y150622D01*
G01X1535613Y150630D02*
X1535611Y150628D01*
G01Y145622D02*
X1535610Y145613D01*
G01X1535611Y145628D02*
Y145622D01*
G01X1535613Y145630D02*
X1535611Y145628D01*
G01Y140622D02*
X1535610Y140613D01*
G01X1535611Y140628D02*
Y140622D01*
G01X1535613Y140630D02*
X1535611Y140628D01*
G01Y135622D02*
X1535610Y135613D01*
G01X1535611Y135628D02*
Y135622D01*
G01X1535613Y135630D02*
X1535611Y135628D01*
G01Y130622D02*
X1535610Y130613D01*
G01X1535611Y130628D02*
Y130622D01*
G01X1535613Y130630D02*
X1535611Y130628D01*
G01Y125622D02*
X1535610Y125613D01*
G01X1535611Y125628D02*
Y125622D01*
G01X1535613Y125630D02*
X1535611Y125628D01*
G01Y120622D02*
X1535610Y120613D01*
G01X1535611Y120628D02*
Y120622D01*
G01X1535613Y120630D02*
X1535611Y120628D01*
G01Y115622D02*
X1535610Y115613D01*
G01X1535611Y115628D02*
Y115622D01*
G01X1535613Y115630D02*
X1535611Y115628D01*
G01Y110622D02*
X1535610Y110613D01*
G01X1535611Y110628D02*
Y110622D01*
G01X1535613Y110630D02*
X1535611Y110628D01*
G01Y105622D02*
X1535610Y105613D01*
G01X1535611Y105628D02*
Y105622D01*
G01X1535613Y105630D02*
X1535611Y105628D01*
G01X1599115Y94488D02*
G03X1585138I-6988J0D01*
G01X1535039Y103681D02*
X1536220Y104862D01*
G01X1531102Y103681D02*
X1532283Y104862D01*
G01X1540945Y186161D02*
X1537598Y182815D01*
G01X1531102Y180138D02*
X1532283Y181319D01*
G01X1533609Y192950D02*
X1531299Y188720D01*
G01X1535610Y106982D02*
X1535611Y106991D01*
G01X1535610Y111982D02*
X1535611Y111991D01*
G01X1535610Y116982D02*
X1535611Y116991D01*
G01X1535610Y121982D02*
X1535611Y121991D01*
G01X1535610Y126982D02*
X1535611Y126991D01*
G01X1535610Y131982D02*
X1535611Y131991D01*
G01X1535610Y136982D02*
X1535611Y136991D01*
G01X1535610Y141982D02*
X1535611Y141991D01*
G01X1535610Y146982D02*
X1535611Y146991D01*
G01X1535610Y151982D02*
X1535611Y151991D01*
G01X1535610Y156982D02*
X1535611Y156991D01*
G01X1535610Y161982D02*
X1535611Y161991D01*
G01X1535610Y166982D02*
X1535611Y166991D01*
G01X1535610Y171982D02*
X1535611Y171991D01*
G01X1535610Y176982D02*
X1535611Y176991D01*
G01X1540945Y186161D02*
Y201909D01*
G01X1539961Y175630D02*
Y177008D01*
G01Y170630D02*
Y172008D01*
G01Y165630D02*
Y167008D01*
G01Y160630D02*
Y162008D01*
G01Y155630D02*
Y157008D01*
G01Y150630D02*
Y152008D01*
G01Y145630D02*
Y147008D01*
G01Y140630D02*
Y142008D01*
G01Y135630D02*
Y137008D01*
G01Y130630D02*
Y132008D01*
G01Y125630D02*
Y127008D01*
G01Y120630D02*
Y122008D01*
G01Y115630D02*
Y117008D01*
G01Y110630D02*
Y112008D01*
G01Y105630D02*
Y107008D01*
G01X1536791D02*
Y105630D01*
G01Y112008D02*
Y110630D01*
G01Y117008D02*
Y115630D01*
G01Y122008D02*
Y120630D01*
G01Y127008D02*
Y125630D01*
G01Y132008D02*
Y130630D01*
G01Y137008D02*
Y135630D01*
G01Y142008D02*
Y140630D01*
G01Y147008D02*
Y145630D01*
G01Y152008D02*
Y150630D01*
G01Y157008D02*
Y155630D01*
G01Y162008D02*
Y160630D01*
G01Y167008D02*
Y165630D01*
G01Y172008D02*
Y170630D01*
G01Y177008D02*
Y175630D01*
G01X1535610Y106982D02*
Y107125D01*
G01Y111982D02*
Y112125D01*
G01Y116982D02*
Y117125D01*
G01Y121982D02*
Y122125D01*
G01Y126982D02*
Y127125D01*
G01Y131982D02*
Y132125D01*
G01Y136982D02*
Y137125D01*
G01Y141982D02*
Y142125D01*
G01Y146982D02*
Y147125D01*
G01Y151982D02*
Y152125D01*
G01Y156982D02*
Y157125D01*
G01Y161982D02*
Y162125D01*
G01Y166982D02*
Y167125D01*
G01Y171982D02*
Y172125D01*
G01Y176982D02*
Y177125D01*
G01Y175138D02*
Y177500D01*
G01Y170138D02*
Y172500D01*
G01Y165138D02*
Y167500D01*
G01Y160138D02*
Y162500D01*
G01Y155138D02*
Y157500D01*
G01Y150138D02*
Y152500D01*
G01Y145138D02*
Y147500D01*
G01Y140138D02*
Y142500D01*
G01Y135138D02*
Y137500D01*
G01Y130138D02*
Y132500D01*
G01Y125138D02*
Y127500D01*
G01Y120138D02*
Y122500D01*
G01Y115138D02*
Y117500D01*
G01Y110138D02*
Y112500D01*
G01Y105138D02*
Y107500D01*
G01X1534626D02*
Y105138D01*
G01Y112500D02*
Y110138D01*
G01Y117500D02*
Y115138D01*
G01Y122500D02*
Y120138D01*
G01Y127500D02*
Y125138D01*
G01Y132500D02*
Y130138D01*
G01Y137500D02*
Y135138D01*
G01Y142500D02*
Y140138D01*
G01Y147500D02*
Y145138D01*
G01Y152500D02*
Y150138D01*
G01Y157500D02*
Y155138D01*
G01Y162500D02*
Y160138D01*
G01Y167500D02*
Y165138D01*
G01Y172500D02*
Y170138D01*
G01Y177500D02*
Y175138D01*
G01X1533858Y192224D02*
Y183681D01*
G01X1532283Y181319D02*
Y104862D01*
G01X1531299Y188720D02*
Y187028D01*
G01X1531102Y180138D02*
Y103681D01*
G01X1531299Y187028D02*
X1532603Y185059D01*
G01X1537008Y183681D02*
X1533858D01*
G01X1535610Y177500D02*
X1534626D01*
G01X1534628Y177008D02*
X1539961D01*
G01Y176969D02*
X1535613D01*
G01X1539961Y175630D02*
X1534628D01*
G01X1534626Y175138D02*
X1535610D01*
G01Y172500D02*
X1534626D01*
G01X1534628Y172008D02*
X1539961D01*
G01Y171969D02*
X1535613D01*
G01X1539961Y170630D02*
X1534628D01*
G01X1534626Y170138D02*
X1535610D01*
G01Y167500D02*
X1534626D01*
G01X1534628Y167008D02*
X1539961D01*
G01Y166969D02*
X1535613D01*
G01X1539961Y165630D02*
X1534628D01*
G01X1534626Y165138D02*
X1535610D01*
G01Y162500D02*
X1534626D01*
G01X1534628Y162008D02*
X1539961D01*
G01Y161969D02*
X1535613D01*
G01X1539961Y160630D02*
X1534628D01*
G01X1534626Y160138D02*
X1535610D01*
G01Y157500D02*
X1534626D01*
G01X1534628Y157008D02*
X1539961D01*
G01Y156969D02*
X1535613D01*
G01X1539961Y155630D02*
X1534628D01*
G01X1534626Y155138D02*
X1535610D01*
G01Y152500D02*
X1534626D01*
G01X1534628Y152008D02*
X1539961D01*
G01Y151969D02*
X1535613D01*
G01X1539961Y150630D02*
X1534628D01*
G01X1534626Y150138D02*
X1535610D01*
G01Y147500D02*
X1534626D01*
G01X1534628Y147008D02*
X1539961D01*
G01Y146969D02*
X1535613D01*
G01X1539961Y145630D02*
X1534628D01*
G01X1534626Y145138D02*
X1535610D01*
G01Y142500D02*
X1534626D01*
G01X1534628Y142008D02*
X1539961D01*
G01Y141969D02*
X1535613D01*
G01X1539961Y140630D02*
X1534628D01*
G01X1534626Y140138D02*
X1535610D01*
G01Y137500D02*
X1534626D01*
G01X1534628Y137008D02*
X1539961D01*
G01Y136969D02*
X1535613D01*
G01X1539961Y135630D02*
X1534628D01*
G01X1534626Y135138D02*
X1535610D01*
G01Y132500D02*
X1534626D01*
G01X1534628Y132008D02*
X1539961D01*
G01Y131969D02*
X1535613D01*
G01X1539961Y130630D02*
X1534628D01*
G01X1534626Y130138D02*
X1535610D01*
G01Y127500D02*
X1534626D01*
G01X1534628Y127008D02*
X1539961D01*
G01Y126969D02*
X1535613D01*
G01X1539961Y125630D02*
X1534628D01*
G01X1534626Y125138D02*
X1535610D01*
G01Y122500D02*
X1534626D01*
G01X1534628Y122008D02*
X1539961D01*
G01Y121969D02*
X1535613D01*
G01X1539961Y120630D02*
X1534628D01*
G01X1534626Y120138D02*
X1535610D01*
G01Y117500D02*
X1534626D01*
G01Y177204D02*
X1535581Y177205D01*
G01X1535610Y175434D02*
X1534626Y175433D01*
G01Y172204D02*
X1535581Y172205D01*
G01X1535610Y170434D02*
X1534626Y170433D01*
G01Y167204D02*
X1535581Y167205D01*
G01X1535610Y165434D02*
X1534626Y165433D01*
G01Y162204D02*
X1535581Y162205D01*
G01X1535610Y160434D02*
X1534626Y160433D01*
G01Y157204D02*
X1535581Y157205D01*
G01X1535610Y155434D02*
X1534626Y155433D01*
G01Y152204D02*
X1535581Y152205D01*
G01X1535610Y150434D02*
X1534626Y150433D01*
G01Y147204D02*
X1535581Y147205D01*
G01X1535610Y145434D02*
X1534626Y145433D01*
G01Y142204D02*
X1535581Y142205D01*
G01X1535610Y140434D02*
X1534626Y140433D01*
G01Y137204D02*
X1535581Y137205D01*
G01X1535610Y135434D02*
X1534626Y135433D01*
G01Y132204D02*
X1535581Y132205D01*
G01X1535610Y130434D02*
X1534626Y130433D01*
G01Y127204D02*
X1535581Y127205D01*
G01X1535610Y125434D02*
X1534626Y125433D01*
G01Y122204D02*
X1535581Y122205D01*
G01X1535610Y120434D02*
X1534626Y120433D01*
G01X1534628Y117008D02*
X1539961D01*
G01Y116969D02*
X1535613D01*
G01X1539961Y115630D02*
X1534628D01*
G01X1534626Y115138D02*
X1535610D01*
G01Y112500D02*
X1534626D01*
G01X1534628Y112008D02*
X1539961D01*
G01Y111969D02*
X1535613D01*
G01X1539961Y110630D02*
X1534628D01*
G01X1534626Y110138D02*
X1535610D01*
G01Y107500D02*
X1534626D01*
G01X1534628Y107008D02*
X1539961D01*
G01Y106969D02*
X1535613D01*
G01X1539961Y105630D02*
X1534628D01*
G01X1534626Y105138D02*
X1535610D01*
G01X1532283Y104862D02*
X1536220D01*
G01X1531102Y103681D02*
X1535039D01*
G01X1534626Y117204D02*
X1535581Y117205D01*
G01X1535610Y115434D02*
X1534626Y115433D01*
G01Y112204D02*
X1535581Y112205D01*
G01X1535610Y110434D02*
X1534626Y110433D01*
G01Y107204D02*
X1535581Y107205D01*
G01X1535610Y105434D02*
X1534626Y105433D01*
G01X1559882Y277843D02*
G03X1566807Y264712I37662J11471D01*
G01X1559882Y277843D02*
G03X1539921I-9980J-3040D01*
G01X1532996Y264712D02*
G03X1539921Y277843I-30737J24602D01*
G01X1614370Y260630D02*
G03X1615551I590J0D01*
G01Y254331D02*
G03X1614370I-590J0D01*
G01X1612402D02*
G03X1611220I-591J0D01*
G01Y260630D02*
G03X1612402I591J0D01*
G01X1614370D02*
G03X1615551I590J0D01*
G01Y254331D02*
G03X1614370I-590J0D01*
G01X1612402D02*
G03X1611220I-591J0D01*
G01Y260630D02*
G03X1612402I591J0D01*
G01X1559882Y277843D02*
G03X1566807Y264712I37662J11471D01*
G01X1559882Y277843D02*
G03X1539921I-9980J-3040D01*
G01X1532996Y264712D02*
G03X1539921Y277843I-30737J24602D01*
G01X1534055Y202500D02*
G03X1533465Y203091I-591J0D01*
G01X1531299Y199350D02*
G03Y201319I0J984D01*
G01X1533858Y192224D02*
G03X1532677Y193406I-1181J1D01*
G01X1540945Y201909D02*
G03X1538976Y203878I-1969J0D01*
G01X1616339Y254331D02*
Y260630D01*
G01Y254331D02*
Y260630D01*
G01X1610433Y254331D02*
Y260630D01*
G01D02*
Y254331D01*
G01X1534055Y196398D02*
Y202500D01*
G01X1611220Y260630D02*
X1610433D01*
G01X1611220D02*
X1610433D01*
G01X1614370D02*
X1612402D01*
G01X1616339D02*
X1615551D01*
G01X1614370D02*
X1612402D01*
G01X1616339D02*
X1615551D01*
G01X1616339Y259646D02*
X1610433D01*
G01Y259449D02*
X1616339D01*
G01X1610433Y255512D02*
X1616339D01*
G01Y255315D02*
X1610433D01*
G01X1615551Y254331D02*
X1616339D01*
G01X1612402D02*
X1614370D01*
G01X1615551D02*
X1616339D01*
G01X1612402D02*
X1614370D01*
G01X1610433D02*
X1611220D01*
G01X1610433D02*
X1611220D01*
G01X1535598Y504755D02*
X1535609Y504740D01*
G01X1535573Y504764D02*
X1535598Y504755D01*
G01Y509755D02*
X1535609Y509740D01*
G01X1535573Y509764D02*
X1535598Y509755D01*
G01Y514755D02*
X1535609Y514740D01*
G01X1535573Y514764D02*
X1535598Y514755D01*
G01Y519755D02*
X1535609Y519740D01*
G01X1535573Y519764D02*
X1535598Y519755D01*
G01Y524755D02*
X1535609Y524740D01*
G01X1535573Y524764D02*
X1535598Y524755D01*
G01Y529755D02*
X1535609Y529740D01*
G01X1535573Y529764D02*
X1535598Y529755D01*
G01Y534755D02*
X1535609Y534740D01*
G01X1535573Y534764D02*
X1535598Y534755D01*
G01Y559755D02*
X1535609Y559740D01*
G01X1535573Y559764D02*
X1535598Y559755D01*
G01Y564755D02*
X1535609Y564740D01*
G01X1535573Y564764D02*
X1535598Y564755D01*
G01Y569755D02*
X1535609Y569740D01*
G01X1535573Y569764D02*
X1535598Y569755D01*
G01X1535611Y504731D02*
X1535610Y504738D01*
G01X1535611Y504726D02*
Y504731D01*
G01X1535613Y504724D02*
X1535611Y504726D01*
G01Y509731D02*
X1535610Y509738D01*
G01X1535611Y509726D02*
Y509731D01*
G01X1535613Y509724D02*
X1535611Y509726D01*
G01Y514731D02*
X1535610Y514738D01*
G01X1535611Y514726D02*
Y514731D01*
G01X1535613Y514724D02*
X1535611Y514726D01*
G01Y519731D02*
X1535610Y519738D01*
G01X1535611Y519726D02*
Y519731D01*
G01X1535613Y519724D02*
X1535611Y519726D01*
G01Y524731D02*
X1535610Y524738D01*
G01X1535611Y524726D02*
Y524731D01*
G01X1535613Y524724D02*
X1535611Y524726D01*
G01Y529731D02*
X1535610Y529738D01*
G01X1535611Y529726D02*
Y529731D01*
G01X1535613Y529724D02*
X1535611Y529726D01*
G01Y534731D02*
X1535610Y534738D01*
G01X1535611Y534726D02*
Y534731D01*
G01X1535613Y534724D02*
X1535611Y534726D01*
G01Y559731D02*
X1535610Y559738D01*
G01X1535611Y559726D02*
Y559731D01*
G01X1535613Y559724D02*
X1535611Y559726D01*
G01Y564731D02*
X1535610Y564738D01*
G01X1535611Y564726D02*
Y564731D01*
G01X1535613Y564724D02*
X1535611Y564726D01*
G01Y569731D02*
X1535610Y569738D01*
G01X1535611Y569726D02*
Y569731D01*
G01X1535613Y569724D02*
X1535611Y569726D01*
G01X1534626Y504771D02*
Y504780D01*
G01X1534627Y504765D02*
X1534626Y504771D01*
G01X1534628Y504764D02*
X1534627Y504765D01*
G01X1534626Y509771D02*
Y509780D01*
G01X1534627Y509765D02*
X1534626Y509771D01*
G01X1534628Y509764D02*
X1534627Y509765D01*
G01X1534626Y514771D02*
Y514780D01*
G01X1534627Y514765D02*
X1534626Y514771D01*
G01X1534628Y514764D02*
X1534627Y514765D01*
G01X1534626Y519771D02*
Y519780D01*
G01X1534627Y519765D02*
X1534626Y519771D01*
G01X1534628Y519764D02*
X1534627Y519765D01*
G01X1535602Y504907D02*
X1535610Y504881D01*
G01X1535593Y504934D02*
X1535602Y504907D01*
G01X1535581Y504961D02*
X1535593Y504934D01*
G01X1535602Y509907D02*
X1535610Y509881D01*
G01X1535593Y509934D02*
X1535602Y509907D01*
G01X1535581Y509961D02*
X1535593Y509934D01*
G01X1534626Y524771D02*
Y524780D01*
G01X1534627Y524765D02*
X1534626Y524771D01*
G01X1534628Y524764D02*
X1534627Y524765D01*
G01X1534626Y529771D02*
Y529780D01*
G01X1534627Y529765D02*
X1534626Y529771D01*
G01X1534628Y529764D02*
X1534627Y529765D01*
G01X1534626Y534771D02*
Y534780D01*
G01X1534627Y534765D02*
X1534626Y534771D01*
G01X1534628Y534764D02*
X1534627Y534765D01*
G01X1534626Y559771D02*
Y559780D01*
G01X1534627Y559765D02*
X1534626Y559771D01*
G01X1534628Y559764D02*
X1534627Y559765D01*
G01X1534626Y564771D02*
Y564780D01*
G01X1534627Y564765D02*
X1534626Y564771D01*
G01X1534628Y564764D02*
X1534627Y564765D01*
G01X1534626Y569771D02*
Y569780D01*
G01X1534627Y569765D02*
X1534626Y569771D01*
G01X1534628Y569764D02*
X1534627Y569765D01*
G01X1535602Y514907D02*
X1535610Y514881D01*
G01X1535593Y514934D02*
X1535602Y514907D01*
G01X1535581Y514961D02*
X1535593Y514934D01*
G01X1535602Y519907D02*
X1535610Y519881D01*
G01X1535593Y519934D02*
X1535602Y519907D01*
G01X1535581Y519961D02*
X1535593Y519934D01*
G01X1535602Y524907D02*
X1535610Y524881D01*
G01X1535593Y524934D02*
X1535602Y524907D01*
G01X1535581Y524961D02*
X1535593Y524934D01*
G01X1535602Y529907D02*
X1535610Y529881D01*
G01X1535593Y529934D02*
X1535602Y529907D01*
G01X1535581Y529961D02*
X1535593Y529934D01*
G01X1535602Y534907D02*
X1535610Y534881D01*
G01X1535593Y534934D02*
X1535602Y534907D01*
G01X1535581Y534961D02*
X1535593Y534934D01*
G01X1535602Y559907D02*
X1535610Y559881D01*
G01X1535593Y559934D02*
X1535602Y559907D01*
G01X1535581Y559961D02*
X1535593Y559934D01*
G01X1535602Y564907D02*
X1535610Y564881D01*
G01X1535593Y564934D02*
X1535602Y564907D01*
G01X1535581Y564961D02*
X1535593Y564934D01*
G01X1535602Y569907D02*
X1535610Y569881D01*
G01X1535593Y569934D02*
X1535602Y569907D01*
G01X1535581Y569961D02*
X1535593Y569934D01*
G01Y504759D02*
X1535574Y504764D01*
G01X1535607Y504744D02*
X1535593Y504759D01*
G01X1535613Y504724D02*
X1535607Y504744D01*
G01X1535593Y509759D02*
X1535574Y509764D01*
G01X1535607Y509744D02*
X1535593Y509759D01*
G01X1535613Y509724D02*
X1535607Y509744D01*
G01X1535593Y514759D02*
X1535574Y514764D01*
G01X1535607Y514744D02*
X1535593Y514759D01*
G01X1535613Y514724D02*
X1535607Y514744D01*
G01X1535593Y519759D02*
X1535574Y519764D01*
G01X1535607Y519744D02*
X1535593Y519759D01*
G01X1535613Y519724D02*
X1535607Y519744D01*
G01X1535593Y524759D02*
X1535574Y524764D01*
G01X1535607Y524744D02*
X1535593Y524759D01*
G01X1535613Y524724D02*
X1535607Y524744D01*
G01X1535593Y529759D02*
X1535574Y529764D01*
G01X1535607Y529744D02*
X1535593Y529759D01*
G01X1535613Y529724D02*
X1535607Y529744D01*
G01X1535593Y534759D02*
X1535574Y534764D01*
G01X1535607Y534744D02*
X1535593Y534759D01*
G01X1535613Y534724D02*
X1535607Y534744D01*
G01X1535593Y559759D02*
X1535574Y559764D01*
G01X1535607Y559744D02*
X1535593Y559759D01*
G01X1535613Y559724D02*
X1535607Y559744D01*
G01X1535593Y564759D02*
X1535574Y564764D01*
G01X1535607Y564744D02*
X1535593Y564759D01*
G01X1535613Y564724D02*
X1535607Y564744D01*
G01X1535593Y569759D02*
X1535574Y569764D01*
G01X1535607Y569744D02*
X1535593Y569759D01*
G01X1535613Y569724D02*
X1535607Y569744D01*
G01X1535577Y504862D02*
X1535581Y504961D01*
G01X1535572Y504790D02*
X1535577Y504862D01*
G01X1535574Y504764D02*
X1535572Y504790D01*
G01X1535577Y509862D02*
X1535581Y509961D01*
G01X1535572Y509790D02*
X1535577Y509862D01*
G01X1535574Y509764D02*
X1535572Y509790D01*
G01X1535577Y514862D02*
X1535581Y514961D01*
G01X1535572Y514790D02*
X1535577Y514862D01*
G01X1535574Y514764D02*
X1535572Y514790D01*
G01X1535577Y519862D02*
X1535581Y519961D01*
G01X1535572Y519790D02*
X1535577Y519862D01*
G01X1535574Y519764D02*
X1535572Y519790D01*
G01X1535577Y524862D02*
X1535581Y524961D01*
G01X1535572Y524790D02*
X1535577Y524862D01*
G01X1535574Y524764D02*
X1535572Y524790D01*
G01X1535577Y529862D02*
X1535581Y529961D01*
G01X1535572Y529790D02*
X1535577Y529862D01*
G01X1535574Y529764D02*
X1535572Y529790D01*
G01X1535577Y534862D02*
X1535581Y534961D01*
G01X1535572Y534790D02*
X1535577Y534862D01*
G01X1535574Y534764D02*
X1535572Y534790D01*
G01X1535577Y559862D02*
X1535581Y559961D01*
G01X1535572Y559790D02*
X1535577Y559862D01*
G01X1535574Y559764D02*
X1535572Y559790D01*
G01X1535577Y564862D02*
X1535581Y564961D01*
G01X1535572Y564790D02*
X1535577Y564862D01*
G01X1535574Y564764D02*
X1535572Y564790D01*
G01X1535577Y569862D02*
X1535581Y569961D01*
G01X1535572Y569790D02*
X1535577Y569862D01*
G01X1535574Y569764D02*
X1535572Y569790D01*
G01X1534627Y568384D02*
X1534628Y568386D01*
G01X1534626Y568378D02*
X1534627Y568384D01*
G01X1534626Y568370D02*
Y568378D01*
G01X1534627Y563384D02*
X1534628Y563386D01*
G01X1534626Y563378D02*
X1534627Y563384D01*
G01X1534626Y563370D02*
Y563378D01*
G01X1534627Y558384D02*
X1534628Y558386D01*
G01X1534626Y558378D02*
X1534627Y558384D01*
G01X1534626Y558370D02*
Y558378D01*
G01X1534627Y533384D02*
X1534628Y533386D01*
G01X1534626Y533378D02*
X1534627Y533384D01*
G01X1534626Y533370D02*
Y533378D01*
G01X1534627Y528384D02*
X1534628Y528386D01*
G01X1534626Y528378D02*
X1534627Y528384D01*
G01X1534626Y528370D02*
Y528378D01*
G01X1534627Y523384D02*
X1534628Y523386D01*
G01X1534626Y523378D02*
X1534627Y523384D01*
G01X1534626Y523370D02*
Y523378D01*
G01X1534627Y518384D02*
X1534628Y518386D01*
G01X1534626Y518378D02*
X1534627Y518384D01*
G01X1534626Y518370D02*
Y518378D01*
G01X1534627Y513384D02*
X1534628Y513386D01*
G01X1534626Y513378D02*
X1534627Y513384D01*
G01X1534626Y513370D02*
Y513378D01*
G01X1534627Y508384D02*
X1534628Y508386D01*
G01X1534626Y508378D02*
X1534627Y508384D01*
G01X1534626Y508370D02*
Y508378D01*
G01X1534627Y503384D02*
X1534628Y503386D01*
G01X1534626Y503378D02*
X1534627Y503384D01*
G01X1534626Y503370D02*
Y503378D01*
G01X1535611Y568378D02*
X1535610Y568369D01*
G01X1535611Y568384D02*
Y568378D01*
G01X1535613Y568386D02*
X1535611Y568384D01*
G01Y563378D02*
X1535610Y563369D01*
G01X1535611Y563384D02*
Y563378D01*
G01X1535613Y563386D02*
X1535611Y563384D01*
G01Y558378D02*
X1535610Y558369D01*
G01X1535611Y558384D02*
Y558378D01*
G01X1535613Y558386D02*
X1535611Y558384D01*
G01Y533378D02*
X1535610Y533369D01*
G01X1535611Y533384D02*
Y533378D01*
G01X1535613Y533386D02*
X1535611Y533384D01*
G01Y528378D02*
X1535610Y528369D01*
G01X1535611Y528384D02*
Y528378D01*
G01X1535613Y528386D02*
X1535611Y528384D01*
G01Y523378D02*
X1535610Y523369D01*
G01X1535611Y523384D02*
Y523378D01*
G01X1535613Y523386D02*
X1535611Y523384D01*
G01Y518378D02*
X1535610Y518369D01*
G01X1535611Y518384D02*
Y518378D01*
G01X1535613Y518386D02*
X1535611Y518384D01*
G01Y513378D02*
X1535610Y513369D01*
G01X1535611Y513384D02*
Y513378D01*
G01X1535613Y513386D02*
X1535611Y513384D01*
G01Y508378D02*
X1535610Y508369D01*
G01X1535611Y508384D02*
Y508378D01*
G01X1535613Y508386D02*
X1535611Y508384D01*
G01Y503378D02*
X1535610Y503369D01*
G01X1535611Y503384D02*
Y503378D01*
G01X1535613Y503386D02*
X1535611Y503384D01*
G01X1532677Y486988D02*
G03X1533858Y488169I0J1181D01*
G01X1533465Y477303D02*
G03X1534055Y477894I-1J591D01*
G01X1531299Y479075D02*
G03Y481043I0J984D01*
G01X1538976Y476516D02*
G03X1540945Y478484I1J1968D01*
G01X1532603Y495335D02*
X1531299Y493366D01*
G01X1535039Y556437D02*
X1536220Y557618D01*
G01X1531102Y556437D02*
X1532283Y557618D01*
G01X1535610Y504738D02*
X1535611Y504746D01*
G01X1535610Y509738D02*
X1535611Y509746D01*
G01X1535610Y514738D02*
X1535611Y514746D01*
G01X1535610Y519738D02*
X1535611Y519746D01*
G01X1535610Y524738D02*
X1535611Y524746D01*
G01X1535610Y529738D02*
X1535611Y529746D01*
G01X1535610Y534738D02*
X1535611Y534746D01*
G01X1535610Y559738D02*
X1535611Y559746D01*
G01X1535610Y564738D02*
X1535611Y564746D01*
G01X1535610Y569738D02*
X1535611Y569746D01*
G01X1540945Y478484D02*
Y494232D01*
G01X1539961Y568386D02*
Y569764D01*
G01Y563386D02*
Y564764D01*
G01Y558386D02*
Y559764D01*
G01Y533386D02*
Y534764D01*
G01Y528386D02*
Y529764D01*
G01Y523386D02*
Y524764D01*
G01Y518386D02*
Y519764D01*
G01Y513386D02*
Y514764D01*
G01Y508386D02*
Y509764D01*
G01Y503386D02*
Y504764D01*
G01X1537598Y635571D02*
Y497579D01*
G01X1537008Y637815D02*
Y495335D01*
G01X1536791Y504764D02*
Y503386D01*
G01Y509764D02*
Y508386D01*
G01Y514764D02*
Y513386D01*
G01Y519764D02*
Y518386D01*
G01Y524764D02*
Y523386D01*
G01Y529764D02*
Y528386D01*
G01Y534764D02*
Y533386D01*
G01Y559764D02*
Y558386D01*
G01Y564764D02*
Y563386D01*
G01Y569764D02*
Y568386D01*
G01X1536220Y557618D02*
Y535531D01*
G01X1535610Y504738D02*
Y504881D01*
G01Y509738D02*
Y509881D01*
G01Y514738D02*
Y514881D01*
G01Y519738D02*
Y519881D01*
G01Y524738D02*
Y524881D01*
G01Y529738D02*
Y529881D01*
G01Y534738D02*
Y534881D01*
G01Y559738D02*
Y559881D01*
G01Y564738D02*
Y564881D01*
G01Y567894D02*
Y570256D01*
G01Y562894D02*
Y565256D01*
G01Y557894D02*
Y560256D01*
G01Y532894D02*
Y535256D01*
G01Y527894D02*
Y530256D01*
G01Y522894D02*
Y525256D01*
G01Y517894D02*
Y520256D01*
G01Y512894D02*
Y515256D01*
G01Y507894D02*
Y510256D01*
G01Y502894D02*
Y505256D01*
G01X1535039Y556437D02*
Y536713D01*
G01X1534626Y505256D02*
Y502894D01*
G01Y510256D02*
Y507894D01*
G01Y515256D02*
Y512894D01*
G01Y520256D02*
Y517894D01*
G01Y525256D02*
Y522894D01*
G01Y530256D02*
Y527894D01*
G01Y535256D02*
Y532894D01*
G01Y560256D02*
Y557894D01*
G01Y565256D02*
Y562894D01*
G01Y570256D02*
Y567894D01*
G01X1534055Y483996D02*
Y477894D01*
G01X1533858Y496713D02*
Y488169D01*
G01X1532283Y535531D02*
Y499075D01*
G01Y634075D02*
Y557618D01*
G01X1531299Y493366D02*
Y491673D01*
G01X1531102Y536713D02*
Y500256D01*
G01Y632894D02*
Y556437D01*
G01X1531299Y491673D02*
X1533609Y487444D01*
G01X1535039Y536713D02*
X1536220Y535531D01*
G01X1531102Y536713D02*
X1532283Y535531D01*
G01X1537598Y497579D02*
X1540945Y494232D01*
G01X1531102Y500256D02*
X1532283Y499075D01*
G01X1535610Y570256D02*
X1534626D01*
G01X1534628Y569764D02*
X1539961D01*
G01Y569724D02*
X1535613D01*
G01X1539961Y568386D02*
X1534628D01*
G01X1534626Y567894D02*
X1535610D01*
G01Y565256D02*
X1534626D01*
G01X1534628Y564764D02*
X1539961D01*
G01Y564724D02*
X1535613D01*
G01X1539961Y563386D02*
X1534628D01*
G01X1534626Y562894D02*
X1535610D01*
G01Y560256D02*
X1534626D01*
G01X1534628Y559764D02*
X1539961D01*
G01Y559724D02*
X1535613D01*
G01X1539961Y558386D02*
X1534628D01*
G01X1534626Y557894D02*
X1535610D01*
G01X1532283Y557618D02*
X1536220D01*
G01X1531102Y556437D02*
X1535039D01*
G01Y536713D02*
X1531102D01*
G01X1536220Y535531D02*
X1532283D01*
G01X1535610Y535256D02*
X1534626D01*
G01X1534628Y534764D02*
X1539961D01*
G01Y534724D02*
X1535613D01*
G01X1539961Y533386D02*
X1534628D01*
G01X1534626Y532894D02*
X1535610D01*
G01Y530256D02*
X1534626D01*
G01X1534628Y529764D02*
X1539961D01*
G01Y529724D02*
X1535613D01*
G01X1539961Y528386D02*
X1534628D01*
G01X1534626Y569959D02*
X1535581Y569961D01*
G01X1535610Y568190D02*
X1534626Y568189D01*
G01Y564959D02*
X1535581Y564961D01*
G01X1535610Y563190D02*
X1534626Y563189D01*
G01Y559959D02*
X1535581Y559961D01*
G01X1535610Y558190D02*
X1534626Y558189D01*
G01Y534959D02*
X1535581Y534961D01*
G01X1535610Y533190D02*
X1534626Y533189D01*
G01Y529959D02*
X1535581Y529961D01*
G01X1534626Y527894D02*
X1535610D01*
G01Y525256D02*
X1534626D01*
G01X1534628Y524764D02*
X1539961D01*
G01Y524724D02*
X1535613D01*
G01X1539961Y523386D02*
X1534628D01*
G01X1534626Y522894D02*
X1535610D01*
G01Y520256D02*
X1534626D01*
G01X1534628Y519764D02*
X1539961D01*
G01Y519724D02*
X1535613D01*
G01X1539961Y518386D02*
X1534628D01*
G01X1534626Y517894D02*
X1535610D01*
G01Y515256D02*
X1534626D01*
G01X1534628Y514764D02*
X1539961D01*
G01Y514724D02*
X1535613D01*
G01X1539961Y513386D02*
X1534628D01*
G01X1534626Y512894D02*
X1535610D01*
G01Y510256D02*
X1534626D01*
G01X1534628Y509764D02*
X1539961D01*
G01Y509724D02*
X1535613D01*
G01X1539961Y508386D02*
X1534628D01*
G01X1534626Y507894D02*
X1535610D01*
G01Y505256D02*
X1534626D01*
G01X1534628Y504764D02*
X1539961D01*
G01Y504724D02*
X1535613D01*
G01X1539961Y503386D02*
X1534628D01*
G01X1534626Y502894D02*
X1535610D01*
G01X1533858Y496713D02*
X1537008D01*
G01X1535610Y528190D02*
X1534626Y528189D01*
G01Y524959D02*
X1535581Y524961D01*
G01X1535610Y523190D02*
X1534626Y523189D01*
G01Y519959D02*
X1535581Y519961D01*
G01X1535610Y518190D02*
X1534626Y518189D01*
G01Y514959D02*
X1535581Y514961D01*
G01X1535610Y513190D02*
X1534626Y513189D01*
G01Y509959D02*
X1535581Y509961D01*
G01X1535610Y508190D02*
X1534626Y508189D01*
G01Y504959D02*
X1535581Y504961D01*
G01X1535610Y503190D02*
X1534626Y503189D01*
G01X1535598Y574755D02*
X1535609Y574740D01*
G01X1535573Y574764D02*
X1535598Y574755D01*
G01Y579755D02*
X1535609Y579740D01*
G01X1535573Y579764D02*
X1535598Y579755D01*
G01Y584755D02*
X1535609Y584740D01*
G01X1535573Y584764D02*
X1535598Y584755D01*
G01X1535609Y589740D02*
X1535610Y589734D01*
G01X1535598Y589755D02*
X1535609Y589740D01*
G01X1535573Y589764D02*
X1535598Y589755D01*
G01Y594755D02*
X1535609Y594740D01*
G01X1535573Y594764D02*
X1535598Y594755D01*
G01Y599755D02*
X1535609Y599740D01*
G01X1535573Y599764D02*
X1535598Y599755D01*
G01Y604755D02*
X1535609Y604740D01*
G01X1535573Y604764D02*
X1535598Y604755D01*
G01Y609755D02*
X1535609Y609740D01*
G01X1535573Y609764D02*
X1535598Y609755D01*
G01Y614755D02*
X1535609Y614740D01*
G01X1535573Y614764D02*
X1535598Y614755D01*
G01Y619755D02*
X1535609Y619740D01*
G01X1535573Y619764D02*
X1535598Y619755D01*
G01Y624755D02*
X1535609Y624740D01*
G01X1535573Y624764D02*
X1535598Y624755D01*
G01Y629755D02*
X1535609Y629740D01*
G01X1535573Y629764D02*
X1535598Y629755D01*
G01X1535611Y574731D02*
X1535610Y574738D01*
G01X1535611Y574726D02*
Y574731D01*
G01X1535613Y574724D02*
X1535611Y574726D01*
G01Y579731D02*
X1535610Y579738D01*
G01X1535611Y579726D02*
Y579731D01*
G01X1535613Y579724D02*
X1535611Y579726D01*
G01Y584731D02*
X1535610Y584738D01*
G01X1535611Y584726D02*
Y584731D01*
G01X1535613Y584724D02*
X1535611Y584726D01*
G01Y589731D02*
X1535610Y589738D01*
G01X1535611Y589726D02*
Y589731D01*
G01X1535613Y589724D02*
X1535611Y589726D01*
G01Y594731D02*
X1535610Y594738D01*
G01X1535611Y594726D02*
Y594731D01*
G01X1535613Y594724D02*
X1535611Y594726D01*
G01Y599731D02*
X1535610Y599738D01*
G01X1535611Y599726D02*
Y599731D01*
G01X1535613Y599724D02*
X1535611Y599726D01*
G01Y604731D02*
X1535610Y604738D01*
G01X1535611Y604726D02*
Y604731D01*
G01X1535613Y604724D02*
X1535611Y604726D01*
G01Y609731D02*
X1535610Y609738D01*
G01X1535611Y609726D02*
Y609731D01*
G01X1535613Y609724D02*
X1535611Y609726D01*
G01Y614731D02*
X1535610Y614738D01*
G01X1535611Y614726D02*
Y614731D01*
G01X1535613Y614724D02*
X1535611Y614726D01*
G01Y619731D02*
X1535610Y619738D01*
G01X1535611Y619726D02*
Y619731D01*
G01X1535613Y619724D02*
X1535611Y619726D01*
G01Y624731D02*
X1535610Y624738D01*
G01X1535611Y624726D02*
Y624731D01*
G01X1535613Y624724D02*
X1535611Y624726D01*
G01Y629731D02*
X1535610Y629738D01*
G01X1535611Y629726D02*
Y629731D01*
G01X1535613Y629724D02*
X1535611Y629726D01*
G01X1534626Y574771D02*
Y574780D01*
G01X1534627Y574765D02*
X1534626Y574771D01*
G01X1534628Y574764D02*
X1534627Y574765D01*
G01X1534626Y579771D02*
Y579780D01*
G01X1534627Y579765D02*
X1534626Y579771D01*
G01X1534628Y579764D02*
X1534627Y579765D01*
G01X1534626Y584771D02*
Y584780D01*
G01X1534627Y584765D02*
X1534626Y584771D01*
G01X1534628Y584764D02*
X1534627Y584765D01*
G01X1534626Y589771D02*
Y589780D01*
G01X1534627Y589765D02*
X1534626Y589771D01*
G01X1534628Y589764D02*
X1534627Y589765D01*
G01X1534626Y594771D02*
Y594780D01*
G01X1534627Y594765D02*
X1534626Y594771D01*
G01X1534628Y594764D02*
X1534627Y594765D01*
G01X1534626Y599771D02*
Y599780D01*
G01X1534627Y599765D02*
X1534626Y599771D01*
G01X1534628Y599764D02*
X1534627Y599765D01*
G01X1534626Y604771D02*
Y604780D01*
G01X1534627Y604765D02*
X1534626Y604771D01*
G01X1534628Y604764D02*
X1534627Y604765D01*
G01X1534626Y609771D02*
Y609780D01*
G01X1534627Y609765D02*
X1534626Y609771D01*
G01X1534628Y609764D02*
X1534627Y609765D01*
G01X1534626Y614771D02*
Y614780D01*
G01X1534627Y614765D02*
X1534626Y614771D01*
G01X1534628Y614764D02*
X1534627Y614765D01*
G01X1534626Y619771D02*
Y619780D01*
G01X1534627Y619765D02*
X1534626Y619771D01*
G01X1534628Y619764D02*
X1534627Y619765D01*
G01X1534626Y624771D02*
Y624780D01*
G01X1534627Y624765D02*
X1534626Y624771D01*
G01X1534628Y624764D02*
X1534627Y624765D01*
G01X1534626Y629771D02*
Y629780D01*
G01X1534627Y629765D02*
X1534626Y629771D01*
G01X1534628Y629764D02*
X1534627Y629765D01*
G01X1535602Y574907D02*
X1535610Y574881D01*
G01X1535593Y574934D02*
X1535602Y574907D01*
G01X1535581Y574961D02*
X1535593Y574934D01*
G01X1535602Y579907D02*
X1535610Y579881D01*
G01X1535593Y579934D02*
X1535602Y579907D01*
G01X1535581Y579961D02*
X1535593Y579934D01*
G01X1535602Y584907D02*
X1535610Y584881D01*
G01X1535593Y584934D02*
X1535602Y584907D01*
G01X1535581Y584961D02*
X1535593Y584934D01*
G01X1535602Y589907D02*
X1535610Y589881D01*
G01X1535593Y589934D02*
X1535602Y589907D01*
G01X1535581Y589961D02*
X1535593Y589934D01*
G01X1535602Y594907D02*
X1535610Y594881D01*
G01X1535593Y594934D02*
X1535602Y594907D01*
G01X1535581Y594961D02*
X1535593Y594934D01*
G01X1535602Y599907D02*
X1535610Y599881D01*
G01X1535593Y599934D02*
X1535602Y599907D01*
G01X1535581Y599961D02*
X1535593Y599934D01*
G01X1535602Y604907D02*
X1535610Y604881D01*
G01X1535593Y604934D02*
X1535602Y604907D01*
G01X1535581Y604961D02*
X1535593Y604934D01*
G01X1535602Y609907D02*
X1535610Y609881D01*
G01X1535593Y609934D02*
X1535602Y609907D01*
G01X1535581Y609961D02*
X1535593Y609934D01*
G01X1535602Y614907D02*
X1535610Y614881D01*
G01X1535593Y614934D02*
X1535602Y614907D01*
G01X1535581Y614961D02*
X1535593Y614934D01*
G01X1535602Y619907D02*
X1535610Y619881D01*
G01X1535593Y619934D02*
X1535602Y619907D01*
G01X1535581Y619961D02*
X1535593Y619934D01*
G01X1535602Y624907D02*
X1535610Y624881D01*
G01X1535593Y624934D02*
X1535602Y624907D01*
G01X1535581Y624961D02*
X1535593Y624934D01*
G01X1535602Y629907D02*
X1535610Y629881D01*
G01X1535593Y629934D02*
X1535602Y629907D01*
G01X1535581Y629961D02*
X1535593Y629934D01*
G01Y574759D02*
X1535574Y574764D01*
G01X1535607Y574744D02*
X1535593Y574759D01*
G01X1535613Y574724D02*
X1535607Y574744D01*
G01X1535593Y579759D02*
X1535574Y579764D01*
G01X1535607Y579744D02*
X1535593Y579759D01*
G01X1535613Y579724D02*
X1535607Y579744D01*
G01X1535593Y584759D02*
X1535574Y584764D01*
G01X1535607Y584744D02*
X1535593Y584759D01*
G01X1535613Y584724D02*
X1535607Y584744D01*
G01X1535577Y574862D02*
X1535581Y574961D01*
G01X1535572Y574790D02*
X1535577Y574862D01*
G01X1535574Y574764D02*
X1535572Y574790D01*
G01X1535577Y579862D02*
X1535581Y579961D01*
G01X1535572Y579790D02*
X1535577Y579862D01*
G01X1535574Y579764D02*
X1535572Y579790D01*
G01X1535577Y584862D02*
X1535581Y584961D01*
G01X1535572Y584790D02*
X1535577Y584862D01*
G01X1535574Y584764D02*
X1535572Y584790D01*
G01X1535577Y589862D02*
X1535581Y589961D01*
G01X1535572Y589790D02*
X1535577Y589862D01*
G01X1535574Y589764D02*
X1535572Y589790D01*
G01X1535577Y594862D02*
X1535581Y594961D01*
G01X1535572Y594790D02*
X1535577Y594862D01*
G01X1535574Y594764D02*
X1535572Y594790D01*
G01X1535577Y599862D02*
X1535581Y599961D01*
G01X1535572Y599790D02*
X1535577Y599862D01*
G01X1535574Y599764D02*
X1535572Y599790D01*
G01X1535577Y604862D02*
X1535581Y604961D01*
G01X1535572Y604790D02*
X1535577Y604862D01*
G01X1535574Y604764D02*
X1535572Y604790D01*
G01X1535577Y609862D02*
X1535581Y609961D01*
G01X1535572Y609790D02*
X1535577Y609862D01*
G01X1535574Y609764D02*
X1535572Y609790D01*
G01X1535577Y614862D02*
X1535581Y614961D01*
G01X1535572Y614790D02*
X1535577Y614862D01*
G01X1535574Y614764D02*
X1535572Y614790D01*
G01X1535577Y619862D02*
X1535581Y619961D01*
G01X1535572Y619790D02*
X1535577Y619862D01*
G01X1535574Y619764D02*
X1535572Y619790D01*
G01X1535577Y624862D02*
X1535581Y624961D01*
G01X1535572Y624790D02*
X1535577Y624862D01*
G01X1535574Y624764D02*
X1535572Y624790D01*
G01X1535577Y629862D02*
X1535581Y629961D01*
G01X1535572Y629790D02*
X1535577Y629862D01*
G01X1535574Y629764D02*
X1535572Y629790D01*
G01X1534627Y628384D02*
X1534628Y628386D01*
G01X1534626Y628378D02*
X1534627Y628384D01*
G01X1534626Y628370D02*
Y628378D01*
G01X1534627Y623384D02*
X1534628Y623386D01*
G01X1534626Y623378D02*
X1534627Y623384D01*
G01X1534626Y623370D02*
Y623378D01*
G01X1534627Y618384D02*
X1534628Y618386D01*
G01X1534626Y618378D02*
X1534627Y618384D01*
G01X1534626Y618370D02*
Y618378D01*
G01X1534627Y613384D02*
X1534628Y613386D01*
G01X1534626Y613378D02*
X1534627Y613384D01*
G01X1534626Y613370D02*
Y613378D01*
G01X1534627Y608384D02*
X1534628Y608386D01*
G01X1534626Y608378D02*
X1534627Y608384D01*
G01X1534626Y608370D02*
Y608378D01*
G01X1534627Y603384D02*
X1534628Y603386D01*
G01X1534626Y603378D02*
X1534627Y603384D01*
G01X1534626Y603370D02*
Y603378D01*
G01X1534627Y598384D02*
X1534628Y598386D01*
G01X1534626Y598378D02*
X1534627Y598384D01*
G01X1534626Y598370D02*
Y598378D01*
G01X1534627Y593384D02*
X1534628Y593386D01*
G01X1534626Y593378D02*
X1534627Y593384D01*
G01X1534626Y593370D02*
Y593378D01*
G01X1534627Y588384D02*
X1534628Y588386D01*
G01X1534626Y588378D02*
X1534627Y588384D01*
G01X1534626Y588370D02*
Y588378D01*
G01X1534627Y583384D02*
X1534628Y583386D01*
G01X1534626Y583378D02*
X1534627Y583384D01*
G01X1534626Y583370D02*
Y583378D01*
G01X1534627Y578384D02*
X1534628Y578386D01*
G01X1534626Y578378D02*
X1534627Y578384D01*
G01X1534626Y578370D02*
Y578378D01*
G01X1534627Y573384D02*
X1534628Y573386D01*
G01X1534626Y573378D02*
X1534627Y573384D01*
G01X1534626Y573370D02*
Y573378D01*
G01X1535611Y628378D02*
X1535610Y628369D01*
G01X1535611Y628384D02*
Y628378D01*
G01X1535613Y628386D02*
X1535611Y628384D01*
G01Y623378D02*
X1535610Y623369D01*
G01X1535611Y623384D02*
Y623378D01*
G01X1535613Y623386D02*
X1535611Y623384D01*
G01Y618378D02*
X1535610Y618369D01*
G01X1535611Y618384D02*
Y618378D01*
G01X1535613Y618386D02*
X1535611Y618384D01*
G01Y613378D02*
X1535610Y613369D01*
G01X1535611Y613384D02*
Y613378D01*
G01X1535613Y613386D02*
X1535611Y613384D01*
G01Y608378D02*
X1535610Y608369D01*
G01X1535611Y608384D02*
Y608378D01*
G01X1535613Y608386D02*
X1535611Y608384D01*
G01Y603378D02*
X1535610Y603369D01*
G01X1535611Y603384D02*
Y603378D01*
G01X1535613Y603386D02*
X1535611Y603384D01*
G01Y598378D02*
X1535610Y598369D01*
G01X1535611Y598384D02*
Y598378D01*
G01X1535613Y598386D02*
X1535611Y598384D01*
G01Y593378D02*
X1535610Y593369D01*
G01X1535611Y593384D02*
Y593378D01*
G01X1535613Y593386D02*
X1535611Y593384D01*
G01Y588378D02*
X1535610Y588369D01*
G01X1535611Y588384D02*
Y588378D01*
G01X1535613Y588386D02*
X1535611Y588384D01*
G01Y583378D02*
X1535610Y583369D01*
G01X1535611Y583384D02*
Y583378D01*
G01X1535613Y583386D02*
X1535611Y583384D01*
G01Y578378D02*
X1535610Y578369D01*
G01X1535611Y578384D02*
Y578378D01*
G01X1535613Y578386D02*
X1535611Y578384D01*
G01Y573378D02*
X1535610Y573369D01*
G01X1535611Y573384D02*
Y573378D01*
G01X1535613Y573386D02*
X1535611Y573384D01*
G01X1535593Y589759D02*
X1535574Y589764D01*
G01X1535607Y589744D02*
X1535593Y589759D01*
G01X1535613Y589724D02*
X1535607Y589744D01*
G01X1535593Y594759D02*
X1535574Y594764D01*
G01X1535607Y594744D02*
X1535593Y594759D01*
G01X1535613Y594724D02*
X1535607Y594744D01*
G01X1535593Y599759D02*
X1535574Y599764D01*
G01X1535607Y599744D02*
X1535593Y599759D01*
G01X1535613Y599724D02*
X1535607Y599744D01*
G01X1535593Y604759D02*
X1535574Y604764D01*
G01X1535607Y604744D02*
X1535593Y604759D01*
G01X1535613Y604724D02*
X1535607Y604744D01*
G01X1535593Y609759D02*
X1535574Y609764D01*
G01X1535607Y609744D02*
X1535593Y609759D01*
G01X1535613Y609724D02*
X1535607Y609744D01*
G01X1535593Y614759D02*
X1535574Y614764D01*
G01X1535607Y614744D02*
X1535593Y614759D01*
G01X1535613Y614724D02*
X1535607Y614744D01*
G01X1535593Y619759D02*
X1535574Y619764D01*
G01X1535607Y619744D02*
X1535593Y619759D01*
G01X1535613Y619724D02*
X1535607Y619744D01*
G01X1535593Y624759D02*
X1535574Y624764D01*
G01X1535607Y624744D02*
X1535593Y624759D01*
G01X1535613Y624724D02*
X1535607Y624744D01*
G01X1535593Y629759D02*
X1535574Y629764D01*
G01X1535607Y629744D02*
X1535593Y629759D01*
G01X1535613Y629724D02*
X1535607Y629744D01*
G01X1534055Y655256D02*
G03X1533465Y655846I-590J0D01*
G01X1531299Y652106D02*
G03Y654075I0J984D01*
G01X1533858Y644980D02*
G03X1532677Y646161I-1181J0D01*
G01X1540945Y654665D02*
G03X1538976Y656634I-1969J0D01*
G01X1533609Y645706D02*
X1531299Y641476D01*
G01X1535610Y574738D02*
X1535611Y574746D01*
G01X1535610Y579738D02*
X1535611Y579746D01*
G01X1535610Y584738D02*
X1535611Y584746D01*
G01X1535610Y589738D02*
X1535611Y589746D01*
G01X1535610Y594738D02*
X1535611Y594746D01*
G01X1535610Y599738D02*
X1535611Y599746D01*
G01X1535610Y604738D02*
X1535611Y604746D01*
G01X1535610Y609738D02*
X1535611Y609746D01*
G01X1535610Y614738D02*
X1535611Y614746D01*
G01X1535610Y619738D02*
X1535611Y619746D01*
G01X1535610Y624738D02*
X1535611Y624746D01*
G01X1535610Y629738D02*
X1535611Y629746D01*
G01X1540945Y638917D02*
Y654665D01*
G01X1539961Y628386D02*
Y629764D01*
G01Y623386D02*
Y624764D01*
G01Y618386D02*
Y619764D01*
G01Y613386D02*
Y614764D01*
G01Y608386D02*
Y609764D01*
G01Y603386D02*
Y604764D01*
G01Y598386D02*
Y599764D01*
G01Y593386D02*
Y594764D01*
G01Y588386D02*
Y589764D01*
G01Y583386D02*
Y584764D01*
G01Y578386D02*
Y579764D01*
G01Y573386D02*
Y574764D01*
G01X1536791D02*
Y573386D01*
G01Y579764D02*
Y578386D01*
G01Y584764D02*
Y583386D01*
G01Y589764D02*
Y588386D01*
G01Y594764D02*
Y593386D01*
G01Y599764D02*
Y598386D01*
G01Y604764D02*
Y603386D01*
G01Y609764D02*
Y608386D01*
G01Y614764D02*
Y613386D01*
G01Y619764D02*
Y618386D01*
G01Y624764D02*
Y623386D01*
G01Y629764D02*
Y628386D01*
G01X1535610Y627894D02*
Y630256D01*
G01Y622894D02*
Y625256D01*
G01Y617894D02*
Y620256D01*
G01Y612894D02*
Y615256D01*
G01Y607894D02*
Y610256D01*
G01Y602894D02*
Y605256D01*
G01Y597894D02*
Y600256D01*
G01Y592894D02*
Y595256D01*
G01Y587894D02*
Y590256D01*
G01Y582894D02*
Y585256D01*
G01Y577894D02*
Y580256D01*
G01Y572894D02*
Y575256D01*
G01X1534626D02*
Y572894D01*
G01Y580256D02*
Y577894D01*
G01Y585256D02*
Y582894D01*
G01Y590256D02*
Y587894D01*
G01Y595256D02*
Y592894D01*
G01Y600256D02*
Y597894D01*
G01Y605256D02*
Y602894D01*
G01Y610256D02*
Y607894D01*
G01Y615256D02*
Y612894D01*
G01Y620256D02*
Y617894D01*
G01Y625256D02*
Y622894D01*
G01Y630256D02*
Y627894D01*
G01X1534055Y649154D02*
Y655256D01*
G01X1533858Y644980D02*
Y636437D01*
G01X1531299Y641476D02*
Y639783D01*
G01X1540945Y638917D02*
X1537598Y635571D01*
G01X1531102Y632894D02*
X1532283Y634075D01*
G01X1531299Y639783D02*
X1532603Y637815D01*
G01X1537008Y636437D02*
X1533858D01*
G01X1535610Y630256D02*
X1534626D01*
G01X1534628Y629764D02*
X1539961D01*
G01Y629724D02*
X1535613D01*
G01X1539961Y628386D02*
X1534628D01*
G01X1534626Y627894D02*
X1535610D01*
G01Y625256D02*
X1534626D01*
G01X1534628Y624764D02*
X1539961D01*
G01Y624724D02*
X1535613D01*
G01X1539961Y623386D02*
X1534628D01*
G01X1534626Y622894D02*
X1535610D01*
G01Y620256D02*
X1534626D01*
G01X1534628Y619764D02*
X1539961D01*
G01Y619724D02*
X1535613D01*
G01X1539961Y618386D02*
X1534628D01*
G01X1534626Y617894D02*
X1535610D01*
G01Y615256D02*
X1534626D01*
G01X1534628Y614764D02*
X1539961D01*
G01Y614724D02*
X1535613D01*
G01X1539961Y613386D02*
X1534628D01*
G01X1534626Y612894D02*
X1535610D01*
G01Y610256D02*
X1534626D01*
G01Y629959D02*
X1535581Y629961D01*
G01X1535610Y628190D02*
X1534626Y628189D01*
G01Y624959D02*
X1535581Y624961D01*
G01X1535610Y623190D02*
X1534626Y623189D01*
G01Y619959D02*
X1535581Y619961D01*
G01X1535610Y618190D02*
X1534626Y618189D01*
G01Y614959D02*
X1535581Y614961D01*
G01X1535610Y613190D02*
X1534626Y613189D01*
G01X1534628Y609764D02*
X1539961D01*
G01Y609724D02*
X1535613D01*
G01X1539961Y608386D02*
X1534628D01*
G01X1534626Y607894D02*
X1535610D01*
G01Y605256D02*
X1534626D01*
G01X1534628Y604764D02*
X1539961D01*
G01Y604724D02*
X1535613D01*
G01X1539961Y603386D02*
X1534628D01*
G01X1534626Y602894D02*
X1535610D01*
G01Y600256D02*
X1534626D01*
G01X1534628Y599764D02*
X1539961D01*
G01Y599724D02*
X1535613D01*
G01X1539961Y598386D02*
X1534628D01*
G01X1534626Y597894D02*
X1535610D01*
G01Y595256D02*
X1534626D01*
G01X1534628Y594764D02*
X1539961D01*
G01Y594724D02*
X1535613D01*
G01X1539961Y593386D02*
X1534628D01*
G01X1534626Y592894D02*
X1535610D01*
G01Y590256D02*
X1534626D01*
G01X1534628Y589764D02*
X1539961D01*
G01Y589724D02*
X1535613D01*
G01X1539961Y588386D02*
X1534628D01*
G01X1534626Y587894D02*
X1535610D01*
G01Y585256D02*
X1534626D01*
G01X1534628Y584764D02*
X1539961D01*
G01Y584724D02*
X1535613D01*
G01X1539961Y583386D02*
X1534628D01*
G01X1534626Y582894D02*
X1535610D01*
G01Y580256D02*
X1534626D01*
G01X1534628Y579764D02*
X1539961D01*
G01Y579724D02*
X1535613D01*
G01X1539961Y578386D02*
X1534628D01*
G01X1534626Y577894D02*
X1535610D01*
G01Y575256D02*
X1534626D01*
G01X1534628Y574764D02*
X1539961D01*
G01Y574724D02*
X1535613D01*
G01X1539961Y573386D02*
X1534628D01*
G01X1534626Y572894D02*
X1535610D01*
G01X1534626Y609959D02*
X1535581Y609961D01*
G01X1535610Y608190D02*
X1534626Y608189D01*
G01Y604959D02*
X1535581Y604961D01*
G01X1535610Y603190D02*
X1534626Y603189D01*
G01Y599959D02*
X1535581Y599961D01*
G01X1535610Y598190D02*
X1534626Y598189D01*
G01Y594959D02*
X1535581Y594961D01*
G01X1535610Y593190D02*
X1534626Y593189D01*
G01Y589959D02*
X1535581Y589961D01*
G01X1535610Y588190D02*
X1534626Y588189D01*
G01Y584959D02*
X1535581Y584961D01*
G01X1535610Y583190D02*
X1534626Y583189D01*
G01Y579959D02*
X1535581Y579961D01*
G01X1535610Y578190D02*
X1534626Y578189D01*
G01Y574959D02*
X1535581Y574961D01*
G01X1535610Y573190D02*
X1534626Y573189D01*
G01X1559882Y730599D02*
G03X1566807Y717468I37662J11471D01*
G01X1559882Y730599D02*
G03X1539921I-9980J-3040D01*
G01X1532996Y717468D02*
G03X1539921Y730599I-30737J24601D01*
G01X1614370Y713386D02*
G03X1615551I590J0D01*
G01Y707087D02*
G03X1614370I-590J0D01*
G01X1612402D02*
G03X1611220I-591J0D01*
G01Y713386D02*
G03X1612402I591J0D01*
G01X1614370D02*
G03X1615551I590J0D01*
G01Y707087D02*
G03X1614370I-590J0D01*
G01X1612402D02*
G03X1611220I-591J0D01*
G01Y713386D02*
G03X1612402I591J0D01*
G01X1559882Y730599D02*
G03X1566807Y717468I37662J11471D01*
G01X1559882Y730599D02*
G03X1539921I-9980J-3040D01*
G01X1532996Y717468D02*
G03X1539921Y730599I-30737J24601D01*
G01X1616339Y707087D02*
Y713386D01*
G01Y707087D02*
Y713386D01*
G01X1610433Y707087D02*
Y713386D01*
G01D02*
Y707087D01*
G01X1611220Y713386D02*
X1610433D01*
G01X1611220D02*
X1610433D01*
G01X1614370D02*
X1612402D01*
G01X1616339D02*
X1615551D01*
G01X1614370D02*
X1612402D01*
G01X1616339D02*
X1615551D01*
G01X1616339Y712402D02*
X1610433D01*
G01Y712205D02*
X1616339D01*
G01X1610433Y708268D02*
X1616339D01*
G01Y708071D02*
X1610433D01*
G01X1615551Y707087D02*
X1616339D01*
G01X1612402D02*
X1614370D01*
G01X1615551D02*
X1616339D01*
G01X1612402D02*
X1614370D01*
G01X1610433D02*
X1611220D01*
G01X1610433D02*
X1611220D01*
G01X1532677Y939744D02*
G03X1533858Y940925I0J1181D01*
G01X1533465Y930059D02*
G03X1534055Y930650I0J590D01*
G01X1531299Y931831D02*
G03Y933799I0J984D01*
G01X1538976Y929272D02*
G03X1540945Y931240I1J1968D01*
G01X1531299Y944429D02*
X1533609Y940200D01*
G01X1537598Y950335D02*
X1540945Y946988D01*
G01X1531102Y953012D02*
X1532283Y951831D01*
G01X1540945Y931240D02*
Y946988D01*
G01X1537598Y1088327D02*
Y950335D01*
G01X1537008Y1090571D02*
Y948091D01*
G01X1534055Y936752D02*
Y930650D01*
G01X1533858Y949469D02*
Y940925D01*
G01X1532283Y988287D02*
Y951831D01*
G01X1531299Y946122D02*
Y944429D01*
G01X1532603Y948091D02*
X1531299Y946122D01*
G01X1533858Y949469D02*
X1537008D01*
G01X1535611Y1046134D02*
X1535610Y1046125D01*
G01X1535611Y1046140D02*
Y1046134D01*
G01X1535613Y1046142D02*
X1535611Y1046140D01*
G01Y1041134D02*
X1535610Y1041125D01*
G01X1535611Y1041140D02*
Y1041134D01*
G01X1535613Y1041142D02*
X1535611Y1041140D01*
G01Y1036134D02*
X1535610Y1036125D01*
G01X1535611Y1036140D02*
Y1036134D01*
G01X1535613Y1036142D02*
X1535611Y1036140D01*
G01Y1031134D02*
X1535610Y1031125D01*
G01X1535611Y1031140D02*
Y1031134D01*
G01X1535613Y1031142D02*
X1535611Y1031140D01*
G01Y1026134D02*
X1535610Y1026125D01*
G01X1535611Y1026140D02*
Y1026134D01*
G01X1535613Y1026142D02*
X1535611Y1026140D01*
G01Y1021134D02*
X1535610Y1021125D01*
G01X1535611Y1021140D02*
Y1021134D01*
G01X1535613Y1021142D02*
X1535611Y1021140D01*
G01Y1016134D02*
X1535610Y1016125D01*
G01X1535611Y1016140D02*
Y1016134D01*
G01X1535613Y1016142D02*
X1535611Y1016140D01*
G01Y1011134D02*
X1535610Y1011125D01*
G01X1535611Y1011140D02*
Y1011134D01*
G01X1535613Y1011142D02*
X1535611Y1011140D01*
G01Y986134D02*
X1535610Y986125D01*
G01X1535611Y986140D02*
Y986134D01*
G01X1535613Y986142D02*
X1535611Y986140D01*
G01Y981134D02*
X1535610Y981125D01*
G01X1535611Y981140D02*
Y981134D01*
G01X1535613Y981142D02*
X1535611Y981140D01*
G01Y976134D02*
X1535610Y976125D01*
G01X1535611Y976140D02*
Y976134D01*
G01X1535613Y976142D02*
X1535611Y976140D01*
G01Y971134D02*
X1535610Y971125D01*
G01X1535611Y971140D02*
Y971134D01*
G01X1535613Y971142D02*
X1535611Y971140D01*
G01Y966134D02*
X1535610Y966125D01*
G01X1535611Y966140D02*
Y966134D01*
G01X1535613Y966142D02*
X1535611Y966140D01*
G01Y961134D02*
X1535610Y961125D01*
G01X1535611Y961140D02*
Y961134D01*
G01X1535613Y961142D02*
X1535611Y961140D01*
G01Y956134D02*
X1535610Y956125D01*
G01X1535611Y956140D02*
Y956134D01*
G01X1535613Y956142D02*
X1535611Y956140D01*
G01X1535598Y957511D02*
X1535609Y957496D01*
G01X1535573Y957520D02*
X1535598Y957511D01*
G01Y962511D02*
X1535609Y962496D01*
G01X1535573Y962520D02*
X1535598Y962511D01*
G01Y967511D02*
X1535609Y967496D01*
G01X1535573Y967520D02*
X1535598Y967511D01*
G01Y972511D02*
X1535609Y972496D01*
G01X1535573Y972520D02*
X1535598Y972511D01*
G01Y977511D02*
X1535609Y977496D01*
G01X1535573Y977520D02*
X1535598Y977511D01*
G01Y982511D02*
X1535609Y982496D01*
G01X1535573Y982520D02*
X1535598Y982511D01*
G01Y987511D02*
X1535609Y987496D01*
G01X1535573Y987520D02*
X1535598Y987511D01*
G01Y1012511D02*
X1535609Y1012496D01*
G01X1535573Y1012520D02*
X1535598Y1012511D01*
G01Y1017511D02*
X1535609Y1017496D01*
G01X1535573Y1017520D02*
X1535598Y1017511D01*
G01Y1022511D02*
X1535609Y1022496D01*
G01X1535573Y1022520D02*
X1535598Y1022511D01*
G01Y1027511D02*
X1535609Y1027496D01*
G01X1535573Y1027520D02*
X1535598Y1027511D01*
G01Y1032511D02*
X1535609Y1032496D01*
G01X1535573Y1032520D02*
X1535598Y1032511D01*
G01Y1037511D02*
X1535609Y1037496D01*
G01X1535573Y1037520D02*
X1535598Y1037511D01*
G01Y1042511D02*
X1535609Y1042496D01*
G01X1535573Y1042520D02*
X1535598Y1042511D01*
G01Y1047511D02*
X1535609Y1047496D01*
G01X1535573Y1047520D02*
X1535598Y1047511D01*
G01X1535577Y957618D02*
X1535581Y957717D01*
G01X1535572Y957546D02*
X1535577Y957618D01*
G01X1535574Y957520D02*
X1535572Y957546D01*
G01X1535577Y962618D02*
X1535581Y962717D01*
G01X1535572Y962546D02*
X1535577Y962618D01*
G01X1535574Y962520D02*
X1535572Y962546D01*
G01X1535577Y967618D02*
X1535581Y967717D01*
G01X1535572Y967546D02*
X1535577Y967618D01*
G01X1535574Y967520D02*
X1535572Y967546D01*
G01X1535577Y972618D02*
X1535581Y972717D01*
G01X1535572Y972546D02*
X1535577Y972618D01*
G01X1535574Y972520D02*
X1535572Y972546D01*
G01X1535577Y977618D02*
X1535581Y977717D01*
G01X1535572Y977546D02*
X1535577Y977618D01*
G01X1535574Y977520D02*
X1535572Y977546D01*
G01X1535577Y982618D02*
X1535581Y982717D01*
G01X1535572Y982546D02*
X1535577Y982618D01*
G01X1535574Y982520D02*
X1535572Y982546D01*
G01X1535577Y987618D02*
X1535581Y987717D01*
G01X1535572Y987546D02*
X1535577Y987618D01*
G01X1535574Y987520D02*
X1535572Y987546D01*
G01X1535577Y1012618D02*
X1535581Y1012717D01*
G01X1535572Y1012546D02*
X1535577Y1012618D01*
G01X1535574Y1012520D02*
X1535572Y1012546D01*
G01X1535577Y1017618D02*
X1535581Y1017717D01*
G01X1535572Y1017546D02*
X1535577Y1017618D01*
G01X1535574Y1017520D02*
X1535572Y1017546D01*
G01X1535577Y1022618D02*
X1535581Y1022717D01*
G01X1535572Y1022546D02*
X1535577Y1022618D01*
G01X1535574Y1022520D02*
X1535572Y1022546D01*
G01X1535577Y1027618D02*
X1535581Y1027717D01*
G01X1535572Y1027546D02*
X1535577Y1027618D01*
G01X1535574Y1027520D02*
X1535572Y1027546D01*
G01X1535577Y1032618D02*
X1535581Y1032717D01*
G01X1535572Y1032546D02*
X1535577Y1032618D01*
G01X1535574Y1032520D02*
X1535572Y1032546D01*
G01X1535577Y1037618D02*
X1535581Y1037717D01*
G01X1535572Y1037546D02*
X1535577Y1037618D01*
G01X1535574Y1037520D02*
X1535572Y1037546D01*
G01X1535577Y1042618D02*
X1535581Y1042717D01*
G01X1535572Y1042546D02*
X1535577Y1042618D01*
G01X1535574Y1042520D02*
X1535572Y1042546D01*
G01X1534627Y1046140D02*
X1534628Y1046142D01*
G01X1534626Y1046134D02*
X1534627Y1046140D01*
G01X1534626Y1046126D02*
Y1046134D01*
G01X1534627Y1041140D02*
X1534628Y1041142D01*
G01X1534626Y1041134D02*
X1534627Y1041140D01*
G01X1534626Y1041126D02*
Y1041134D01*
G01X1534627Y1036140D02*
X1534628Y1036142D01*
G01X1534626Y1036134D02*
X1534627Y1036140D01*
G01X1534626Y1036126D02*
Y1036134D01*
G01X1534627Y1031140D02*
X1534628Y1031142D01*
G01X1534626Y1031134D02*
X1534627Y1031140D01*
G01X1534626Y1031126D02*
Y1031134D01*
G01X1534627Y1026140D02*
X1534628Y1026142D01*
G01X1534626Y1026134D02*
X1534627Y1026140D01*
G01X1534626Y1026126D02*
Y1026134D01*
G01X1534627Y1021140D02*
X1534628Y1021142D01*
G01X1534626Y1021134D02*
X1534627Y1021140D01*
G01X1534626Y1021126D02*
Y1021134D01*
G01X1534627Y1016140D02*
X1534628Y1016142D01*
G01X1534626Y1016134D02*
X1534627Y1016140D01*
G01X1534626Y1016126D02*
Y1016134D01*
G01X1534627Y1011140D02*
X1534628Y1011142D01*
G01X1534626Y1011134D02*
X1534627Y1011140D01*
G01X1534626Y1011126D02*
Y1011134D01*
G01X1534627Y986140D02*
X1534628Y986142D01*
G01X1534626Y986134D02*
X1534627Y986140D01*
G01X1534626Y986126D02*
Y986134D01*
G01X1534627Y981140D02*
X1534628Y981142D01*
G01X1534626Y981134D02*
X1534627Y981140D01*
G01X1534626Y981126D02*
Y981134D01*
G01X1534627Y976140D02*
X1534628Y976142D01*
G01X1534626Y976134D02*
X1534627Y976140D01*
G01X1534626Y976126D02*
Y976134D01*
G01X1534627Y971140D02*
X1534628Y971142D01*
G01X1534626Y971134D02*
X1534627Y971140D01*
G01X1534626Y971126D02*
Y971134D01*
G01X1534627Y966140D02*
X1534628Y966142D01*
G01X1534626Y966134D02*
X1534627Y966140D01*
G01X1534626Y966126D02*
Y966134D01*
G01X1534627Y961140D02*
X1534628Y961142D01*
G01X1534626Y961134D02*
X1534627Y961140D01*
G01X1534626Y961126D02*
Y961134D01*
G01X1534627Y956140D02*
X1534628Y956142D01*
G01X1534626Y956134D02*
X1534627Y956140D01*
G01X1534626Y956126D02*
Y956134D01*
G01X1535611Y957487D02*
X1535610Y957494D01*
G01X1535611Y957482D02*
Y957487D01*
G01X1535613Y957480D02*
X1535611Y957482D01*
G01Y962487D02*
X1535610Y962494D01*
G01X1535611Y962482D02*
Y962487D01*
G01X1535613Y962480D02*
X1535611Y962482D01*
G01Y967487D02*
X1535610Y967494D01*
G01X1535611Y967482D02*
Y967487D01*
G01X1535613Y967480D02*
X1535611Y967482D01*
G01Y972487D02*
X1535610Y972494D01*
G01X1535611Y972482D02*
Y972487D01*
G01X1535613Y972480D02*
X1535611Y972482D01*
G01Y977487D02*
X1535610Y977494D01*
G01X1535611Y977482D02*
Y977487D01*
G01X1535613Y977480D02*
X1535611Y977482D01*
G01Y982487D02*
X1535610Y982494D01*
G01X1535611Y982482D02*
Y982487D01*
G01X1535613Y982480D02*
X1535611Y982482D01*
G01Y987487D02*
X1535610Y987494D01*
G01X1535611Y987482D02*
Y987487D01*
G01X1535613Y987480D02*
X1535611Y987482D01*
G01Y1012487D02*
X1535610Y1012494D01*
G01X1535611Y1012482D02*
Y1012487D01*
G01X1535613Y1012480D02*
X1535611Y1012482D01*
G01Y1017487D02*
X1535610Y1017494D01*
G01X1535611Y1017482D02*
Y1017487D01*
G01X1535613Y1017480D02*
X1535611Y1017482D01*
G01Y1022487D02*
X1535610Y1022494D01*
G01X1535611Y1022482D02*
Y1022487D01*
G01X1535613Y1022480D02*
X1535611Y1022482D01*
G01Y1027487D02*
X1535610Y1027494D01*
G01X1535611Y1027482D02*
Y1027487D01*
G01X1535613Y1027480D02*
X1535611Y1027482D01*
G01Y1032487D02*
X1535610Y1032494D01*
G01X1535611Y1032482D02*
Y1032487D01*
G01X1535613Y1032480D02*
X1535611Y1032482D01*
G01Y1037487D02*
X1535610Y1037494D01*
G01X1535611Y1037482D02*
Y1037487D01*
G01X1535613Y1037480D02*
X1535611Y1037482D01*
G01Y1042487D02*
X1535610Y1042494D01*
G01X1535611Y1042482D02*
Y1042487D01*
G01X1535613Y1042480D02*
X1535611Y1042482D01*
G01Y1047487D02*
X1535610Y1047494D01*
G01X1535613Y1047480D02*
X1535611Y1047482D01*
G01X1534626Y957527D02*
Y957536D01*
G01X1534627Y957521D02*
X1534626Y957527D01*
G01X1534628Y957520D02*
X1534627Y957521D01*
G01X1534626Y962527D02*
Y962536D01*
G01X1534627Y962521D02*
X1534626Y962527D01*
G01X1534628Y962520D02*
X1534627Y962521D01*
G01X1534626Y967527D02*
Y967536D01*
G01X1534627Y967521D02*
X1534626Y967527D01*
G01X1534628Y967520D02*
X1534627Y967521D01*
G01X1534626Y972527D02*
Y972536D01*
G01X1534627Y972521D02*
X1534626Y972527D01*
G01X1534628Y972520D02*
X1534627Y972521D01*
G01X1534626Y977527D02*
Y977536D01*
G01X1534627Y977521D02*
X1534626Y977527D01*
G01X1534628Y977520D02*
X1534627Y977521D01*
G01X1534626Y982527D02*
Y982536D01*
G01X1534627Y982521D02*
X1534626Y982527D01*
G01X1534628Y982520D02*
X1534627Y982521D01*
G01X1534626Y987527D02*
Y987536D01*
G01X1534627Y987521D02*
X1534626Y987527D01*
G01X1534628Y987520D02*
X1534627Y987521D01*
G01X1534626Y1012527D02*
Y1012536D01*
G01X1534627Y1012521D02*
X1534626Y1012527D01*
G01X1534628Y1012520D02*
X1534627Y1012521D01*
G01X1534626Y1017527D02*
Y1017536D01*
G01X1534627Y1017521D02*
X1534626Y1017527D01*
G01X1534628Y1017520D02*
X1534627Y1017521D01*
G01X1534626Y1022527D02*
Y1022536D01*
G01X1534627Y1022521D02*
X1534626Y1022527D01*
G01X1534628Y1022520D02*
X1534627Y1022521D01*
G01X1534626Y1027527D02*
Y1027536D01*
G01X1534627Y1027521D02*
X1534626Y1027527D01*
G01X1534628Y1027520D02*
X1534627Y1027521D01*
G01X1534626Y1032527D02*
Y1032536D01*
G01X1534627Y1032521D02*
X1534626Y1032527D01*
G01X1534628Y1032520D02*
X1534627Y1032521D01*
G01X1534626Y1037527D02*
Y1037536D01*
G01X1534627Y1037521D02*
X1534626Y1037527D01*
G01X1534628Y1037520D02*
X1534627Y1037521D01*
G01X1534626Y1042527D02*
Y1042536D01*
G01X1534627Y1042521D02*
X1534626Y1042527D01*
G01X1534628Y1042520D02*
X1534627Y1042521D01*
G01X1534628Y1047520D02*
X1534627Y1047521D01*
G01X1535602Y957663D02*
X1535610Y957637D01*
G01X1535593Y957690D02*
X1535602Y957663D01*
G01X1535581Y957717D02*
X1535593Y957690D01*
G01X1535602Y962663D02*
X1535610Y962637D01*
G01X1535593Y962690D02*
X1535602Y962663D01*
G01X1535581Y962717D02*
X1535593Y962690D01*
G01X1535602Y967663D02*
X1535610Y967637D01*
G01X1535593Y967690D02*
X1535602Y967663D01*
G01X1535581Y967717D02*
X1535593Y967690D01*
G01X1535602Y972663D02*
X1535610Y972637D01*
G01X1535593Y972690D02*
X1535602Y972663D01*
G01X1535581Y972717D02*
X1535593Y972690D01*
G01X1535602Y977663D02*
X1535610Y977637D01*
G01X1535593Y977690D02*
X1535602Y977663D01*
G01X1535581Y977717D02*
X1535593Y977690D01*
G01X1535602Y982663D02*
X1535610Y982637D01*
G01X1535593Y982690D02*
X1535602Y982663D01*
G01X1535581Y982717D02*
X1535593Y982690D01*
G01X1535602Y987663D02*
X1535610Y987637D01*
G01X1535593Y987690D02*
X1535602Y987663D01*
G01X1535581Y987717D02*
X1535593Y987690D01*
G01X1535602Y1012663D02*
X1535610Y1012637D01*
G01X1535593Y1012690D02*
X1535602Y1012663D01*
G01X1535581Y1012717D02*
X1535593Y1012690D01*
G01X1535602Y1017663D02*
X1535610Y1017637D01*
G01X1535593Y1017690D02*
X1535602Y1017663D01*
G01X1535581Y1017717D02*
X1535593Y1017690D01*
G01X1535602Y1022663D02*
X1535610Y1022637D01*
G01X1535593Y1022690D02*
X1535602Y1022663D01*
G01X1535581Y1022717D02*
X1535593Y1022690D01*
G01X1535602Y1027663D02*
X1535610Y1027637D01*
G01X1535593Y1027690D02*
X1535602Y1027663D01*
G01X1535581Y1027717D02*
X1535593Y1027690D01*
G01X1535602Y1032663D02*
X1535610Y1032637D01*
G01X1535593Y1032690D02*
X1535602Y1032663D01*
G01X1535581Y1032717D02*
X1535593Y1032690D01*
G01X1535602Y1037663D02*
X1535610Y1037637D01*
G01X1535593Y1037690D02*
X1535602Y1037663D01*
G01X1535581Y1037717D02*
X1535593Y1037690D01*
G01X1535602Y1042663D02*
X1535610Y1042637D01*
G01X1535593Y1042690D02*
X1535602Y1042663D01*
G01X1535581Y1042717D02*
X1535593Y1042690D01*
G01Y957515D02*
X1535574Y957520D01*
G01X1535607Y957500D02*
X1535593Y957515D01*
G01X1535613Y957480D02*
X1535607Y957500D01*
G01X1535593Y962515D02*
X1535574Y962520D01*
G01X1535607Y962500D02*
X1535593Y962515D01*
G01X1535613Y962480D02*
X1535607Y962500D01*
G01X1535593Y967515D02*
X1535574Y967520D01*
G01X1535607Y967500D02*
X1535593Y967515D01*
G01X1535613Y967480D02*
X1535607Y967500D01*
G01X1535593Y972515D02*
X1535574Y972520D01*
G01X1535607Y972500D02*
X1535593Y972515D01*
G01X1535613Y972480D02*
X1535607Y972500D01*
G01X1535593Y977515D02*
X1535574Y977520D01*
G01X1535607Y977500D02*
X1535593Y977515D01*
G01X1535613Y977480D02*
X1535607Y977500D01*
G01X1535593Y982515D02*
X1535574Y982520D01*
G01X1535607Y982500D02*
X1535593Y982515D01*
G01X1535613Y982480D02*
X1535607Y982500D01*
G01X1535593Y987515D02*
X1535574Y987520D01*
G01X1535607Y987500D02*
X1535593Y987515D01*
G01X1535613Y987480D02*
X1535607Y987500D01*
G01X1535593Y1012515D02*
X1535574Y1012520D01*
G01X1535607Y1012500D02*
X1535593Y1012515D01*
G01X1535613Y1012480D02*
X1535607Y1012500D01*
G01X1535593Y1017515D02*
X1535574Y1017520D01*
G01X1535607Y1017500D02*
X1535593Y1017515D01*
G01X1535613Y1017480D02*
X1535607Y1017500D01*
G01X1535593Y1022515D02*
X1535574Y1022520D01*
G01X1535607Y1022500D02*
X1535593Y1022515D01*
G01X1535613Y1022480D02*
X1535607Y1022500D01*
G01X1535593Y1027515D02*
X1535574Y1027520D01*
G01X1535607Y1027500D02*
X1535593Y1027515D01*
G01X1535613Y1027480D02*
X1535607Y1027500D01*
G01X1535593Y1032515D02*
X1535574Y1032520D01*
G01X1535607Y1032500D02*
X1535593Y1032515D01*
G01X1535613Y1032480D02*
X1535607Y1032500D01*
G01X1535593Y1037515D02*
X1535574Y1037520D01*
G01X1535607Y1037500D02*
X1535593Y1037515D01*
G01X1535613Y1037480D02*
X1535607Y1037500D01*
G01X1535593Y1042515D02*
X1535574Y1042520D01*
G01X1535607Y1042500D02*
X1535593Y1042515D01*
G01X1535613Y1042480D02*
X1535607Y1042500D01*
G01X1535593Y1047515D02*
X1535574Y1047520D01*
G01X1535607Y1047500D02*
X1535593Y1047515D01*
G01X1535613Y1047480D02*
X1535607Y1047500D01*
G01X1535039Y989469D02*
X1536220Y988287D01*
G01X1531102Y989469D02*
X1532283Y988287D01*
G01X1535610Y957494D02*
X1535611Y957502D01*
G01X1535610Y962494D02*
X1535611Y962502D01*
G01X1535610Y967494D02*
X1535611Y967502D01*
G01X1535610Y972494D02*
X1535611Y972502D01*
G01X1535610Y977494D02*
X1535611Y977502D01*
G01X1535610Y982494D02*
X1535611Y982502D01*
G01X1535610Y987494D02*
X1535611Y987502D01*
G01X1535610Y1012494D02*
X1535611Y1012502D01*
G01X1535610Y1017494D02*
X1535611Y1017502D01*
G01X1535610Y1022494D02*
X1535611Y1022502D01*
G01X1535610Y1027494D02*
X1535611Y1027502D01*
G01X1535610Y1032494D02*
X1535611Y1032502D01*
G01X1535610Y1037494D02*
X1535611Y1037502D01*
G01X1535610Y1042494D02*
X1535611Y1042502D01*
G01X1539961Y1046142D02*
Y1047520D01*
G01Y1041142D02*
Y1042520D01*
G01Y1036142D02*
Y1037520D01*
G01Y1031142D02*
Y1032520D01*
G01Y1026142D02*
Y1027520D01*
G01Y1021142D02*
Y1022520D01*
G01Y1016142D02*
Y1017520D01*
G01Y1011142D02*
Y1012520D01*
G01Y986142D02*
Y987520D01*
G01Y981142D02*
Y982520D01*
G01Y976142D02*
Y977520D01*
G01Y971142D02*
Y972520D01*
G01Y966142D02*
Y967520D01*
G01Y961142D02*
Y962520D01*
G01Y956142D02*
Y957520D01*
G01X1536791D02*
Y956142D01*
G01Y962520D02*
Y961142D01*
G01Y967520D02*
Y966142D01*
G01Y972520D02*
Y971142D01*
G01Y977520D02*
Y976142D01*
G01Y982520D02*
Y981142D01*
G01Y987520D02*
Y986142D01*
G01Y1012520D02*
Y1011142D01*
G01Y1017520D02*
Y1016142D01*
G01Y1022520D02*
Y1021142D01*
G01Y1027520D02*
Y1026142D01*
G01Y1032520D02*
Y1031142D01*
G01Y1037520D02*
Y1036142D01*
G01Y1042520D02*
Y1041142D01*
G01Y1047520D02*
Y1046142D01*
G01X1536220Y1010374D02*
Y988287D01*
G01X1535610Y1045650D02*
Y1048012D01*
G01Y1040650D02*
Y1043012D01*
G01Y1035650D02*
Y1038012D01*
G01Y1030650D02*
Y1033012D01*
G01Y1025650D02*
Y1028012D01*
G01Y1020650D02*
Y1023012D01*
G01Y1015650D02*
Y1018012D01*
G01Y1010650D02*
Y1013012D01*
G01Y985650D02*
Y988012D01*
G01Y980650D02*
Y983012D01*
G01Y975650D02*
Y978012D01*
G01Y970650D02*
Y973012D01*
G01Y965650D02*
Y968012D01*
G01Y960650D02*
Y963012D01*
G01Y955650D02*
Y958012D01*
G01Y962494D02*
Y962637D01*
G01Y967494D02*
Y967637D01*
G01Y972494D02*
Y972637D01*
G01Y977494D02*
Y977637D01*
G01Y982494D02*
Y982637D01*
G01Y987494D02*
Y987637D01*
G01Y1012494D02*
Y1012637D01*
G01Y1017494D02*
Y1017637D01*
G01Y1022494D02*
Y1022637D01*
G01Y1027494D02*
Y1027637D01*
G01Y1032494D02*
Y1032637D01*
G01Y1037494D02*
Y1037637D01*
G01Y1042494D02*
Y1042637D01*
G01X1535039Y1009193D02*
Y989469D01*
G01X1534626Y958012D02*
Y955650D01*
G01Y963012D02*
Y960650D01*
G01Y968012D02*
Y965650D01*
G01Y973012D02*
Y970650D01*
G01Y978012D02*
Y975650D01*
G01Y983012D02*
Y980650D01*
G01Y988012D02*
Y985650D01*
G01Y1013012D02*
Y1010650D01*
G01Y1018012D02*
Y1015650D01*
G01Y1023012D02*
Y1020650D01*
G01Y1028012D02*
Y1025650D01*
G01Y1033012D02*
Y1030650D01*
G01Y1038012D02*
Y1035650D01*
G01Y1043012D02*
Y1040650D01*
G01Y1048012D02*
Y1045650D01*
G01X1532283Y1086831D02*
Y1010374D01*
G01X1531102Y989469D02*
Y953012D01*
G01Y1085650D02*
Y1009193D01*
G01X1539961Y1046142D02*
X1534628D01*
G01X1534626Y1045650D02*
X1535610D01*
G01Y1043012D02*
X1534626D01*
G01X1534628Y1042520D02*
X1539961D01*
G01Y1042480D02*
X1535613D01*
G01X1539961Y1041142D02*
X1534628D01*
G01X1534626Y1040650D02*
X1535610D01*
G01Y1038012D02*
X1534626D01*
G01X1534628Y1037520D02*
X1539961D01*
G01Y1037480D02*
X1535613D01*
G01X1539961Y1036142D02*
X1534628D01*
G01X1534626Y1035650D02*
X1535610D01*
G01Y1033012D02*
X1534626D01*
G01X1534628Y1032520D02*
X1539961D01*
G01Y1032480D02*
X1535613D01*
G01X1539961Y1031142D02*
X1534628D01*
G01X1534626Y1030650D02*
X1535610D01*
G01Y1028012D02*
X1534626D01*
G01X1534628Y1027520D02*
X1539961D01*
G01Y1027480D02*
X1535613D01*
G01X1539961Y1026142D02*
X1534628D01*
G01X1534626Y1025650D02*
X1535610D01*
G01Y1023012D02*
X1534626D01*
G01X1534628Y1022520D02*
X1539961D01*
G01Y1022480D02*
X1535613D01*
G01X1539961Y1021142D02*
X1534628D01*
G01X1535610Y1045946D02*
X1534626Y1045945D01*
G01Y1042715D02*
X1535581Y1042717D01*
G01X1535610Y1040946D02*
X1534626Y1040945D01*
G01Y1037715D02*
X1535581Y1037717D01*
G01X1535610Y1035946D02*
X1534626Y1035945D01*
G01Y1032715D02*
X1535581Y1032717D01*
G01X1535610Y1030946D02*
X1534626Y1030945D01*
G01Y1027715D02*
X1535581Y1027717D01*
G01X1535610Y1025946D02*
X1534626Y1025945D01*
G01Y1022715D02*
X1535581Y1022717D01*
G01X1534626Y1020650D02*
X1535610D01*
G01Y1018012D02*
X1534626D01*
G01X1534628Y1017520D02*
X1539961D01*
G01Y1017480D02*
X1535613D01*
G01X1539961Y1016142D02*
X1534628D01*
G01X1534626Y1015650D02*
X1535610D01*
G01Y1013012D02*
X1534626D01*
G01X1534628Y1012520D02*
X1539961D01*
G01Y1012480D02*
X1535613D01*
G01X1539961Y1011142D02*
X1534628D01*
G01X1534626Y1010650D02*
X1535610D01*
G01X1532283Y1010374D02*
X1536220D01*
G01X1531102Y1009193D02*
X1535039D01*
G01Y989469D02*
X1531102D01*
G01X1536220Y988287D02*
X1532283D01*
G01X1535610Y988012D02*
X1534626D01*
G01X1534628Y987520D02*
X1539961D01*
G01Y987480D02*
X1535613D01*
G01X1539961Y986142D02*
X1534628D01*
G01X1534626Y985650D02*
X1535610D01*
G01Y983012D02*
X1534626D01*
G01X1534628Y982520D02*
X1539961D01*
G01Y982480D02*
X1535613D01*
G01X1539961Y981142D02*
X1534628D01*
G01X1534626Y980650D02*
X1535610D01*
G01Y978012D02*
X1534626D01*
G01X1534628Y977520D02*
X1539961D01*
G01Y977480D02*
X1535613D01*
G01X1539961Y976142D02*
X1534628D01*
G01X1534626Y975650D02*
X1535610D01*
G01Y973012D02*
X1534626D01*
G01X1534628Y972520D02*
X1539961D01*
G01Y972480D02*
X1535613D01*
G01X1539961Y971142D02*
X1534628D01*
G01X1534626Y970650D02*
X1535610D01*
G01Y968012D02*
X1534626D01*
G01X1534628Y967520D02*
X1539961D01*
G01Y967480D02*
X1535613D01*
G01X1539961Y966142D02*
X1534628D01*
G01X1534626Y965650D02*
X1535610D01*
G01Y963012D02*
X1534626D01*
G01X1534628Y962520D02*
X1539961D01*
G01Y962480D02*
X1535613D01*
G01X1539961Y961142D02*
X1534628D01*
G01X1534626Y960650D02*
X1535610D01*
G01Y958012D02*
X1534626D01*
G01X1534628Y957520D02*
X1539961D01*
G01Y957480D02*
X1535613D01*
G01X1539961Y956142D02*
X1534628D01*
G01X1534626Y955650D02*
X1535610D01*
G01Y1020946D02*
X1534626Y1020945D01*
G01Y1017715D02*
X1535581Y1017717D01*
G01X1535610Y1015946D02*
X1534626Y1015945D01*
G01Y1012715D02*
X1535581Y1012717D01*
G01X1535610Y1010946D02*
X1534626Y1010945D01*
G01Y987715D02*
X1535581Y987717D01*
G01X1535610Y985946D02*
X1534626Y985945D01*
G01Y982715D02*
X1535581Y982717D01*
G01X1535610Y980946D02*
X1534626Y980945D01*
G01Y977715D02*
X1535581Y977717D01*
G01X1535610Y975946D02*
X1534626Y975945D01*
G01Y972715D02*
X1535581Y972717D01*
G01X1535610Y970946D02*
X1534626Y970945D01*
G01Y967715D02*
X1535581Y967717D01*
G01X1535610Y965946D02*
X1534626Y965945D01*
G01Y962715D02*
X1535581Y962717D01*
G01X1535610Y960946D02*
X1534626Y960945D01*
G01Y957715D02*
X1535581Y957717D01*
G01X1535610Y955946D02*
X1534626Y955945D01*
G01X1535039Y1009193D02*
X1536220Y1010374D01*
G01X1531102Y1009193D02*
X1532283Y1010374D01*
G01X1535611Y1081134D02*
X1535610Y1081125D01*
G01X1535611Y1081140D02*
Y1081134D01*
G01X1535613Y1081142D02*
X1535611Y1081140D01*
G01Y1076134D02*
X1535610Y1076125D01*
G01X1535611Y1076140D02*
Y1076134D01*
G01X1535613Y1076142D02*
X1535611Y1076140D01*
G01Y1071134D02*
X1535610Y1071125D01*
G01X1535611Y1071140D02*
Y1071134D01*
G01X1535613Y1071142D02*
X1535611Y1071140D01*
G01Y1066134D02*
X1535610Y1066125D01*
G01X1535611Y1066140D02*
Y1066134D01*
G01X1535613Y1066142D02*
X1535611Y1066140D01*
G01Y1061134D02*
X1535610Y1061125D01*
G01X1535611Y1061140D02*
Y1061134D01*
G01X1535613Y1061142D02*
X1535611Y1061140D01*
G01Y1056134D02*
X1535610Y1056125D01*
G01X1535611Y1056140D02*
Y1056134D01*
G01X1535613Y1056142D02*
X1535611Y1056140D01*
G01Y1051134D02*
X1535610Y1051125D01*
G01X1535611Y1051140D02*
Y1051134D01*
G01X1535613Y1051142D02*
X1535611Y1051140D01*
G01X1535598Y1052511D02*
X1535609Y1052496D01*
G01X1535573Y1052520D02*
X1535598Y1052511D01*
G01Y1057511D02*
X1535609Y1057496D01*
G01X1535573Y1057520D02*
X1535598Y1057511D01*
G01Y1062511D02*
X1535609Y1062496D01*
G01X1535573Y1062520D02*
X1535598Y1062511D01*
G01Y1067511D02*
X1535609Y1067496D01*
G01X1535573Y1067520D02*
X1535598Y1067511D01*
G01Y1072511D02*
X1535609Y1072496D01*
G01X1535573Y1072520D02*
X1535598Y1072511D01*
G01Y1077511D02*
X1535609Y1077496D01*
G01X1535573Y1077520D02*
X1535598Y1077511D01*
G01Y1082511D02*
X1535609Y1082496D01*
G01X1535573Y1082520D02*
X1535598Y1082511D01*
G01X1534627Y1081140D02*
X1534628Y1081142D01*
G01X1534626Y1081134D02*
X1534627Y1081140D01*
G01X1534626Y1081126D02*
Y1081134D01*
G01X1534627Y1076140D02*
X1534628Y1076142D01*
G01X1534626Y1076134D02*
X1534627Y1076140D01*
G01X1534626Y1076126D02*
Y1076134D01*
G01X1534627Y1071140D02*
X1534628Y1071142D01*
G01X1534626Y1071134D02*
X1534627Y1071140D01*
G01X1534626Y1071126D02*
Y1071134D01*
G01X1534627Y1066140D02*
X1534628Y1066142D01*
G01X1534626Y1066134D02*
X1534627Y1066140D01*
G01X1534626Y1066126D02*
Y1066134D01*
G01X1534627Y1061140D02*
X1534628Y1061142D01*
G01X1534626Y1061134D02*
X1534627Y1061140D01*
G01X1534626Y1061126D02*
Y1061134D01*
G01X1534627Y1056140D02*
X1534628Y1056142D01*
G01X1534626Y1056134D02*
X1534627Y1056140D01*
G01X1534626Y1056126D02*
Y1056134D01*
G01X1534627Y1051140D02*
X1534628Y1051142D01*
G01X1534626Y1051134D02*
X1534627Y1051140D01*
G01X1534626Y1051126D02*
Y1051134D01*
G01X1535577Y1047618D02*
X1535581Y1047717D01*
G01X1535572Y1047546D02*
X1535577Y1047618D01*
G01X1535574Y1047520D02*
X1535572Y1047546D01*
G01X1535577Y1052618D02*
X1535581Y1052717D01*
G01X1535572Y1052546D02*
X1535577Y1052618D01*
G01X1535574Y1052520D02*
X1535572Y1052546D01*
G01X1535577Y1057618D02*
X1535581Y1057717D01*
G01X1535572Y1057546D02*
X1535577Y1057618D01*
G01X1535574Y1057520D02*
X1535572Y1057546D01*
G01X1535577Y1062618D02*
X1535581Y1062717D01*
G01X1535572Y1062546D02*
X1535577Y1062618D01*
G01X1535574Y1062520D02*
X1535572Y1062546D01*
G01X1535577Y1067618D02*
X1535581Y1067717D01*
G01X1535572Y1067546D02*
X1535577Y1067618D01*
G01X1535574Y1067520D02*
X1535572Y1067546D01*
G01X1535577Y1072618D02*
X1535581Y1072717D01*
G01X1535572Y1072546D02*
X1535577Y1072618D01*
G01X1535574Y1072520D02*
X1535572Y1072546D01*
G01X1535577Y1077618D02*
X1535581Y1077717D01*
G01X1535572Y1077546D02*
X1535577Y1077618D01*
G01X1535574Y1077520D02*
X1535572Y1077546D01*
G01X1535577Y1082618D02*
X1535581Y1082717D01*
G01X1535572Y1082546D02*
X1535577Y1082618D01*
G01X1535574Y1082520D02*
X1535572Y1082546D01*
G01X1535611Y1047482D02*
Y1047487D01*
G01Y1052487D02*
X1535610Y1052494D01*
G01X1535611Y1052482D02*
Y1052487D01*
G01X1535613Y1052480D02*
X1535611Y1052482D01*
G01Y1057487D02*
X1535610Y1057494D01*
G01X1535611Y1057482D02*
Y1057487D01*
G01X1535613Y1057480D02*
X1535611Y1057482D01*
G01Y1062487D02*
X1535610Y1062494D01*
G01X1535611Y1062482D02*
Y1062487D01*
G01X1535613Y1062480D02*
X1535611Y1062482D01*
G01Y1067487D02*
X1535610Y1067494D01*
G01X1535611Y1067482D02*
Y1067487D01*
G01X1535613Y1067480D02*
X1535611Y1067482D01*
G01Y1072487D02*
X1535610Y1072494D01*
G01X1535611Y1072482D02*
Y1072487D01*
G01X1535613Y1072480D02*
X1535611Y1072482D01*
G01Y1077487D02*
X1535610Y1077494D01*
G01X1535611Y1077482D02*
Y1077487D01*
G01X1535613Y1077480D02*
X1535611Y1077482D01*
G01Y1082487D02*
X1535610Y1082494D01*
G01X1535611Y1082482D02*
Y1082487D01*
G01X1535613Y1082480D02*
X1535611Y1082482D01*
G01X1534626Y1047527D02*
Y1047536D01*
G01X1534627Y1047521D02*
X1534626Y1047527D01*
G01Y1052527D02*
Y1052536D01*
G01X1534627Y1052521D02*
X1534626Y1052527D01*
G01X1534628Y1052520D02*
X1534627Y1052521D01*
G01X1534626Y1057527D02*
Y1057536D01*
G01X1534627Y1057521D02*
X1534626Y1057527D01*
G01X1534628Y1057520D02*
X1534627Y1057521D01*
G01X1534626Y1062527D02*
Y1062536D01*
G01X1534627Y1062521D02*
X1534626Y1062527D01*
G01X1534628Y1062520D02*
X1534627Y1062521D01*
G01X1534626Y1067527D02*
Y1067536D01*
G01X1534627Y1067521D02*
X1534626Y1067527D01*
G01X1534628Y1067520D02*
X1534627Y1067521D01*
G01X1534626Y1072527D02*
Y1072536D01*
G01X1534627Y1072521D02*
X1534626Y1072527D01*
G01X1534628Y1072520D02*
X1534627Y1072521D01*
G01X1534626Y1077527D02*
Y1077536D01*
G01X1534627Y1077521D02*
X1534626Y1077527D01*
G01X1534628Y1077520D02*
X1534627Y1077521D01*
G01X1534626Y1082527D02*
Y1082536D01*
G01X1534627Y1082521D02*
X1534626Y1082527D01*
G01X1534628Y1082520D02*
X1534627Y1082521D01*
G01X1535602Y1047663D02*
X1535610Y1047637D01*
G01X1535593Y1047690D02*
X1535602Y1047663D01*
G01X1535581Y1047717D02*
X1535593Y1047690D01*
G01X1535602Y1052663D02*
X1535610Y1052637D01*
G01X1535593Y1052690D02*
X1535602Y1052663D01*
G01X1535581Y1052717D02*
X1535593Y1052690D01*
G01X1535602Y1057663D02*
X1535610Y1057637D01*
G01X1535593Y1057690D02*
X1535602Y1057663D01*
G01X1535581Y1057717D02*
X1535593Y1057690D01*
G01X1535602Y1062663D02*
X1535610Y1062637D01*
G01X1535593Y1062690D02*
X1535602Y1062663D01*
G01X1535581Y1062717D02*
X1535593Y1062690D01*
G01X1535602Y1067663D02*
X1535610Y1067637D01*
G01X1535593Y1067690D02*
X1535602Y1067663D01*
G01X1535581Y1067717D02*
X1535593Y1067690D01*
G01X1535602Y1072663D02*
X1535610Y1072637D01*
G01X1535593Y1072690D02*
X1535602Y1072663D01*
G01X1535581Y1072717D02*
X1535593Y1072690D01*
G01X1535602Y1077663D02*
X1535610Y1077637D01*
G01X1535593Y1077690D02*
X1535602Y1077663D01*
G01X1535581Y1077717D02*
X1535593Y1077690D01*
G01X1535602Y1082663D02*
X1535610Y1082637D01*
G01X1535593Y1082690D02*
X1535602Y1082663D01*
G01X1535581Y1082717D02*
X1535593Y1082690D01*
G01Y1052515D02*
X1535574Y1052520D01*
G01X1535607Y1052500D02*
X1535593Y1052515D01*
G01X1535613Y1052480D02*
X1535607Y1052500D01*
G01X1535593Y1057515D02*
X1535574Y1057520D01*
G01X1535607Y1057500D02*
X1535593Y1057515D01*
G01X1535613Y1057480D02*
X1535607Y1057500D01*
G01X1535593Y1062515D02*
X1535574Y1062520D01*
G01X1535607Y1062500D02*
X1535593Y1062515D01*
G01X1535613Y1062480D02*
X1535607Y1062500D01*
G01X1535593Y1067515D02*
X1535574Y1067520D01*
G01X1535607Y1067500D02*
X1535593Y1067515D01*
G01X1535613Y1067480D02*
X1535607Y1067500D01*
G01X1535593Y1072515D02*
X1535574Y1072520D01*
G01X1535607Y1072500D02*
X1535593Y1072515D01*
G01X1535613Y1072480D02*
X1535607Y1072500D01*
G01X1535593Y1077515D02*
X1535574Y1077520D01*
G01X1535607Y1077500D02*
X1535593Y1077515D01*
G01X1535613Y1077480D02*
X1535607Y1077500D01*
G01X1535593Y1082515D02*
X1535574Y1082520D01*
G01X1535607Y1082500D02*
X1535593Y1082515D01*
G01X1535613Y1082480D02*
X1535607Y1082500D01*
G01X1534055Y1108012D02*
G03X1533465Y1108602I-590J0D01*
G01X1531299Y1104862D02*
G03Y1106831I0J984D01*
G01X1540945Y1107421D02*
G03X1538976Y1109390I-1969J0D01*
G01X1533858Y1097736D02*
G03X1532677Y1098917I-1181J0D01*
G01X1531299Y1092539D02*
X1532603Y1090571D01*
G01X1535610Y1047494D02*
X1535611Y1047502D01*
G01X1535610Y1052494D02*
X1535611Y1052502D01*
G01X1535610Y1057494D02*
X1535611Y1057502D01*
G01X1535610Y1062494D02*
X1535611Y1062502D01*
G01X1535610Y1067494D02*
X1535611Y1067502D01*
G01X1535610Y1072494D02*
X1535611Y1072502D01*
G01X1535610Y1077494D02*
X1535611Y1077502D01*
G01X1535610Y1082494D02*
X1535611Y1082502D01*
G01X1540945Y1091673D02*
Y1107421D01*
G01X1539961Y1081142D02*
Y1082520D01*
G01Y1076142D02*
Y1077520D01*
G01Y1071142D02*
Y1072520D01*
G01Y1066142D02*
Y1067520D01*
G01Y1061142D02*
Y1062520D01*
G01Y1056142D02*
Y1057520D01*
G01Y1051142D02*
Y1052520D01*
G01X1536791D02*
Y1051142D01*
G01Y1057520D02*
Y1056142D01*
G01Y1062520D02*
Y1061142D01*
G01Y1067520D02*
Y1066142D01*
G01Y1072520D02*
Y1071142D01*
G01Y1077520D02*
Y1076142D01*
G01Y1082520D02*
Y1081142D01*
G01X1535610Y1080650D02*
Y1083012D01*
G01Y1075650D02*
Y1078012D01*
G01Y1070650D02*
Y1073012D01*
G01Y1065650D02*
Y1068012D01*
G01Y1060650D02*
Y1063012D01*
G01Y1055650D02*
Y1058012D01*
G01Y1050650D02*
Y1053012D01*
G01Y1047494D02*
Y1047637D01*
G01Y1052494D02*
Y1052637D01*
G01Y1057494D02*
Y1057637D01*
G01Y1062494D02*
Y1062637D01*
G01Y1067494D02*
Y1067637D01*
G01Y1072494D02*
Y1072637D01*
G01Y1077494D02*
Y1077637D01*
G01Y1082494D02*
Y1082637D01*
G01X1534626Y1053012D02*
Y1050650D01*
G01Y1058012D02*
Y1055650D01*
G01Y1063012D02*
Y1060650D01*
G01Y1068012D02*
Y1065650D01*
G01Y1073012D02*
Y1070650D01*
G01Y1078012D02*
Y1075650D01*
G01Y1083012D02*
Y1080650D01*
G01X1534055Y1101909D02*
Y1108012D01*
G01X1533858Y1097736D02*
Y1089193D01*
G01X1531299Y1094232D02*
Y1092539D01*
G01X1537008Y1089193D02*
X1533858D01*
G01X1535610Y1083012D02*
X1534626D01*
G01X1534628Y1082520D02*
X1539961D01*
G01Y1082480D02*
X1535613D01*
G01X1539961Y1081142D02*
X1534628D01*
G01X1534626Y1080650D02*
X1535610D01*
G01Y1078012D02*
X1534626D01*
G01X1534628Y1077520D02*
X1539961D01*
G01Y1077480D02*
X1535613D01*
G01X1539961Y1076142D02*
X1534628D01*
G01X1534626Y1075650D02*
X1535610D01*
G01Y1073012D02*
X1534626D01*
G01X1534628Y1072520D02*
X1539961D01*
G01Y1072480D02*
X1535613D01*
G01X1539961Y1071142D02*
X1534628D01*
G01X1534626Y1070650D02*
X1535610D01*
G01Y1068012D02*
X1534626D01*
G01X1534628Y1067520D02*
X1539961D01*
G01Y1067480D02*
X1535613D01*
G01X1539961Y1066142D02*
X1534628D01*
G01X1534626Y1065650D02*
X1535610D01*
G01Y1063012D02*
X1534626D01*
G01X1534628Y1062520D02*
X1539961D01*
G01Y1062480D02*
X1535613D01*
G01X1539961Y1061142D02*
X1534628D01*
G01X1534626Y1060650D02*
X1535610D01*
G01Y1058012D02*
X1534626D01*
G01X1534628Y1057520D02*
X1539961D01*
G01Y1057480D02*
X1535613D01*
G01X1539961Y1056142D02*
X1534628D01*
G01X1534626Y1055650D02*
X1535610D01*
G01Y1053012D02*
X1534626D01*
G01X1534628Y1052520D02*
X1539961D01*
G01Y1052480D02*
X1535613D01*
G01X1539961Y1051142D02*
X1534628D01*
G01X1534626Y1050650D02*
X1535610D01*
G01Y1048012D02*
X1534626D01*
G01X1534628Y1047520D02*
X1539961D01*
G01Y1047480D02*
X1535613D01*
G01X1534626Y1082715D02*
X1535581Y1082717D01*
G01X1535610Y1080946D02*
X1534626Y1080945D01*
G01Y1077715D02*
X1535581Y1077717D01*
G01X1535610Y1075946D02*
X1534626Y1075945D01*
G01Y1072715D02*
X1535581Y1072717D01*
G01X1535610Y1070946D02*
X1534626Y1070945D01*
G01Y1067715D02*
X1535581Y1067717D01*
G01X1535610Y1065946D02*
X1534626Y1065945D01*
G01Y1062715D02*
X1535581Y1062717D01*
G01X1535610Y1060946D02*
X1534626Y1060945D01*
G01Y1057715D02*
X1535581Y1057717D01*
G01X1535610Y1055946D02*
X1534626Y1055945D01*
G01Y1052715D02*
X1535581Y1052717D01*
G01X1535610Y1050946D02*
X1534626Y1050945D01*
G01Y1047715D02*
X1535581Y1047717D01*
G01X1533609Y1098461D02*
X1531299Y1094232D01*
G01X1540945Y1091673D02*
X1537598Y1088327D01*
G01X1531102Y1085650D02*
X1532283Y1086831D01*
G01X1559882Y1183355D02*
G03X1566807Y1170224I37662J11471D01*
G01X1559882Y1183355D02*
G03X1539921I-9980J-3040D01*
G01X1532996Y1170224D02*
G03X1539921Y1183355I-30737J24602D01*
G01X1559882D02*
G03X1539921I-9980J-3040D01*
G01X1559882D02*
G03X1566807Y1170224I37662J11471D01*
G01X1532996D02*
G03X1539921Y1183355I-30737J24601D01*
G01X1542292Y1511515D02*
G03I-4291J0D01*
G01D02*
G03I-4291J0D01*
G01X1624803Y1503937D02*
G03Y1496063I0J-3937D01*
G01X1606693D02*
G03Y1503937I0J3937D01*
G01X1636614D02*
X1624803D01*
G01D02*
G03Y1496063I0J-3937D01*
G01X1606693D02*
G03Y1503937I0J3937D01*
G01X1636614D02*
X1624803D01*
G01X1576613Y1808346D02*
Y1789409D01*
G01X1640444Y-369410D02*
X2030207D01*
G01X1645416Y84941D02*
X1645411Y84921D01*
G01X1645431Y84955D02*
X1645416Y84941D01*
G01X1645450Y84961D02*
X1645431Y84955D01*
G01X1645416Y88091D02*
X1645411Y88071D01*
G01X1645431Y88105D02*
X1645416Y88091D01*
G01X1645450Y88110D02*
X1645431Y88105D01*
G01X1645416Y91240D02*
X1645411Y91220D01*
G01X1645431Y91254D02*
X1645416Y91240D01*
G01X1645450Y91260D02*
X1645431Y91254D01*
G01X1646391Y83799D02*
X1646396Y83819D01*
G01X1646376Y83785D02*
X1646391Y83799D01*
G01X1646357Y83780D02*
X1646376Y83785D01*
G01X1646391Y86949D02*
X1646396Y86969D01*
G01X1646376Y86934D02*
X1646391Y86949D01*
G01X1646357Y86929D02*
X1646376Y86934D01*
G01X1646391Y90098D02*
X1646396Y90118D01*
G01X1646376Y90084D02*
X1646391Y90098D01*
G01X1646357Y90079D02*
X1646376Y90084D01*
G01X1646391Y93248D02*
X1646396Y93268D01*
G01X1646376Y93233D02*
X1646391Y93248D01*
G01X1646357Y93228D02*
X1646376Y93233D01*
G01X1646375Y83772D02*
X1646378Y83774D01*
G01X1646372Y83770D02*
X1646375Y83772D01*
G01X1646369Y83770D02*
X1646372D01*
G01X1646365Y83769D02*
X1646369Y83770D01*
G01X1646362Y83769D02*
X1646365D01*
G01X1646358Y83768D02*
X1646362Y83769D01*
G01X1645436Y84968D02*
X1645433Y84967D01*
G01X1645439Y84969D02*
X1645436Y84968D01*
G01X1645443Y84970D02*
X1645439Y84969D01*
G01X1645446Y84971D02*
X1645443Y84970D01*
G01X1645449Y84972D02*
X1645446Y84971D01*
G01X1645453Y84972D02*
X1645449D01*
G01X1646375Y86921D02*
X1646378Y86923D01*
G01X1646372Y86920D02*
X1646375Y86921D01*
G01X1646369Y86919D02*
X1646372Y86920D01*
G01X1646365Y86919D02*
X1646369D01*
G01X1646362Y86918D02*
X1646365Y86919D01*
G01X1646358Y86918D02*
X1646362D01*
G01X1645436Y88118D02*
X1645433Y88116D01*
G01X1645439Y88119D02*
X1645436Y88118D01*
G01X1645443Y88120D02*
X1645439Y88119D01*
G01X1645446Y88121D02*
X1645443Y88120D01*
G01X1645449Y88121D02*
X1645446D01*
G01X1645453D02*
X1645449D01*
G01X1646375Y90071D02*
X1646378Y90073D01*
G01X1646372Y90070D02*
X1646375Y90071D01*
G01X1646369Y90069D02*
X1646372Y90070D01*
G01X1646365Y90068D02*
X1646369Y90069D01*
G01X1646362Y90068D02*
X1646365D01*
G01X1646358Y90067D02*
X1646362Y90068D01*
G01X1645436Y91267D02*
X1645433Y91266D01*
G01X1645439Y91269D02*
X1645436Y91267D01*
G01X1645443Y91270D02*
X1645439Y91269D01*
G01X1645446Y91270D02*
X1645443D01*
G01X1645449Y91271D02*
X1645446Y91270D01*
G01X1645453Y91271D02*
X1645449D01*
G01X1646375Y93220D02*
X1646378Y93222D01*
G01X1646372Y93219D02*
X1646375Y93220D01*
G01X1646369Y93219D02*
X1646372D01*
G01X1646365Y93218D02*
X1646369Y93219D01*
G01X1646362Y93217D02*
X1646365Y93218D01*
G01X1646358Y93217D02*
X1646362D01*
G01X1646388Y84959D02*
X1646392Y84954D01*
G01X1646383Y84963D02*
X1646388Y84959D01*
G01X1646378Y84967D02*
X1646383Y84963D01*
G01X1646372Y84970D02*
X1646378Y84967D01*
G01X1646365Y84971D02*
X1646372Y84970D01*
G01X1646358Y84972D02*
X1646365Y84971D01*
G01X1646388Y88109D02*
X1646392Y88103D01*
G01X1646383Y88113D02*
X1646388Y88109D01*
G01X1646378Y88117D02*
X1646383Y88113D01*
G01X1646372Y88119D02*
X1646378Y88117D01*
G01X1646365Y88121D02*
X1646372Y88119D01*
G01X1646358Y88121D02*
X1646365D01*
G01X1646388Y91258D02*
X1646392Y91253D01*
G01X1646383Y91263D02*
X1646388Y91258D01*
G01X1646378Y91266D02*
X1646383Y91263D01*
G01X1646372Y91269D02*
X1646378Y91266D01*
G01X1646365Y91270D02*
X1646372Y91269D01*
G01X1646358Y91271D02*
X1646365Y91270D01*
G01X1645414Y83798D02*
X1645413Y83805D01*
G01X1645417Y83791D02*
X1645414Y83798D01*
G01X1645420Y83785D02*
X1645417Y83791D01*
G01X1645425Y83779D02*
X1645420Y83785D01*
G01X1645431Y83774D02*
X1645425Y83779D01*
G01X1645438Y83771D02*
X1645431Y83774D01*
G01X1645445Y83769D02*
X1645438Y83771D01*
G01X1645453Y83768D02*
X1645445Y83769D01*
G01X1645414Y86948D02*
X1645413Y86955D01*
G01X1645417Y86941D02*
X1645414Y86948D01*
G01X1645420Y86934D02*
X1645417Y86941D01*
G01X1645425Y86929D02*
X1645420Y86934D01*
G01X1645431Y86924D02*
X1645425Y86929D01*
G01X1645438Y86920D02*
X1645431Y86924D01*
G01X1645445Y86919D02*
X1645438Y86920D01*
G01X1645453Y86918D02*
X1645445Y86919D01*
G01X1645414Y90097D02*
X1645413Y90104D01*
G01X1645417Y90090D02*
X1645414Y90097D01*
G01X1645420Y90084D02*
X1645417Y90090D01*
G01X1645425Y90078D02*
X1645420Y90084D01*
G01X1645431Y90074D02*
X1645425Y90078D01*
G01X1645438Y90070D02*
X1645431Y90074D01*
G01X1645445Y90068D02*
X1645438Y90070D01*
G01X1645453Y90067D02*
X1645445Y90068D01*
G01X1645414Y93247D02*
X1645413Y93254D01*
G01X1645417Y93240D02*
X1645414Y93247D01*
G01X1645420Y93233D02*
X1645417Y93240D01*
G01X1645425Y93228D02*
X1645420Y93233D01*
G01X1645431Y93223D02*
X1645425Y93228D01*
G01X1645438Y93220D02*
X1645431Y93223D01*
G01X1645445Y93218D02*
X1645438Y93220D01*
G01X1645453Y93217D02*
X1645445Y93218D01*
G01X1646367Y84959D02*
X1646377Y84955D01*
G01X1646357Y84961D02*
X1646367Y84959D01*
G01Y88109D02*
X1646377Y88105D01*
G01X1646357Y88110D02*
X1646367Y88109D01*
G01Y91258D02*
X1646377Y91254D01*
G01X1646357Y91260D02*
X1646367Y91258D01*
G01X1645413Y86959D02*
Y86955D01*
G01X1645415Y86952D02*
X1645413Y86959D01*
G01X1645427Y86937D02*
X1645415Y86952D01*
G01X1645452Y86929D02*
X1645427Y86937D01*
G01X1645413Y90108D02*
Y90104D01*
G01X1645415Y90102D02*
X1645413Y90108D01*
G01X1645426Y90087D02*
X1645415Y90102D01*
G01X1645451Y90079D02*
X1645426Y90087D01*
G01X1645413Y83809D02*
Y83806D01*
G01X1645415Y83803D02*
X1645413Y83809D01*
G01X1645426Y83788D02*
X1645415Y83803D01*
G01X1645451Y83780D02*
X1645426Y83788D01*
G01X1659810Y51999D02*
X1659821Y51984D01*
G01X1659786Y52008D02*
X1659810Y51999D01*
G01Y56999D02*
X1659821Y56984D01*
G01X1659786Y57008D02*
X1659810Y56999D01*
G01Y61999D02*
X1659821Y61984D01*
G01X1659786Y62008D02*
X1659810Y61999D01*
G01Y66999D02*
X1659821Y66984D01*
G01X1659786Y67008D02*
X1659810Y66999D01*
G01Y71999D02*
X1659821Y71984D01*
G01X1659786Y72008D02*
X1659810Y71999D01*
G01Y76999D02*
X1659821Y76984D01*
G01X1659786Y77008D02*
X1659810Y76999D01*
G01Y81999D02*
X1659821Y81984D01*
G01X1659786Y82008D02*
X1659810Y81999D01*
G01X1645413Y93258D02*
Y93254D01*
G01X1645415Y93252D02*
X1645413Y93258D01*
G01X1645425Y93238D02*
X1645415Y93252D01*
G01X1645448Y93228D02*
X1645425Y93238D01*
G01X1646366Y91259D02*
X1646357Y91260D01*
G01X1646375Y91256D02*
X1646366Y91259D01*
G01X1646383Y91250D02*
X1646375Y91256D01*
G01X1646366Y84959D02*
X1646357Y84961D01*
G01X1646375Y84956D02*
X1646366Y84959D01*
G01X1646383Y84951D02*
X1646375Y84956D01*
G01X1646366Y88109D02*
X1646357Y88110D01*
G01X1646375Y88106D02*
X1646366Y88109D01*
G01X1646383Y88100D02*
X1646375Y88106D01*
G01X1645452Y83774D02*
X1645453Y83768D01*
G01X1645452Y83778D02*
Y83774D01*
G01X1645450Y83780D02*
X1645452Y83778D01*
G01Y86924D02*
X1645453Y86918D01*
G01X1645452Y86928D02*
Y86924D01*
G01X1645450Y86929D02*
X1645452Y86928D01*
G01Y90074D02*
X1645453Y90067D01*
G01X1645452Y90078D02*
Y90074D01*
G01X1645450Y90079D02*
X1645452Y90078D01*
G01Y93223D02*
X1645453Y93217D01*
G01X1645452Y93227D02*
Y93223D01*
G01X1645450Y93228D02*
X1645452Y93227D01*
G01X1659823Y51975D02*
Y51982D01*
G01X1659824Y51970D02*
X1659823Y51975D01*
G01X1659825Y51969D02*
X1659824Y51970D01*
G01X1659823Y56975D02*
Y56982D01*
G01X1659824Y56970D02*
X1659823Y56975D01*
G01X1659825Y56969D02*
X1659824Y56970D01*
G01X1659823Y61975D02*
Y61982D01*
G01X1659824Y61970D02*
X1659823Y61975D01*
G01X1659825Y61969D02*
X1659824Y61970D01*
G01X1659823Y66975D02*
Y66982D01*
G01X1659824Y66970D02*
X1659823Y66975D01*
G01X1659825Y66969D02*
X1659824Y66970D01*
G01X1659823Y71975D02*
Y71982D01*
G01X1659824Y71970D02*
X1659823Y71975D01*
G01X1659825Y71969D02*
X1659824Y71970D01*
G01X1659823Y76975D02*
Y76982D01*
G01X1659824Y76970D02*
X1659823Y76975D01*
G01X1659825Y76969D02*
X1659824Y76970D01*
G01X1659823Y81975D02*
Y81982D01*
G01X1659824Y81970D02*
X1659823Y81975D01*
G01X1659825Y81969D02*
X1659824Y81970D01*
G01X1645436Y86931D02*
X1645450Y86929D01*
G01X1645425Y86939D02*
X1645436Y86931D01*
G01X1645413Y86957D02*
X1645425Y86939D01*
G01X1645436Y90081D02*
X1645450Y90079D01*
G01X1645424Y90089D02*
X1645436Y90081D01*
G01X1645412Y90109D02*
X1645424Y90089D01*
G01X1646398Y83813D02*
Y83805D01*
G01X1646397Y83817D02*
X1646398Y83813D01*
G01X1646396Y83819D02*
X1646397Y83817D01*
G01X1646398Y86963D02*
Y86955D01*
G01X1646397Y86967D02*
X1646398Y86963D01*
G01X1646396Y86969D02*
X1646397Y86967D01*
G01X1646398Y90112D02*
Y90104D01*
G01X1646397Y90117D02*
X1646398Y90112D01*
G01X1646396Y90118D02*
X1646397Y90117D01*
G01X1646398Y93262D02*
Y93254D01*
G01X1646397Y93266D02*
X1646398Y93262D01*
G01X1646396Y93268D02*
X1646397Y93266D01*
G01X1645435Y83782D02*
X1645450Y83780D01*
G01X1645422Y83791D02*
X1645435Y83782D01*
G01X1645412Y83811D02*
X1645422Y83791D01*
G01X1646397Y84941D02*
X1646398Y84935D01*
G01X1646395Y84948D02*
X1646397Y84941D01*
G01X1646392Y84954D02*
X1646395Y84948D01*
G01X1646397Y88091D02*
X1646398Y88084D01*
G01X1646395Y88097D02*
X1646397Y88091D01*
G01X1646392Y88103D02*
X1646395Y88097D01*
G01X1646397Y91241D02*
X1646398Y91234D01*
G01X1646395Y91247D02*
X1646397Y91241D01*
G01X1646392Y91253D02*
X1646395Y91247D01*
G01X1646359Y83774D02*
Y83768D01*
G01X1646357Y83778D02*
X1646359Y83774D01*
G01X1646357Y83780D02*
Y83778D01*
G01X1646359Y86924D02*
Y86918D01*
G01X1646357Y86928D02*
X1646359Y86924D01*
G01X1646357Y86929D02*
Y86928D01*
G01X1646359Y90074D02*
Y90067D01*
G01X1646357Y90077D02*
X1646359Y90074D01*
G01X1646357Y90079D02*
Y90077D01*
G01X1646359Y93223D02*
Y93217D01*
G01X1646357Y93227D02*
X1646359Y93223D01*
G01X1646357Y93228D02*
Y93227D01*
G01X1658839Y52015D02*
Y52024D01*
G01Y52009D02*
Y52015D01*
G01X1658840Y52008D02*
X1658839Y52009D01*
G01Y57015D02*
Y57024D01*
G01Y57009D02*
Y57015D01*
G01X1658840Y57008D02*
X1658839Y57009D01*
G01Y62015D02*
Y62024D01*
G01Y62009D02*
Y62015D01*
G01X1658840Y62008D02*
X1658839Y62009D01*
G01Y67015D02*
Y67024D01*
G01Y67009D02*
Y67015D01*
G01X1658840Y67008D02*
X1658839Y67009D01*
G01Y72015D02*
Y72024D01*
G01Y72009D02*
Y72015D01*
G01X1658840Y72008D02*
X1658839Y72009D01*
G01Y77015D02*
Y77024D01*
G01Y77009D02*
Y77015D01*
G01X1658840Y77008D02*
X1658839Y77009D01*
G01Y82015D02*
Y82024D01*
G01Y82009D02*
Y82015D01*
G01X1658840Y82008D02*
X1658839Y82009D01*
G01X1659815Y52152D02*
X1659823Y52125D01*
G01X1659805Y52178D02*
X1659815Y52152D01*
G01X1659794Y52205D02*
X1659805Y52178D01*
G01X1659815Y57152D02*
X1659823Y57125D01*
G01X1659805Y57178D02*
X1659815Y57152D01*
G01X1659794Y57205D02*
X1659805Y57178D01*
G01X1659815Y62152D02*
X1659823Y62125D01*
G01X1659805Y62178D02*
X1659815Y62152D01*
G01X1659794Y62205D02*
X1659805Y62178D01*
G01X1659815Y67152D02*
X1659823Y67125D01*
G01X1659805Y67178D02*
X1659815Y67152D01*
G01X1659794Y67205D02*
X1659805Y67178D01*
G01X1659815Y72152D02*
X1659823Y72125D01*
G01X1659805Y72178D02*
X1659815Y72152D01*
G01X1659794Y72205D02*
X1659805Y72178D01*
G01X1659815Y77152D02*
X1659823Y77125D01*
G01X1659805Y77178D02*
X1659815Y77152D01*
G01X1659794Y77205D02*
X1659805Y77178D01*
G01X1659815Y82152D02*
X1659823Y82125D01*
G01X1659805Y82178D02*
X1659815Y82152D01*
G01X1659794Y82205D02*
X1659805Y82178D01*
G01X1645431Y93233D02*
X1645450Y93228D01*
G01X1645418Y93246D02*
X1645431Y93233D01*
G01X1645411Y93263D02*
X1645418Y93246D01*
G01X1659806Y52003D02*
X1659786Y52008D01*
G01X1659820Y51988D02*
X1659806Y52003D01*
G01X1659825Y51969D02*
X1659820Y51988D01*
G01X1659806Y57003D02*
X1659786Y57008D01*
G01X1659820Y56988D02*
X1659806Y57003D01*
G01X1659825Y56969D02*
X1659820Y56988D01*
G01X1659806Y62003D02*
X1659786Y62008D01*
G01X1659820Y61988D02*
X1659806Y62003D01*
G01X1659825Y61969D02*
X1659820Y61988D01*
G01X1659806Y67003D02*
X1659786Y67008D01*
G01X1659820Y66988D02*
X1659806Y67003D01*
G01X1659825Y66969D02*
X1659820Y66988D01*
G01X1659806Y72003D02*
X1659786Y72008D01*
G01X1659820Y71988D02*
X1659806Y72003D01*
G01X1659825Y71969D02*
X1659820Y71988D01*
G01X1659806Y77003D02*
X1659786Y77008D01*
G01X1659820Y76988D02*
X1659806Y77003D01*
G01X1659825Y76969D02*
X1659820Y76988D01*
G01X1659806Y82003D02*
X1659786Y82008D01*
G01X1659820Y81988D02*
X1659806Y82003D01*
G01X1659825Y81969D02*
X1659820Y81988D01*
G01X1646390Y91242D02*
X1646383Y91250D01*
G01X1646395Y91231D02*
X1646390Y91242D01*
G01X1646396Y91220D02*
X1646395Y91231D01*
G01X1646390Y84943D02*
X1646383Y84951D01*
G01X1646395Y84932D02*
X1646390Y84943D01*
G01X1646396Y84921D02*
X1646395Y84932D01*
G01X1646390Y88092D02*
X1646383Y88100D01*
G01X1646395Y88082D02*
X1646390Y88092D01*
G01X1646396Y88071D02*
X1646395Y88082D01*
G01X1659790Y52106D02*
X1659794Y52205D01*
G01X1659784Y52034D02*
X1659790Y52106D01*
G01X1659786Y52008D02*
X1659784Y52034D01*
G01X1659790Y57106D02*
X1659794Y57205D01*
G01X1659784Y57034D02*
X1659790Y57106D01*
G01X1659786Y57008D02*
X1659784Y57034D01*
G01X1659790Y62106D02*
X1659794Y62205D01*
G01X1659784Y62034D02*
X1659790Y62106D01*
G01X1659786Y62008D02*
X1659784Y62034D01*
G01X1659790Y67106D02*
X1659794Y67205D01*
G01X1659784Y67034D02*
X1659790Y67106D01*
G01X1659786Y67008D02*
X1659784Y67034D01*
G01X1659790Y72106D02*
X1659794Y72205D01*
G01X1659784Y72034D02*
X1659790Y72106D01*
G01X1659786Y72008D02*
X1659784Y72034D01*
G01X1659790Y77106D02*
X1659794Y77205D01*
G01X1659784Y77034D02*
X1659790Y77106D01*
G01X1659786Y77008D02*
X1659784Y77034D01*
G01X1659790Y82106D02*
X1659794Y82205D01*
G01X1659784Y82034D02*
X1659790Y82106D01*
G01X1659786Y82008D02*
X1659784Y82034D01*
G01X1645454Y91444D02*
X1645453Y91457D01*
G01X1645450Y91431D02*
X1645454Y91444D01*
G01X1645450Y91417D02*
Y91431D01*
G01X1645454Y88294D02*
X1645453Y88307D01*
G01X1645450Y88281D02*
X1645454Y88294D01*
G01X1645450Y88268D02*
Y88281D01*
G01X1645454Y85145D02*
X1645453Y85157D01*
G01X1645450Y85132D02*
X1645454Y85145D01*
G01X1645450Y85118D02*
Y85132D01*
G01X1658839Y80628D02*
X1658840Y80630D01*
G01X1658839Y80622D02*
Y80628D01*
G01Y80614D02*
Y80622D01*
G01Y75628D02*
X1658840Y75630D01*
G01X1658839Y75622D02*
Y75628D01*
G01Y75614D02*
Y75622D01*
G01Y70628D02*
X1658840Y70630D01*
G01X1658839Y70622D02*
Y70628D01*
G01Y70614D02*
Y70622D01*
G01Y65628D02*
X1658840Y65630D01*
G01X1658839Y65622D02*
Y65628D01*
G01Y65614D02*
Y65622D01*
G01Y60628D02*
X1658840Y60630D01*
G01X1658839Y60622D02*
Y60628D01*
G01Y60614D02*
Y60622D01*
G01Y55628D02*
X1658840Y55630D01*
G01X1658839Y55622D02*
Y55628D01*
G01Y55614D02*
Y55622D01*
G01Y50628D02*
X1658840Y50630D01*
G01X1658839Y50622D02*
Y50628D01*
G01Y50614D02*
Y50622D01*
G01X1645450Y93057D02*
X1645449Y93070D01*
G01X1645454Y93044D02*
X1645450Y93057D01*
G01X1645453Y93031D02*
X1645454Y93044D01*
G01X1645450Y89907D02*
X1645449Y89921D01*
G01X1645454Y89894D02*
X1645450Y89907D01*
G01X1645453Y89882D02*
X1645454Y89894D01*
G01X1645450Y86757D02*
X1645449Y86771D01*
G01X1645454Y86745D02*
X1645450Y86757D01*
G01X1645453Y86732D02*
X1645454Y86745D01*
G01X1645450Y83608D02*
X1645449Y83622D01*
G01X1645454Y83595D02*
X1645450Y83608D01*
G01X1645453Y83583D02*
X1645454Y83595D01*
G01X1646361Y91431D02*
X1646362Y91417D01*
G01X1646357Y91444D02*
X1646361Y91431D01*
G01X1646358Y91457D02*
X1646357Y91444D01*
G01X1646361Y88281D02*
X1646362Y88268D01*
G01X1646357Y88294D02*
X1646361Y88281D01*
G01X1646358Y88307D02*
X1646357Y88294D01*
G01X1646361Y85132D02*
X1646362Y85118D01*
G01X1646357Y85145D02*
X1646361Y85132D01*
G01X1646358Y85157D02*
X1646357Y85145D01*
G01X1645413Y90112D02*
Y90105D01*
G01X1645412Y90117D02*
X1645413Y90112D01*
G01X1645412Y90109D02*
Y90117D01*
G01X1646357Y93044D02*
X1646358Y93031D01*
G01X1646360Y93057D02*
X1646357Y93044D01*
G01X1646361Y93070D02*
X1646360Y93057D01*
G01X1646357Y89894D02*
X1646358Y89882D01*
G01X1646360Y89907D02*
X1646357Y89894D01*
G01X1646361Y89921D02*
X1646360Y89907D01*
G01X1646357Y86745D02*
X1646358Y86732D01*
G01X1646360Y86757D02*
X1646357Y86745D01*
G01X1646361Y86771D02*
X1646360Y86757D01*
G01X1646357Y83595D02*
X1646358Y83583D01*
G01X1646360Y83608D02*
X1646357Y83595D01*
G01X1646361Y83622D02*
X1646360Y83608D01*
G01X1645413Y83813D02*
Y83806D01*
G01X1645412Y83817D02*
X1645413Y83813D01*
G01X1645412Y83811D02*
Y83817D01*
G01X1645426Y91251D02*
X1645450Y91260D01*
G01X1645415Y91237D02*
X1645426Y91251D01*
G01X1645413Y91230D02*
X1645415Y91237D01*
G01X1645426Y88102D02*
X1645450Y88110D01*
G01X1645415Y88087D02*
X1645426Y88102D01*
G01X1645413Y88080D02*
X1645415Y88087D01*
G01X1645426Y84952D02*
X1645450Y84961D01*
G01X1645415Y84937D02*
X1645426Y84952D01*
G01X1645413Y84931D02*
X1645415Y84937D01*
G01X1646398Y91227D02*
Y91234D01*
G01X1646397Y91222D02*
X1646398Y91227D01*
G01X1646396Y91220D02*
X1646397Y91222D01*
G01X1646398Y88077D02*
Y88084D01*
G01X1646397Y88072D02*
X1646398Y88077D01*
G01X1646396Y88071D02*
X1646397Y88072D01*
G01X1646398Y84928D02*
Y84935D01*
G01X1646397Y84923D02*
X1646398Y84928D01*
G01X1646396Y84921D02*
X1646397Y84923D01*
G01X1645413Y93262D02*
Y93254D01*
G01X1645412Y93266D02*
X1645413Y93262D01*
G01X1645411Y93263D02*
X1645412Y93266D01*
G01X1646369Y93230D02*
X1646357Y93228D01*
G01X1646379Y93235D02*
X1646369Y93230D01*
G01Y90081D02*
X1646357Y90079D01*
G01X1646379Y90085D02*
X1646369Y90081D01*
G01Y86931D02*
X1646357Y86929D01*
G01X1646379Y86936D02*
X1646369Y86931D01*
G01Y83781D02*
X1646357Y83780D01*
G01X1646379Y83786D02*
X1646369Y83781D01*
G01X1645413Y86963D02*
Y86955D01*
G01X1645412Y86967D02*
X1645413Y86963D01*
G01X1645411Y86965D02*
X1645412Y86967D01*
G01X1646358Y91265D02*
Y91271D01*
G01X1646357Y91261D02*
X1646358Y91265D01*
G01X1646357Y91260D02*
Y91261D01*
G01X1646358Y88115D02*
Y88121D01*
G01X1646357Y88111D02*
X1646358Y88115D01*
G01X1646357Y88110D02*
Y88111D01*
G01X1646358Y84966D02*
Y84972D01*
G01X1646357Y84962D02*
X1646358Y84966D01*
G01X1646357Y84961D02*
Y84962D01*
G01X1659823Y80622D02*
Y80613D01*
G01X1659824Y80628D02*
X1659823Y80622D01*
G01X1659826Y80630D02*
X1659824Y80628D01*
G01X1659823Y75622D02*
Y75613D01*
G01X1659824Y75628D02*
X1659823Y75622D01*
G01X1659826Y75630D02*
X1659824Y75628D01*
G01X1659823Y70622D02*
Y70613D01*
G01X1659824Y70628D02*
X1659823Y70622D01*
G01X1659826Y70630D02*
X1659824Y70628D01*
G01X1659823Y65622D02*
Y65613D01*
G01X1659824Y65628D02*
X1659823Y65622D01*
G01X1659826Y65630D02*
X1659824Y65628D01*
G01X1659823Y60622D02*
Y60613D01*
G01X1659824Y60628D02*
X1659823Y60622D01*
G01X1659826Y60630D02*
X1659824Y60628D01*
G01X1659823Y55622D02*
Y55613D01*
G01X1659824Y55628D02*
X1659823Y55622D01*
G01X1659826Y55630D02*
X1659824Y55628D01*
G01X1659823Y50622D02*
Y50613D01*
G01X1659824Y50628D02*
X1659823Y50622D01*
G01X1659826Y50630D02*
X1659824Y50628D01*
G01X1645413Y91226D02*
Y91234D01*
G01X1645412Y91222D02*
X1645413Y91226D01*
G01X1645411Y91220D02*
X1645412Y91222D01*
G01X1645413Y88077D02*
Y88084D01*
G01X1645412Y88072D02*
X1645413Y88077D01*
G01X1645411Y88071D02*
X1645412Y88072D01*
G01X1645413Y84927D02*
Y84935D01*
G01X1645412Y84923D02*
X1645413Y84927D01*
G01X1645411Y84921D02*
X1645412Y84923D01*
G01X1646395Y93242D02*
X1646398Y93254D01*
G01X1646389Y93230D02*
X1646395Y93242D01*
G01X1646378Y93222D02*
X1646389Y93230D01*
G01X1646395Y90092D02*
X1646398Y90104D01*
G01X1646389Y90081D02*
X1646395Y90092D01*
G01X1646378Y90073D02*
X1646389Y90081D01*
G01X1646395Y86943D02*
X1646398Y86955D01*
G01X1646389Y86931D02*
X1646395Y86943D01*
G01X1646378Y86923D02*
X1646389Y86931D01*
G01X1646395Y83793D02*
X1646398Y83805D01*
G01X1646389Y83781D02*
X1646395Y83793D01*
G01X1646378Y83774D02*
X1646389Y83781D01*
G01X1645452Y91265D02*
Y91271D01*
G01Y91261D02*
Y91265D01*
G01X1645450Y91260D02*
X1645452Y91261D01*
G01Y88115D02*
Y88121D01*
G01Y88111D02*
Y88115D01*
G01X1645450Y88110D02*
X1645452Y88111D01*
G01Y84965D02*
Y84972D01*
G01Y84962D02*
Y84965D01*
G01X1645450Y84961D02*
X1645452Y84962D01*
G01X1645414Y91240D02*
X1645413Y91234D01*
G01X1645416Y91246D02*
X1645414Y91240D01*
G01X1645419Y91252D02*
X1645416Y91246D01*
G01X1645422Y91257D02*
X1645419Y91252D01*
G01X1645427Y91262D02*
X1645422Y91257D01*
G01X1645433Y91266D02*
X1645427Y91262D01*
G01X1645414Y88091D02*
X1645413Y88084D01*
G01X1645416Y88097D02*
X1645414Y88091D01*
G01X1645419Y88103D02*
X1645416Y88097D01*
G01X1645422Y88108D02*
X1645419Y88103D01*
G01X1645427Y88113D02*
X1645422Y88108D01*
G01X1645433Y88116D02*
X1645427Y88113D01*
G01X1645414Y84941D02*
X1645413Y84935D01*
G01X1645416Y84947D02*
X1645414Y84941D01*
G01X1645419Y84953D02*
X1645416Y84947D01*
G01X1645422Y84958D02*
X1645419Y84953D01*
G01X1645427Y84963D02*
X1645422Y84958D01*
G01X1645433Y84967D02*
X1645427Y84963D01*
G01X1650394Y25138D02*
G03X1650984Y24547I591J0D01*
G01X1657677D02*
G03X1658268Y25138I0J591D01*
G01X1655512Y26319D02*
G03Y28287I0J984D01*
G01X1653150D02*
G03Y26319I0J-984D01*
G01X1655433Y39508D02*
G03I-1102J0D01*
G01X1656890Y34232D02*
G03X1658071Y35413I0J1181D01*
G01X1650591D02*
G03X1651772Y34232I1181J0D01*
G01X1655906Y39508D02*
G03I-1575J0D01*
G01X1643504Y25728D02*
G03X1645472Y23760I1968J0D01*
G01X1663189D02*
G03X1665157Y25728I0J1968D01*
G01X1649803Y47500D02*
X1648622Y46319D01*
G01X1646850Y44823D02*
X1643504Y41476D01*
G01X1656815Y42579D02*
X1655512Y40610D01*
G01X1650839Y34688D02*
X1653150Y38917D01*
G01X1646397Y84923D02*
X1646398Y84935D01*
G01X1646397Y88073D02*
X1646398Y88084D01*
G01X1646397Y91222D02*
X1646398Y91234D01*
G01X1659823Y51982D02*
Y51991D01*
G01Y56982D02*
Y56991D01*
G01Y61982D02*
Y61991D01*
G01Y66982D02*
Y66991D01*
G01Y71982D02*
Y71991D01*
G01Y76982D02*
Y76991D01*
G01Y81982D02*
Y81991D01*
G01X1665157Y25728D02*
Y41476D01*
G01X1664173Y80630D02*
Y82008D01*
G01Y75630D02*
Y77008D01*
G01Y70630D02*
Y72008D01*
G01Y65630D02*
Y67008D01*
G01Y60630D02*
Y62008D01*
G01Y55630D02*
Y57008D01*
G01Y50630D02*
Y52008D01*
G01X1661811Y182815D02*
Y44823D01*
G01X1661220Y185059D02*
Y42579D01*
G01X1661004Y52008D02*
Y50630D01*
G01Y57008D02*
Y55630D01*
G01Y62008D02*
Y60630D01*
G01Y67008D02*
Y65630D01*
G01Y72008D02*
Y70630D01*
G01Y77008D02*
Y75630D01*
G01Y82008D02*
Y80630D01*
G01X1660433Y104862D02*
Y82776D01*
G01X1659823Y56982D02*
Y57125D01*
G01Y51982D02*
Y52125D01*
G01Y66982D02*
Y67125D01*
G01Y61982D02*
Y62125D01*
G01Y76982D02*
Y77125D01*
G01Y71982D02*
Y72125D01*
G01Y81982D02*
Y82125D01*
G01Y80138D02*
Y82500D01*
G01Y75138D02*
Y77500D01*
G01Y70138D02*
Y72500D01*
G01Y65138D02*
Y67500D01*
G01Y60138D02*
Y62500D01*
G01Y55138D02*
Y57500D01*
G01Y50138D02*
Y52500D01*
G01X1659252Y103681D02*
Y83957D01*
G01X1658839Y52500D02*
Y50138D01*
G01Y57500D02*
Y55138D01*
G01Y62500D02*
Y60138D01*
G01Y67500D02*
Y65138D01*
G01Y72500D02*
Y70138D01*
G01Y77500D02*
Y75138D01*
G01Y82500D02*
Y80138D01*
G01X1658268Y31240D02*
Y25138D01*
G01X1658071Y43957D02*
Y35413D01*
G01X1656496Y82776D02*
Y46319D01*
G01X1655512Y40610D02*
Y38917D01*
G01X1655315Y83957D02*
Y47500D01*
G01X1653150Y38917D02*
Y40610D01*
G01X1650591Y35413D02*
Y43957D01*
G01X1650394Y31240D02*
Y25138D01*
G01X1649803Y47500D02*
Y180138D01*
G01X1648622Y46319D02*
Y181319D01*
G01X1646850Y81614D02*
Y42579D01*
G01X1646398Y93070D02*
Y94567D01*
G01Y89921D02*
Y91417D01*
G01Y86771D02*
Y88268D01*
G01Y83622D02*
Y85118D01*
G01X1646358Y86918D02*
Y86771D01*
G01Y83768D02*
Y83621D01*
G01Y85119D02*
Y84972D01*
G01Y90067D02*
Y89920D01*
G01Y91418D02*
Y91271D01*
G01Y88268D02*
Y88121D01*
G01Y93217D02*
Y93070D01*
G01X1645453D02*
Y93217D01*
G01Y89920D02*
Y90067D01*
G01Y91271D02*
Y91418D01*
G01Y88121D02*
Y88268D01*
G01Y86771D02*
Y86918D01*
G01Y83621D02*
Y83768D01*
G01Y84972D02*
Y85119D01*
G01X1645413Y85118D02*
Y83622D01*
G01Y91417D02*
Y89921D01*
G01Y88268D02*
Y86772D01*
G01Y94567D02*
Y93071D01*
G01X1644232Y88110D02*
Y86929D01*
G01Y84961D02*
Y83780D01*
G01Y91260D02*
Y90079D01*
G01Y94409D02*
Y93228D01*
G01X1643898Y106024D02*
Y81614D01*
G01X1643504D02*
Y106024D01*
G01Y41476D02*
Y25728D01*
G01X1640472Y93228D02*
Y94409D01*
G01Y90079D02*
Y91260D01*
G01Y86929D02*
Y88110D01*
G01Y83780D02*
Y84961D01*
G01X1646398Y93254D02*
X1646397Y93265D01*
G01X1646398Y90105D02*
X1646397Y90115D01*
G01X1646398Y86955D02*
X1646397Y86966D01*
G01X1646398Y83806D02*
X1646397Y83816D01*
G01X1659823Y81978D02*
Y81981D01*
G01Y76978D02*
Y76981D01*
G01Y71978D02*
Y71981D01*
G01Y66978D02*
Y66981D01*
G01X1655512Y38917D02*
X1657822Y34688D01*
G01X1653150Y40610D02*
X1651846Y42579D01*
G01X1659252Y83957D02*
X1660433Y82776D01*
G01X1655315Y83957D02*
X1656496Y82776D01*
G01X1665157Y41476D02*
X1661811Y44823D01*
G01X1655315Y47500D02*
X1656496Y46319D01*
G01X1645411Y93263D02*
X1645300Y93268D01*
G01X1645411Y86965D02*
X1645300Y86969D01*
G01X1644666Y93268D02*
X1644232D01*
G01X1646396D02*
X1640472D01*
G01X1646357Y93228D02*
X1640472D01*
G01X1645413Y93071D02*
X1646398D01*
G01X1645453Y93031D02*
X1646358D01*
G01Y91457D02*
X1645453D01*
G01X1646398Y91417D02*
X1645413D01*
G01X1646357Y91260D02*
X1640472D01*
G01Y91220D02*
X1646396D01*
G01Y90118D02*
X1640472D01*
G01X1646357Y90079D02*
X1640472D01*
G01X1645413Y89921D02*
X1646398D01*
G01X1645453Y89882D02*
X1646358D01*
G01Y88307D02*
X1645453D01*
G01X1646398Y88268D02*
X1645413D01*
G01X1646357Y88110D02*
X1640472D01*
G01Y88071D02*
X1646396D01*
G01X1644666Y86969D02*
X1644232D01*
G01X1646396D02*
X1640472D01*
G01X1646357Y86929D02*
X1640472D01*
G01X1645413Y86772D02*
X1646398D01*
G01X1645453Y86732D02*
X1646358D01*
G01Y85157D02*
X1645453D01*
G01X1646398Y85118D02*
X1645413D01*
G01X1646357Y84961D02*
X1640472D01*
G01Y84921D02*
X1646396D01*
G01X1659252Y83957D02*
X1655315D01*
G01X1646396Y83819D02*
X1640472D01*
G01X1646357Y83780D02*
X1640472D01*
G01X1645413Y83622D02*
X1646398D01*
G01X1645453Y83583D02*
X1646358D01*
G01X1660433Y82776D02*
X1656496D01*
G01X1659823Y82500D02*
X1658839D01*
G01X1658840Y82008D02*
X1664173D01*
G01Y81969D02*
X1659825D01*
G01X1646850Y81614D02*
X1643504D01*
G01X1664173Y80630D02*
X1658840D01*
G01X1658839Y80138D02*
X1659823D01*
G01Y77500D02*
X1658839D01*
G01X1658840Y77008D02*
X1664173D01*
G01Y76969D02*
X1659825D01*
G01X1664173Y75630D02*
X1658840D01*
G01X1658839Y75138D02*
X1659823D01*
G01Y72500D02*
X1658839D01*
G01X1658840Y72008D02*
X1664173D01*
G01Y71969D02*
X1659825D01*
G01X1664173Y70630D02*
X1658840D01*
G01X1658839Y70138D02*
X1659823D01*
G01Y67500D02*
X1658839D01*
G01X1658840Y67008D02*
X1664173D01*
G01Y66969D02*
X1659825D01*
G01X1664173Y65630D02*
X1658840D01*
G01X1658839Y65138D02*
X1659823D01*
G01Y62500D02*
X1658839D01*
G01X1658840Y62008D02*
X1664173D01*
G01Y61969D02*
X1659825D01*
G01X1664173Y60630D02*
X1658840D01*
G01X1658839Y60138D02*
X1659823D01*
G01Y57500D02*
X1658839D01*
G01X1658840Y57008D02*
X1664173D01*
G01Y56969D02*
X1659825D01*
G01X1664173Y55630D02*
X1658840D01*
G01X1658839Y55138D02*
X1659823D01*
G01Y52500D02*
X1658839D01*
G01X1658840Y52008D02*
X1664173D01*
G01Y51969D02*
X1659825D01*
G01X1664173Y50630D02*
X1658840D01*
G01X1658839Y50138D02*
X1659823D01*
G01X1655315Y47500D02*
X1649803D01*
G01X1656496Y46319D02*
X1648622D01*
G01X1661811Y44823D02*
X1646850D01*
G01X1658071Y43957D02*
X1661220D01*
G01X1650591D02*
X1646850D01*
G01Y42579D02*
X1661220D01*
G01X1655512Y40610D02*
X1653150D01*
G01X1655512Y38917D02*
X1653150D01*
G01X1658839Y82204D02*
X1659794Y82205D01*
G01X1659823Y80434D02*
X1658839Y80433D01*
G01Y77204D02*
X1659794Y77205D01*
G01X1659823Y75434D02*
X1658839Y75433D01*
G01Y72204D02*
X1659794Y72205D01*
G01X1659823Y70434D02*
X1658839Y70433D01*
G01Y67204D02*
X1659794Y67205D01*
G01X1659823Y65434D02*
X1658839Y65433D01*
G01Y62204D02*
X1659794Y62205D01*
G01X1659823Y60434D02*
X1658839Y60433D01*
G01Y57204D02*
X1659794Y57205D01*
G01X1659823Y55434D02*
X1658839Y55433D01*
G01Y52204D02*
X1659794Y52205D01*
G01X1659823Y50434D02*
X1658839Y50433D01*
G01X1656890Y34232D02*
X1651772D01*
G01X1665157Y34193D02*
X1643504D01*
G01X1658268Y31240D02*
X1650394D01*
G01Y29665D02*
X1658268D01*
G01X1655512Y28287D02*
X1653150D01*
G01Y26319D02*
X1655512D01*
G01X1657677Y24547D02*
X1650984D01*
G01X1663189Y23760D02*
X1645472D01*
G01X1645416Y94390D02*
X1645411Y94370D01*
G01X1645431Y94404D02*
X1645416Y94390D01*
G01X1645450Y94409D02*
X1645431Y94404D01*
G01X1645416Y97539D02*
X1645411Y97520D01*
G01X1645431Y97554D02*
X1645416Y97539D01*
G01X1645450Y97559D02*
X1645431Y97554D01*
G01X1645416Y100689D02*
X1645411Y100669D01*
G01X1645431Y100703D02*
X1645416Y100689D01*
G01X1645450Y100709D02*
X1645431Y100703D01*
G01X1645416Y103839D02*
X1645411Y103819D01*
G01X1645431Y103853D02*
X1645416Y103839D01*
G01X1645450Y103858D02*
X1645431Y103853D01*
G01X1646391Y96398D02*
X1646396Y96417D01*
G01X1646376Y96383D02*
X1646391Y96398D01*
G01X1646357Y96378D02*
X1646376Y96383D01*
G01X1646391Y99547D02*
X1646396Y99567D01*
G01X1646376Y99533D02*
X1646391Y99547D01*
G01X1646357Y99528D02*
X1646376Y99533D01*
G01X1646391Y102697D02*
X1646396Y102717D01*
G01X1646376Y102682D02*
X1646391Y102697D01*
G01X1646357Y102677D02*
X1646376Y102682D01*
G01X1646397Y99546D02*
X1646398Y99553D01*
G01X1646394Y99539D02*
X1646397Y99546D01*
G01X1646391Y99533D02*
X1646394Y99539D01*
G01X1646386Y99527D02*
X1646391Y99533D01*
G01X1646380Y99522D02*
X1646386Y99527D01*
G01X1646373Y99519D02*
X1646380Y99522D01*
G01X1646366Y99517D02*
X1646373Y99519D01*
G01X1646358Y99516D02*
X1646366Y99517D01*
G01X1645436Y94417D02*
X1645433Y94415D01*
G01X1645439Y94418D02*
X1645436Y94417D01*
G01X1645443Y94419D02*
X1645439Y94418D01*
G01X1645446Y94420D02*
X1645443Y94419D01*
G01X1645449Y94420D02*
X1645446D01*
G01X1645453D02*
X1645449D01*
G01X1646375Y96370D02*
X1646378Y96372D01*
G01X1646372Y96369D02*
X1646375Y96370D01*
G01X1646369Y96368D02*
X1646372Y96369D01*
G01X1646365Y96367D02*
X1646369Y96368D01*
G01X1646362Y96367D02*
X1646365D01*
G01X1646358D02*
X1646362D01*
G01X1645436Y97567D02*
X1645433Y97565D01*
G01X1645439Y97568D02*
X1645436Y97567D01*
G01X1645443Y97569D02*
X1645439Y97568D01*
G01X1645446Y97570D02*
X1645443Y97569D01*
G01X1645449Y97570D02*
X1645446D01*
G01X1645453D02*
X1645449D01*
G01X1645436Y100716D02*
X1645433Y100715D01*
G01X1645439Y100717D02*
X1645436Y100716D01*
G01X1645443Y100719D02*
X1645439Y100717D01*
G01X1645446Y100719D02*
X1645443D01*
G01X1645449Y100720D02*
X1645446Y100719D01*
G01X1645453Y100720D02*
X1645449D01*
G01X1646375Y102669D02*
X1646378Y102671D01*
G01X1646372Y102668D02*
X1646375Y102669D01*
G01X1646369Y102667D02*
X1646372Y102668D01*
G01X1646365Y102667D02*
X1646369D01*
G01X1646362Y102666D02*
X1646365Y102667D01*
G01X1646358Y102666D02*
X1646362D01*
G01X1645436Y103866D02*
X1645433Y103864D01*
G01X1645439Y103867D02*
X1645436Y103866D01*
G01X1645443Y103868D02*
X1645439Y103867D01*
G01X1645446Y103869D02*
X1645443Y103868D01*
G01X1645449Y103869D02*
X1645446D01*
G01X1645453D02*
X1645449D01*
G01X1646388Y94408D02*
X1646392Y94402D01*
G01X1646383Y94412D02*
X1646388Y94408D01*
G01X1646378Y94416D02*
X1646383Y94412D01*
G01X1646372Y94419D02*
X1646378Y94416D01*
G01X1646365Y94420D02*
X1646372Y94419D01*
G01X1646358Y94420D02*
X1646365D01*
G01X1646388Y97557D02*
X1646392Y97552D01*
G01X1646383Y97562D02*
X1646388Y97557D01*
G01X1646378Y97565D02*
X1646383Y97562D01*
G01X1646372Y97568D02*
X1646378Y97565D01*
G01X1646365Y97570D02*
X1646372Y97568D01*
G01X1646358Y97570D02*
X1646365D01*
G01X1646388Y100707D02*
X1646392Y100702D01*
G01X1646383Y100711D02*
X1646388Y100707D01*
G01X1646378Y100715D02*
X1646383Y100711D01*
G01X1646372Y100718D02*
X1646378Y100715D01*
G01X1646365Y100719D02*
X1646372Y100718D01*
G01X1646358Y100720D02*
X1646365Y100719D01*
G01X1646388Y103857D02*
X1646392Y103851D01*
G01X1646383Y103861D02*
X1646388Y103857D01*
G01X1646378Y103865D02*
X1646383Y103861D01*
G01X1646372Y103867D02*
X1646378Y103865D01*
G01X1646365Y103869D02*
X1646372Y103867D01*
G01X1646358Y103869D02*
X1646365D01*
G01X1645414Y96396D02*
X1645413Y96404D01*
G01X1645417Y96389D02*
X1645414Y96396D01*
G01X1645420Y96383D02*
X1645417Y96389D01*
G01X1645425Y96378D02*
X1645420Y96383D01*
G01X1645431Y96373D02*
X1645425Y96378D01*
G01X1645438Y96369D02*
X1645431Y96373D01*
G01X1645445Y96367D02*
X1645438Y96369D01*
G01X1645453Y96367D02*
X1645445D01*
G01X1645414Y99546D02*
X1645413Y99553D01*
G01X1645417Y99539D02*
X1645414Y99546D01*
G01X1645420Y99533D02*
X1645417Y99539D01*
G01X1645425Y99527D02*
X1645420Y99533D01*
G01X1645431Y99522D02*
X1645425Y99527D01*
G01X1645438Y99519D02*
X1645431Y99522D01*
G01X1645445Y99517D02*
X1645438Y99519D01*
G01X1645453Y99516D02*
X1645445Y99517D01*
G01X1645414Y102696D02*
X1645413Y102703D01*
G01X1645417Y102689D02*
X1645414Y102696D01*
G01X1645420Y102682D02*
X1645417Y102689D01*
G01X1645425Y102677D02*
X1645420Y102682D01*
G01X1645431Y102672D02*
X1645425Y102677D01*
G01X1645438Y102669D02*
X1645431Y102672D01*
G01X1645445Y102667D02*
X1645438Y102669D01*
G01X1645453Y102666D02*
X1645445Y102667D01*
G01X1646367Y94408D02*
X1646377Y94404D01*
G01X1646357Y94409D02*
X1646367Y94408D01*
G01Y97557D02*
X1646377Y97554D01*
G01X1646357Y97559D02*
X1646367Y97557D01*
G01Y100707D02*
X1646377Y100703D01*
G01X1646357Y100709D02*
X1646367Y100707D01*
G01Y103857D02*
X1646377Y103853D01*
G01X1646357Y103858D02*
X1646367Y103857D01*
G01X1645413Y96407D02*
Y96404D01*
G01X1645415Y96401D02*
X1645413Y96407D01*
G01X1645426Y96386D02*
X1645415Y96401D01*
G01X1645451Y96378D02*
X1645426Y96386D01*
G01X1645413Y99557D02*
Y99553D01*
G01X1645415Y99551D02*
X1645413Y99557D01*
G01X1645426Y99536D02*
X1645415Y99551D01*
G01X1645451Y99528D02*
X1645426Y99536D01*
G01X1645413Y102707D02*
Y102703D01*
G01X1645415Y102701D02*
X1645413Y102707D01*
G01X1645426Y102685D02*
X1645415Y102701D01*
G01X1645451Y102677D02*
X1645426Y102685D01*
G01X1659810Y106999D02*
X1659821Y106984D01*
G01X1659786Y107008D02*
X1659810Y106999D01*
G01Y111999D02*
X1659821Y111984D01*
G01X1659786Y112008D02*
X1659810Y111999D01*
G01Y116999D02*
X1659821Y116984D01*
G01X1659786Y117008D02*
X1659810Y116999D01*
G01Y121999D02*
X1659821Y121984D01*
G01X1659786Y122008D02*
X1659810Y121999D01*
G01X1659821Y126984D02*
X1659823Y126978D01*
G01X1659810Y126999D02*
X1659821Y126984D01*
G01X1659786Y127008D02*
X1659810Y126999D01*
G01Y131999D02*
X1659821Y131984D01*
G01X1659786Y132008D02*
X1659810Y131999D01*
G01Y136999D02*
X1659821Y136984D01*
G01X1659786Y137008D02*
X1659810Y136999D01*
G01Y141999D02*
X1659821Y141984D01*
G01X1659786Y142008D02*
X1659810Y141999D01*
G01Y146999D02*
X1659821Y146984D01*
G01X1659786Y147008D02*
X1659810Y146999D01*
G01Y151999D02*
X1659821Y151984D01*
G01X1659786Y152008D02*
X1659810Y151999D01*
G01Y156999D02*
X1659821Y156984D01*
G01X1659786Y157008D02*
X1659810Y156999D01*
G01Y161999D02*
X1659821Y161984D01*
G01X1659786Y162008D02*
X1659810Y161999D01*
G01Y166999D02*
X1659821Y166984D01*
G01X1659786Y167008D02*
X1659810Y166999D01*
G01Y171999D02*
X1659821Y171984D01*
G01X1659786Y172008D02*
X1659810Y171999D01*
G01Y176999D02*
X1659821Y176984D01*
G01X1659786Y177008D02*
X1659810Y176999D01*
G01X1646366Y94408D02*
X1646357Y94409D01*
G01X1646375Y94405D02*
X1646366Y94408D01*
G01X1646383Y94400D02*
X1646375Y94405D01*
G01X1646366Y97558D02*
X1646357Y97559D01*
G01X1646375Y97555D02*
X1646366Y97558D01*
G01X1646383Y97549D02*
X1646375Y97555D01*
G01X1646366Y100707D02*
X1646357Y100709D01*
G01X1646375Y100704D02*
X1646366Y100707D01*
G01X1646383Y100699D02*
X1646375Y100704D01*
G01X1646366Y103857D02*
X1646357Y103858D01*
G01X1646375Y103854D02*
X1646366Y103857D01*
G01X1646383Y103848D02*
X1646375Y103854D01*
G01X1645452Y96373D02*
X1645453Y96367D01*
G01X1645452Y96377D02*
Y96373D01*
G01X1645450Y96378D02*
X1645452Y96377D01*
G01Y99522D02*
X1645453Y99516D01*
G01X1645452Y99526D02*
Y99522D01*
G01X1645450Y99528D02*
X1645452Y99526D01*
G01Y102672D02*
X1645453Y102666D01*
G01X1645452Y102676D02*
Y102672D01*
G01X1645450Y102677D02*
X1645452Y102676D01*
G01X1659823Y106975D02*
Y106982D01*
G01X1659824Y106970D02*
X1659823Y106975D01*
G01X1659825Y106969D02*
X1659824Y106970D01*
G01X1659823Y111975D02*
Y111982D01*
G01X1659824Y111970D02*
X1659823Y111975D01*
G01X1659825Y111969D02*
X1659824Y111970D01*
G01X1659823Y116975D02*
Y116982D01*
G01X1659824Y116970D02*
X1659823Y116975D01*
G01X1659825Y116969D02*
X1659824Y116970D01*
G01X1659823Y121975D02*
Y121982D01*
G01X1659824Y121970D02*
X1659823Y121975D01*
G01X1659825Y121969D02*
X1659824Y121970D01*
G01X1659823Y126975D02*
Y126982D01*
G01X1659824Y126970D02*
X1659823Y126975D01*
G01X1659825Y126969D02*
X1659824Y126970D01*
G01X1659823Y131975D02*
Y131982D01*
G01X1659824Y131970D02*
X1659823Y131975D01*
G01X1659825Y131969D02*
X1659824Y131970D01*
G01X1659823Y136975D02*
Y136982D01*
G01X1659824Y136970D02*
X1659823Y136975D01*
G01X1659825Y136969D02*
X1659824Y136970D01*
G01X1659823Y141975D02*
Y141982D01*
G01X1659824Y141970D02*
X1659823Y141975D01*
G01X1659825Y141969D02*
X1659824Y141970D01*
G01X1659823Y146975D02*
Y146982D01*
G01X1659824Y146970D02*
X1659823Y146975D01*
G01X1659825Y146969D02*
X1659824Y146970D01*
G01X1659823Y151975D02*
Y151982D01*
G01X1659824Y151970D02*
X1659823Y151975D01*
G01X1659825Y151969D02*
X1659824Y151970D01*
G01X1659823Y156975D02*
Y156982D01*
G01X1659824Y156970D02*
X1659823Y156975D01*
G01X1659825Y156969D02*
X1659824Y156970D01*
G01X1659823Y161975D02*
Y161982D01*
G01X1659824Y161970D02*
X1659823Y161975D01*
G01X1659825Y161969D02*
X1659824Y161970D01*
G01X1659823Y166975D02*
Y166982D01*
G01X1659824Y166970D02*
X1659823Y166975D01*
G01X1659825Y166969D02*
X1659824Y166970D01*
G01X1659823Y171975D02*
Y171982D01*
G01X1659824Y171970D02*
X1659823Y171975D01*
G01X1659825Y171969D02*
X1659824Y171970D01*
G01X1659823Y176975D02*
Y176982D01*
G01X1659824Y176970D02*
X1659823Y176975D01*
G01X1659825Y176969D02*
X1659824Y176970D01*
G01X1645436Y96380D02*
X1645450Y96378D01*
G01X1645424Y96388D02*
X1645436Y96380D01*
G01X1645413Y96406D02*
X1645424Y96388D01*
G01X1645436Y99530D02*
X1645450Y99528D01*
G01X1645424Y99538D02*
X1645436Y99530D01*
G01X1645412Y99558D02*
X1645424Y99538D01*
G01X1646398Y96411D02*
Y96404D01*
G01X1646397Y96416D02*
X1646398Y96411D01*
G01X1646396Y96417D02*
X1646397Y96416D01*
G01X1646398Y99561D02*
Y99553D01*
G01X1646397Y99565D02*
X1646398Y99561D01*
G01X1646396Y99567D02*
X1646397Y99565D01*
G01X1646398Y102711D02*
Y102703D01*
G01X1646397Y102715D02*
X1646398Y102711D01*
G01X1646396Y102717D02*
X1646397Y102715D01*
G01X1645436Y102680D02*
X1645450Y102677D01*
G01X1645423Y102688D02*
X1645436Y102680D01*
G01X1645412Y102708D02*
X1645423Y102688D01*
G01X1646397Y94390D02*
X1646398Y94383D01*
G01X1646395Y94396D02*
X1646397Y94390D01*
G01X1646392Y94402D02*
X1646395Y94396D01*
G01X1646397Y97540D02*
X1646398Y97533D01*
G01X1646395Y97546D02*
X1646397Y97540D01*
G01X1646392Y97552D02*
X1646395Y97546D01*
G01X1646397Y100689D02*
X1646398Y100683D01*
G01X1646395Y100696D02*
X1646397Y100689D01*
G01X1646392Y100702D02*
X1646395Y100696D01*
G01X1646397Y103839D02*
X1646398Y103832D01*
G01X1646395Y103845D02*
X1646397Y103839D01*
G01X1646392Y103851D02*
X1646395Y103845D01*
G01X1646359Y96373D02*
Y96367D01*
G01X1646357Y96376D02*
X1646359Y96373D01*
G01X1646357Y96378D02*
Y96376D01*
G01X1646359Y102672D02*
Y102666D01*
G01X1646357Y102676D02*
X1646359Y102672D01*
G01X1646357Y102677D02*
Y102676D01*
G01X1658839Y107015D02*
Y107024D01*
G01Y107009D02*
Y107015D01*
G01X1658840Y107008D02*
X1658839Y107009D01*
G01Y112015D02*
Y112024D01*
G01Y112009D02*
Y112015D01*
G01X1658840Y112008D02*
X1658839Y112009D01*
G01Y117015D02*
Y117024D01*
G01Y117009D02*
Y117015D01*
G01X1658840Y117008D02*
X1658839Y117009D01*
G01Y122015D02*
Y122024D01*
G01Y122009D02*
Y122015D01*
G01X1658840Y122008D02*
X1658839Y122009D01*
G01Y127015D02*
Y127024D01*
G01Y127009D02*
Y127015D01*
G01X1658840Y127008D02*
X1658839Y127009D01*
G01Y132015D02*
Y132024D01*
G01Y132009D02*
Y132015D01*
G01X1658840Y132008D02*
X1658839Y132009D01*
G01Y137015D02*
Y137024D01*
G01Y137009D02*
Y137015D01*
G01X1658840Y137008D02*
X1658839Y137009D01*
G01Y142015D02*
Y142024D01*
G01Y142009D02*
Y142015D01*
G01X1658840Y142008D02*
X1658839Y142009D01*
G01Y147015D02*
Y147024D01*
G01Y147009D02*
Y147015D01*
G01X1658840Y147008D02*
X1658839Y147009D01*
G01Y152015D02*
Y152024D01*
G01Y152009D02*
Y152015D01*
G01X1658840Y152008D02*
X1658839Y152009D01*
G01Y157015D02*
Y157024D01*
G01Y157009D02*
Y157015D01*
G01X1658840Y157008D02*
X1658839Y157009D01*
G01Y162015D02*
Y162024D01*
G01Y162009D02*
Y162015D01*
G01X1658840Y162008D02*
X1658839Y162009D01*
G01Y167015D02*
Y167024D01*
G01Y167009D02*
Y167015D01*
G01X1658840Y167008D02*
X1658839Y167009D01*
G01Y172015D02*
Y172024D01*
G01Y172009D02*
Y172015D01*
G01X1658840Y172008D02*
X1658839Y172009D01*
G01Y177015D02*
Y177024D01*
G01Y177009D02*
Y177015D01*
G01X1658840Y177008D02*
X1658839Y177009D01*
G01X1659815Y107152D02*
X1659823Y107125D01*
G01X1659805Y107178D02*
X1659815Y107152D01*
G01X1659794Y107205D02*
X1659805Y107178D01*
G01X1659815Y112152D02*
X1659823Y112125D01*
G01X1659805Y112178D02*
X1659815Y112152D01*
G01X1659794Y112205D02*
X1659805Y112178D01*
G01X1659815Y117152D02*
X1659823Y117125D01*
G01X1659805Y117178D02*
X1659815Y117152D01*
G01X1659794Y117205D02*
X1659805Y117178D01*
G01X1659815Y122152D02*
X1659823Y122125D01*
G01X1659805Y122178D02*
X1659815Y122152D01*
G01X1659794Y122205D02*
X1659805Y122178D01*
G01X1659815Y127152D02*
X1659823Y127125D01*
G01X1659805Y127178D02*
X1659815Y127152D01*
G01X1659794Y127205D02*
X1659805Y127178D01*
G01X1659815Y132152D02*
X1659823Y132125D01*
G01X1659805Y132178D02*
X1659815Y132152D01*
G01X1659794Y132205D02*
X1659805Y132178D01*
G01X1659815Y137152D02*
X1659823Y137125D01*
G01X1659805Y137178D02*
X1659815Y137152D01*
G01X1659794Y137205D02*
X1659805Y137178D01*
G01X1659815Y142152D02*
X1659823Y142125D01*
G01X1659805Y142178D02*
X1659815Y142152D01*
G01X1659794Y142205D02*
X1659805Y142178D01*
G01X1659815Y147152D02*
X1659823Y147125D01*
G01X1659805Y147178D02*
X1659815Y147152D01*
G01X1659794Y147205D02*
X1659805Y147178D01*
G01X1659815Y152152D02*
X1659823Y152125D01*
G01X1659805Y152178D02*
X1659815Y152152D01*
G01X1659794Y152205D02*
X1659805Y152178D01*
G01X1659815Y157152D02*
X1659823Y157125D01*
G01X1659805Y157178D02*
X1659815Y157152D01*
G01X1659794Y157205D02*
X1659805Y157178D01*
G01X1659815Y162152D02*
X1659823Y162125D01*
G01X1659805Y162178D02*
X1659815Y162152D01*
G01X1659794Y162205D02*
X1659805Y162178D01*
G01X1659815Y167152D02*
X1659823Y167125D01*
G01X1659805Y167178D02*
X1659815Y167152D01*
G01X1659794Y167205D02*
X1659805Y167178D01*
G01X1659815Y172152D02*
X1659823Y172125D01*
G01X1659805Y172178D02*
X1659815Y172152D01*
G01X1659794Y172205D02*
X1659805Y172178D01*
G01X1659815Y177152D02*
X1659823Y177125D01*
G01X1659805Y177178D02*
X1659815Y177152D01*
G01X1659794Y177205D02*
X1659805Y177178D01*
G01X1659806Y107003D02*
X1659786Y107008D01*
G01X1659820Y106988D02*
X1659806Y107003D01*
G01X1659825Y106969D02*
X1659820Y106988D01*
G01X1659806Y112003D02*
X1659786Y112008D01*
G01X1659820Y111988D02*
X1659806Y112003D01*
G01X1659825Y111969D02*
X1659820Y111988D01*
G01X1659806Y117003D02*
X1659786Y117008D01*
G01X1659820Y116988D02*
X1659806Y117003D01*
G01X1659825Y116969D02*
X1659820Y116988D01*
G01X1659806Y122003D02*
X1659786Y122008D01*
G01X1659820Y121988D02*
X1659806Y122003D01*
G01X1659825Y121969D02*
X1659820Y121988D01*
G01X1659806Y127003D02*
X1659786Y127008D01*
G01X1659820Y126988D02*
X1659806Y127003D01*
G01X1659825Y126969D02*
X1659820Y126988D01*
G01X1659806Y132003D02*
X1659786Y132008D01*
G01X1659820Y131988D02*
X1659806Y132003D01*
G01X1659825Y131969D02*
X1659820Y131988D01*
G01X1659806Y137003D02*
X1659786Y137008D01*
G01X1659820Y136988D02*
X1659806Y137003D01*
G01X1659825Y136969D02*
X1659820Y136988D01*
G01X1659806Y142003D02*
X1659786Y142008D01*
G01X1659820Y141988D02*
X1659806Y142003D01*
G01X1659825Y141969D02*
X1659820Y141988D01*
G01X1659806Y147003D02*
X1659786Y147008D01*
G01X1659820Y146988D02*
X1659806Y147003D01*
G01X1659825Y146969D02*
X1659820Y146988D01*
G01X1659806Y152003D02*
X1659786Y152008D01*
G01X1659820Y151988D02*
X1659806Y152003D01*
G01X1659825Y151969D02*
X1659820Y151988D01*
G01X1659806Y157003D02*
X1659786Y157008D01*
G01X1659820Y156988D02*
X1659806Y157003D01*
G01X1659825Y156969D02*
X1659820Y156988D01*
G01X1659806Y162003D02*
X1659786Y162008D01*
G01X1659820Y161988D02*
X1659806Y162003D01*
G01X1659825Y161969D02*
X1659820Y161988D01*
G01X1659806Y167003D02*
X1659786Y167008D01*
G01X1659820Y166988D02*
X1659806Y167003D01*
G01X1659825Y166969D02*
X1659820Y166988D01*
G01X1659806Y172003D02*
X1659786Y172008D01*
G01X1659820Y171988D02*
X1659806Y172003D01*
G01X1659825Y171969D02*
X1659820Y171988D01*
G01X1659806Y177003D02*
X1659786Y177008D01*
G01X1659820Y176988D02*
X1659806Y177003D01*
G01X1659825Y176969D02*
X1659820Y176988D01*
G01X1646390Y94391D02*
X1646383Y94400D01*
G01X1646395Y94381D02*
X1646390Y94391D01*
G01X1646396Y94370D02*
X1646395Y94381D01*
G01X1646390Y97541D02*
X1646383Y97549D01*
G01X1646395Y97531D02*
X1646390Y97541D01*
G01X1646396Y97520D02*
X1646395Y97531D01*
G01X1646390Y100691D02*
X1646383Y100699D01*
G01X1646395Y100680D02*
X1646390Y100691D01*
G01X1646396Y100669D02*
X1646395Y100680D01*
G01X1646390Y103840D02*
X1646383Y103848D01*
G01X1646395Y103830D02*
X1646390Y103840D01*
G01X1646396Y103819D02*
X1646395Y103830D01*
G01X1659790Y107106D02*
X1659794Y107205D01*
G01X1659784Y107034D02*
X1659790Y107106D01*
G01X1659786Y107008D02*
X1659784Y107034D01*
G01X1659790Y112106D02*
X1659794Y112205D01*
G01X1659784Y112034D02*
X1659790Y112106D01*
G01X1659786Y112008D02*
X1659784Y112034D01*
G01X1659790Y117106D02*
X1659794Y117205D01*
G01X1659784Y117034D02*
X1659790Y117106D01*
G01X1659786Y117008D02*
X1659784Y117034D01*
G01X1659790Y122106D02*
X1659794Y122205D01*
G01X1659784Y122034D02*
X1659790Y122106D01*
G01X1659786Y122008D02*
X1659784Y122034D01*
G01X1659790Y127106D02*
X1659794Y127205D01*
G01X1659784Y127034D02*
X1659790Y127106D01*
G01X1659786Y127008D02*
X1659784Y127034D01*
G01X1659790Y132106D02*
X1659794Y132205D01*
G01X1659784Y132034D02*
X1659790Y132106D01*
G01X1659786Y132008D02*
X1659784Y132034D01*
G01X1659790Y137106D02*
X1659794Y137205D01*
G01X1659784Y137034D02*
X1659790Y137106D01*
G01X1659786Y137008D02*
X1659784Y137034D01*
G01X1659790Y142106D02*
X1659794Y142205D01*
G01X1659784Y142034D02*
X1659790Y142106D01*
G01X1659786Y142008D02*
X1659784Y142034D01*
G01X1659790Y147106D02*
X1659794Y147205D01*
G01X1659784Y147034D02*
X1659790Y147106D01*
G01X1659786Y147008D02*
X1659784Y147034D01*
G01X1659790Y152106D02*
X1659794Y152205D01*
G01X1659784Y152034D02*
X1659790Y152106D01*
G01X1659786Y152008D02*
X1659784Y152034D01*
G01X1659790Y157106D02*
X1659794Y157205D01*
G01X1659784Y157034D02*
X1659790Y157106D01*
G01X1659786Y157008D02*
X1659784Y157034D01*
G01X1659790Y162106D02*
X1659794Y162205D01*
G01X1659784Y162034D02*
X1659790Y162106D01*
G01X1659786Y162008D02*
X1659784Y162034D01*
G01X1659790Y167106D02*
X1659794Y167205D01*
G01X1659784Y167034D02*
X1659790Y167106D01*
G01X1659786Y167008D02*
X1659784Y167034D01*
G01X1659790Y172106D02*
X1659794Y172205D01*
G01X1659784Y172034D02*
X1659790Y172106D01*
G01X1659786Y172008D02*
X1659784Y172034D01*
G01X1659790Y177106D02*
X1659794Y177205D01*
G01X1659784Y177034D02*
X1659790Y177106D01*
G01X1659786Y177008D02*
X1659784Y177034D01*
G01X1645413Y96411D02*
Y96404D01*
G01X1645412Y96416D02*
X1645413Y96411D01*
G01Y96406D02*
X1645412Y96416D01*
G01X1645454Y104043D02*
X1645453Y104055D01*
G01X1645450Y104030D02*
X1645454Y104043D01*
G01X1645450Y104016D02*
Y104030D01*
G01X1645454Y100893D02*
X1645453Y100906D01*
G01X1645450Y100880D02*
X1645454Y100893D01*
G01X1645450Y100866D02*
Y100880D01*
G01X1645454Y97743D02*
X1645453Y97756D01*
G01X1645450Y97730D02*
X1645454Y97743D01*
G01X1645450Y97717D02*
Y97730D01*
G01X1645454Y94594D02*
X1645453Y94606D01*
G01X1645450Y94581D02*
X1645454Y94594D01*
G01X1645450Y94567D02*
Y94581D01*
G01X1658839Y175628D02*
X1658840Y175630D01*
G01X1658839Y175622D02*
Y175628D01*
G01Y175614D02*
Y175622D01*
G01Y170628D02*
X1658840Y170630D01*
G01X1658839Y170622D02*
Y170628D01*
G01Y170614D02*
Y170622D01*
G01Y165628D02*
X1658840Y165630D01*
G01X1658839Y165622D02*
Y165628D01*
G01Y165614D02*
Y165622D01*
G01Y160628D02*
X1658840Y160630D01*
G01X1658839Y160622D02*
Y160628D01*
G01Y160614D02*
Y160622D01*
G01Y155628D02*
X1658840Y155630D01*
G01X1658839Y155622D02*
Y155628D01*
G01Y155614D02*
Y155622D01*
G01Y150628D02*
X1658840Y150630D01*
G01X1658839Y150622D02*
Y150628D01*
G01Y150614D02*
Y150622D01*
G01Y145628D02*
X1658840Y145630D01*
G01X1658839Y145622D02*
Y145628D01*
G01Y145614D02*
Y145622D01*
G01Y140628D02*
X1658840Y140630D01*
G01X1658839Y140622D02*
Y140628D01*
G01Y140614D02*
Y140622D01*
G01Y135628D02*
X1658840Y135630D01*
G01X1658839Y135622D02*
Y135628D01*
G01Y135614D02*
Y135622D01*
G01Y130628D02*
X1658840Y130630D01*
G01X1658839Y130622D02*
Y130628D01*
G01Y130614D02*
Y130622D01*
G01Y125628D02*
X1658840Y125630D01*
G01X1658839Y125622D02*
Y125628D01*
G01Y125614D02*
Y125622D01*
G01Y120628D02*
X1658840Y120630D01*
G01X1658839Y120622D02*
Y120628D01*
G01Y120614D02*
Y120622D01*
G01Y115628D02*
X1658840Y115630D01*
G01X1658839Y115622D02*
Y115628D01*
G01Y115614D02*
Y115622D01*
G01Y110628D02*
X1658840Y110630D01*
G01X1658839Y110622D02*
Y110628D01*
G01Y110614D02*
Y110622D01*
G01Y105628D02*
X1658840Y105630D01*
G01X1658839Y105622D02*
Y105628D01*
G01Y105614D02*
Y105622D01*
G01X1645413Y102711D02*
Y102703D01*
G01X1645412Y102715D02*
X1645413Y102711D01*
G01X1645412Y102707D02*
Y102715D01*
G01X1645450Y102506D02*
X1645449Y102519D01*
G01X1645454Y102493D02*
X1645450Y102506D01*
G01X1645453Y102480D02*
X1645454Y102493D01*
G01X1645450Y99356D02*
X1645449Y99370D01*
G01X1645454Y99343D02*
X1645450Y99356D01*
G01X1645453Y99331D02*
X1645454Y99343D01*
G01X1645450Y96206D02*
X1645449Y96220D01*
G01X1645454Y96194D02*
X1645450Y96206D01*
G01X1645453Y96181D02*
X1645454Y96194D01*
G01X1646361Y104030D02*
X1646362Y104016D01*
G01X1646357Y104043D02*
X1646361Y104030D01*
G01X1646358Y104055D02*
X1646357Y104043D01*
G01X1646361Y100880D02*
X1646362Y100866D01*
G01X1646357Y100893D02*
X1646361Y100880D01*
G01X1646358Y100906D02*
X1646357Y100893D01*
G01X1646361Y97730D02*
X1646362Y97717D01*
G01X1646357Y97743D02*
X1646361Y97730D01*
G01X1646358Y97756D02*
X1646357Y97743D01*
G01X1646361Y94581D02*
X1646362Y94567D01*
G01X1646357Y94594D02*
X1646361Y94581D01*
G01X1646358Y94606D02*
X1646357Y94594D01*
G01X1645413Y99561D02*
Y99554D01*
G01X1645412Y99565D02*
X1645413Y99561D01*
G01X1645412Y99558D02*
Y99565D01*
G01X1646357Y102493D02*
X1646358Y102480D01*
G01X1646360Y102506D02*
X1646357Y102493D01*
G01X1646361Y102519D02*
X1646360Y102506D01*
G01X1646357Y99343D02*
X1646358Y99331D01*
G01X1646360Y99356D02*
X1646357Y99343D01*
G01X1646361Y99370D02*
X1646360Y99356D01*
G01X1646357Y96194D02*
X1646358Y96181D01*
G01X1646360Y96206D02*
X1646357Y96194D01*
G01X1646361Y96220D02*
X1646360Y96206D01*
G01X1645426Y103850D02*
X1645450Y103858D01*
G01X1645415Y103835D02*
X1645426Y103850D01*
G01X1645413Y103828D02*
X1645415Y103835D01*
G01X1645426Y100700D02*
X1645450Y100709D01*
G01X1645415Y100685D02*
X1645426Y100700D01*
G01X1645413Y100679D02*
X1645415Y100685D01*
G01X1645426Y97550D02*
X1645450Y97559D01*
G01X1645415Y97536D02*
X1645426Y97550D01*
G01X1645413Y97529D02*
X1645415Y97536D01*
G01X1645426Y94401D02*
X1645450Y94409D01*
G01X1645415Y94386D02*
X1645426Y94401D01*
G01X1645413Y94380D02*
X1645415Y94386D01*
G01X1646398Y103825D02*
Y103832D01*
G01X1646397Y103820D02*
X1646398Y103825D01*
G01X1646396Y103819D02*
X1646397Y103820D01*
G01X1646398Y100676D02*
Y100683D01*
G01X1646397Y100671D02*
X1646398Y100676D01*
G01X1646396Y100669D02*
X1646397Y100671D01*
G01X1646398Y97526D02*
Y97533D01*
G01X1646397Y97521D02*
X1646398Y97526D01*
G01X1646396Y97520D02*
X1646397Y97521D01*
G01X1646398Y94376D02*
Y94383D01*
G01X1646397Y94372D02*
X1646398Y94376D01*
G01X1646396Y94370D02*
X1646397Y94372D01*
G01X1659823Y175622D02*
Y175613D01*
G01X1659824Y175628D02*
X1659823Y175622D01*
G01X1659826Y175630D02*
X1659824Y175628D01*
G01X1659823Y170622D02*
Y170613D01*
G01X1659824Y170628D02*
X1659823Y170622D01*
G01X1659826Y170630D02*
X1659824Y170628D01*
G01X1659823Y165622D02*
Y165613D01*
G01X1659824Y165628D02*
X1659823Y165622D01*
G01X1659826Y165630D02*
X1659824Y165628D01*
G01X1646369Y102679D02*
X1646357Y102677D01*
G01X1646379Y102684D02*
X1646369Y102679D01*
G01Y99530D02*
X1646357Y99528D01*
G01X1646379Y99534D02*
X1646369Y99530D01*
G01Y96380D02*
X1646357Y96378D01*
G01X1646379Y96385D02*
X1646369Y96380D01*
G01X1646358Y103863D02*
Y103869D01*
G01X1646357Y103859D02*
X1646358Y103863D01*
G01X1646357Y103858D02*
Y103859D01*
G01X1646358Y100714D02*
Y100720D01*
G01X1646357Y100710D02*
X1646358Y100714D01*
G01X1646357Y100709D02*
Y100710D01*
G01X1646358Y97564D02*
Y97570D01*
G01X1646357Y97560D02*
X1646358Y97564D01*
G01X1646357Y97559D02*
Y97560D01*
G01X1646358Y94415D02*
Y94420D01*
G01X1646357Y94411D02*
X1646358Y94415D01*
G01X1646357Y94409D02*
Y94411D01*
G01X1659823Y160622D02*
Y160613D01*
G01X1659824Y160628D02*
X1659823Y160622D01*
G01X1659826Y160630D02*
X1659824Y160628D01*
G01X1659823Y155622D02*
Y155613D01*
G01X1659824Y155628D02*
X1659823Y155622D01*
G01X1659826Y155630D02*
X1659824Y155628D01*
G01X1659823Y150622D02*
Y150613D01*
G01X1659824Y150628D02*
X1659823Y150622D01*
G01X1659826Y150630D02*
X1659824Y150628D01*
G01X1659823Y145622D02*
Y145613D01*
G01X1659824Y145628D02*
X1659823Y145622D01*
G01X1659826Y145630D02*
X1659824Y145628D01*
G01X1659823Y140622D02*
Y140613D01*
G01X1659824Y140628D02*
X1659823Y140622D01*
G01X1659826Y140630D02*
X1659824Y140628D01*
G01X1659823Y135622D02*
Y135613D01*
G01X1659824Y135628D02*
X1659823Y135622D01*
G01X1659826Y135630D02*
X1659824Y135628D01*
G01X1659823Y130622D02*
Y130613D01*
G01X1659824Y130628D02*
X1659823Y130622D01*
G01X1659826Y130630D02*
X1659824Y130628D01*
G01X1659823Y125622D02*
Y125613D01*
G01X1659824Y125628D02*
X1659823Y125622D01*
G01X1659826Y125630D02*
X1659824Y125628D01*
G01X1659823Y120622D02*
Y120613D01*
G01X1659824Y120628D02*
X1659823Y120622D01*
G01X1659826Y120630D02*
X1659824Y120628D01*
G01X1659823Y115622D02*
Y115613D01*
G01X1659824Y115628D02*
X1659823Y115622D01*
G01X1659826Y115630D02*
X1659824Y115628D01*
G01X1659823Y110622D02*
Y110613D01*
G01X1659824Y110628D02*
X1659823Y110622D01*
G01X1659826Y110630D02*
X1659824Y110628D01*
G01X1659823Y105622D02*
Y105613D01*
G01X1659824Y105628D02*
X1659823Y105622D01*
G01X1659826Y105630D02*
X1659824Y105628D01*
G01X1645413Y103825D02*
Y103832D01*
G01X1645412Y103820D02*
X1645413Y103825D01*
G01X1645411Y103819D02*
X1645412Y103820D01*
G01X1645413Y100675D02*
Y100683D01*
G01X1645412Y100671D02*
X1645413Y100675D01*
G01X1645411Y100669D02*
X1645412Y100671D01*
G01X1645413Y97526D02*
Y97533D01*
G01X1645412Y97521D02*
X1645413Y97526D01*
G01X1645411Y97520D02*
X1645412Y97521D01*
G01X1645413Y94376D02*
Y94383D01*
G01X1645412Y94372D02*
X1645413Y94376D01*
G01X1645411Y94370D02*
X1645412Y94372D01*
G01X1646395Y102691D02*
X1646398Y102703D01*
G01X1646389Y102679D02*
X1646395Y102691D01*
G01X1646378Y102671D02*
X1646389Y102679D01*
G01X1646395Y96391D02*
X1646398Y96404D01*
G01X1646389Y96380D02*
X1646395Y96391D01*
G01X1646378Y96372D02*
X1646389Y96380D01*
G01X1645452Y103863D02*
Y103869D01*
G01Y103859D02*
Y103863D01*
G01X1645450Y103858D02*
X1645452Y103859D01*
G01Y100713D02*
Y100720D01*
G01Y100710D02*
Y100713D01*
G01X1645450Y100709D02*
X1645452Y100710D01*
G01Y97564D02*
Y97570D01*
G01Y97560D02*
Y97564D01*
G01X1645450Y97559D02*
X1645452Y97560D01*
G01Y94414D02*
Y94420D01*
G01Y94411D02*
Y94414D01*
G01X1645450Y94409D02*
X1645452Y94411D01*
G01X1645414Y103839D02*
X1645413Y103832D01*
G01X1645416Y103845D02*
X1645414Y103839D01*
G01X1645419Y103851D02*
X1645416Y103845D01*
G01X1645422Y103856D02*
X1645419Y103851D01*
G01X1645427Y103861D02*
X1645422Y103856D01*
G01X1645433Y103864D02*
X1645427Y103861D01*
G01X1645414Y100689D02*
X1645413Y100683D01*
G01X1645416Y100695D02*
X1645414Y100689D01*
G01X1645419Y100701D02*
X1645416Y100695D01*
G01X1645422Y100706D02*
X1645419Y100701D01*
G01X1645427Y100711D02*
X1645422Y100706D01*
G01X1645433Y100715D02*
X1645427Y100711D01*
G01X1645414Y97539D02*
X1645413Y97533D01*
G01X1645416Y97546D02*
X1645414Y97539D01*
G01X1645419Y97552D02*
X1645416Y97546D01*
G01X1645422Y97557D02*
X1645419Y97552D01*
G01X1645427Y97561D02*
X1645422Y97557D01*
G01X1645433Y97565D02*
X1645427Y97561D01*
G01X1645414Y94390D02*
X1645413Y94383D01*
G01X1645416Y94396D02*
X1645414Y94390D01*
G01X1645419Y94402D02*
X1645416Y94396D01*
G01X1645422Y94407D02*
X1645419Y94402D01*
G01X1645427Y94412D02*
X1645422Y94407D01*
G01X1645433Y94415D02*
X1645427Y94412D01*
G01X1656220Y188130D02*
G03I-1889J0D01*
G01X1656693D02*
G03I-2362J0D01*
G01X1659252Y103681D02*
X1660433Y104862D01*
G01X1655315Y103681D02*
X1656496Y104862D01*
G01X1665157Y186161D02*
X1661811Y182815D01*
G01X1655315Y180138D02*
X1656496Y181319D01*
G01X1651846Y185059D02*
X1653150Y187028D01*
G01X1657822Y192950D02*
X1655512Y188720D01*
G01X1646397Y94372D02*
X1646398Y94383D01*
G01X1646397Y97522D02*
X1646398Y97533D01*
G01X1646397Y100671D02*
X1646398Y100683D01*
G01X1646397Y103821D02*
X1646398Y103832D01*
G01X1659823Y106982D02*
Y106991D01*
G01Y111982D02*
Y111991D01*
G01Y116982D02*
Y116991D01*
G01Y121982D02*
Y121991D01*
G01Y126982D02*
Y126991D01*
G01Y131982D02*
Y131991D01*
G01Y136982D02*
Y136991D01*
G01Y141982D02*
Y141991D01*
G01Y146982D02*
Y146991D01*
G01Y151982D02*
Y151991D01*
G01Y156982D02*
Y156991D01*
G01Y161982D02*
Y161991D01*
G01Y166982D02*
Y166991D01*
G01Y171982D02*
Y171991D01*
G01Y176982D02*
Y176991D01*
G01X1665157Y186161D02*
Y201909D01*
G01X1664173Y175630D02*
Y177008D01*
G01Y170630D02*
Y172008D01*
G01Y165630D02*
Y167008D01*
G01Y160630D02*
Y162008D01*
G01Y155630D02*
Y157008D01*
G01Y150630D02*
Y152008D01*
G01Y145630D02*
Y147008D01*
G01Y140630D02*
Y142008D01*
G01Y135630D02*
Y137008D01*
G01Y130630D02*
Y132008D01*
G01Y125630D02*
Y127008D01*
G01Y120630D02*
Y122008D01*
G01Y115630D02*
Y117008D01*
G01Y110630D02*
Y112008D01*
G01Y105630D02*
Y107008D01*
G01X1661004D02*
Y105630D01*
G01Y112008D02*
Y110630D01*
G01Y117008D02*
Y115630D01*
G01Y122008D02*
Y120630D01*
G01Y127008D02*
Y125630D01*
G01Y132008D02*
Y130630D01*
G01Y137008D02*
Y135630D01*
G01Y142008D02*
Y140630D01*
G01Y147008D02*
Y145630D01*
G01Y152008D02*
Y150630D01*
G01Y157008D02*
Y155630D01*
G01Y162008D02*
Y160630D01*
G01Y167008D02*
Y165630D01*
G01Y172008D02*
Y170630D01*
G01Y177008D02*
Y175630D01*
G01X1659823Y106982D02*
Y107125D01*
G01Y116982D02*
Y117125D01*
G01Y111982D02*
Y112125D01*
G01Y126982D02*
Y127125D01*
G01Y121982D02*
Y122125D01*
G01Y136982D02*
Y137125D01*
G01Y131982D02*
Y132125D01*
G01Y146982D02*
Y147125D01*
G01Y141982D02*
Y142125D01*
G01Y156982D02*
Y157125D01*
G01Y151982D02*
Y152125D01*
G01Y166982D02*
Y167125D01*
G01Y161982D02*
Y162125D01*
G01Y176982D02*
Y177125D01*
G01Y171982D02*
Y172125D01*
G01Y175138D02*
Y177500D01*
G01Y170138D02*
Y172500D01*
G01Y165138D02*
Y167500D01*
G01Y160138D02*
Y162500D01*
G01Y155138D02*
Y157500D01*
G01Y150138D02*
Y152500D01*
G01Y145138D02*
Y147500D01*
G01Y140138D02*
Y142500D01*
G01Y135138D02*
Y137500D01*
G01Y130138D02*
Y132500D01*
G01Y125138D02*
Y127500D01*
G01Y120138D02*
Y122500D01*
G01Y115138D02*
Y117500D01*
G01Y110138D02*
Y112500D01*
G01Y105138D02*
Y107500D01*
G01X1658839D02*
Y105138D01*
G01Y112500D02*
Y110138D01*
G01Y117500D02*
Y115138D01*
G01Y122500D02*
Y120138D01*
G01Y127500D02*
Y125138D01*
G01Y132500D02*
Y130138D01*
G01Y137500D02*
Y135138D01*
G01Y142500D02*
Y140138D01*
G01Y147500D02*
Y145138D01*
G01Y152500D02*
Y150138D01*
G01Y157500D02*
Y155138D01*
G01Y162500D02*
Y160138D01*
G01Y167500D02*
Y165138D01*
G01Y172500D02*
Y170138D01*
G01Y177500D02*
Y175138D01*
G01X1658071Y192224D02*
Y183681D01*
G01X1656496Y181319D02*
Y104862D01*
G01X1655512Y188720D02*
Y187028D01*
G01X1655315Y180138D02*
Y103681D01*
G01X1653150Y187028D02*
Y188720D01*
G01X1650591Y183681D02*
Y192224D01*
G01X1646850Y185059D02*
Y106024D01*
G01X1646398Y102519D02*
Y104016D01*
G01Y99370D02*
Y100866D01*
G01Y96220D02*
Y97717D01*
G01X1646358Y96367D02*
Y96220D01*
G01Y94567D02*
Y94420D01*
G01Y99516D02*
Y99369D01*
G01Y100867D02*
Y100720D01*
G01Y97717D02*
Y97570D01*
G01Y102666D02*
Y102519D01*
G01Y104016D02*
Y103869D01*
G01X1645453Y102519D02*
Y102666D01*
G01Y103869D02*
Y104016D01*
G01Y99369D02*
Y99516D01*
G01Y100720D02*
Y100867D01*
G01Y97570D02*
Y97717D01*
G01Y96220D02*
Y96367D01*
G01Y94420D02*
Y94567D01*
G01X1645413Y100866D02*
Y99370D01*
G01Y97717D02*
Y96220D01*
G01Y104016D02*
Y102520D01*
G01X1644232Y97559D02*
Y96378D01*
G01Y100709D02*
Y99528D01*
G01Y103858D02*
Y102677D01*
G01X1643504Y201909D02*
Y186161D01*
G01X1640472Y102677D02*
Y103858D01*
G01Y99528D02*
Y100709D01*
G01Y96378D02*
Y97559D01*
G01X1646398Y102703D02*
X1646397Y102714D01*
G01X1646398Y99554D02*
X1646397Y99564D01*
G01X1646398Y96404D02*
X1646397Y96415D01*
G01X1646357Y99528D02*
X1646360Y99516D01*
G01X1653150Y188720D02*
X1650839Y192950D01*
G01X1655512Y187028D02*
X1656815Y185059D01*
G01X1648622Y181319D02*
X1649803Y180138D01*
G01X1646850Y182815D02*
X1643504Y186161D01*
G01X1645300Y102717D02*
X1645412Y102708D01*
G01X1645411Y96414D02*
X1645300Y96417D01*
G01X1653150Y187028D02*
X1655512D01*
G01X1646850Y185059D02*
X1661220D01*
G01X1646850Y183681D02*
X1650591D01*
G01X1661220D02*
X1658071D01*
G01X1646850Y182815D02*
X1661811D01*
G01X1648622Y181319D02*
X1656496D01*
G01X1649803Y180138D02*
X1655315D01*
G01X1659823Y177500D02*
X1658839D01*
G01X1658840Y177008D02*
X1664173D01*
G01Y176969D02*
X1659825D01*
G01X1664173Y175630D02*
X1658840D01*
G01X1658839Y175138D02*
X1659823D01*
G01Y172500D02*
X1658839D01*
G01X1658840Y172008D02*
X1664173D01*
G01Y171969D02*
X1659825D01*
G01X1664173Y170630D02*
X1658840D01*
G01X1658839Y170138D02*
X1659823D01*
G01Y167500D02*
X1658839D01*
G01X1658840Y167008D02*
X1664173D01*
G01Y166969D02*
X1659825D01*
G01X1664173Y165630D02*
X1658840D01*
G01X1658839Y165138D02*
X1659823D01*
G01Y162500D02*
X1658839D01*
G01X1658840Y162008D02*
X1664173D01*
G01Y161969D02*
X1659825D01*
G01X1664173Y160630D02*
X1658840D01*
G01X1658839Y160138D02*
X1659823D01*
G01Y157500D02*
X1658839D01*
G01X1658840Y157008D02*
X1664173D01*
G01Y156969D02*
X1659825D01*
G01X1664173Y155630D02*
X1658840D01*
G01X1658839Y155138D02*
X1659823D01*
G01Y152500D02*
X1658839D01*
G01X1658840Y152008D02*
X1664173D01*
G01Y151969D02*
X1659825D01*
G01X1664173Y150630D02*
X1658840D01*
G01X1658839Y150138D02*
X1659823D01*
G01Y147500D02*
X1658839D01*
G01X1658840Y147008D02*
X1664173D01*
G01Y146969D02*
X1659825D01*
G01X1664173Y145630D02*
X1658840D01*
G01X1658839Y145138D02*
X1659823D01*
G01Y142500D02*
X1658839D01*
G01X1658840Y142008D02*
X1664173D01*
G01Y141969D02*
X1659825D01*
G01X1664173Y140630D02*
X1658840D01*
G01X1658839Y140138D02*
X1659823D01*
G01Y137500D02*
X1658839D01*
G01X1658840Y137008D02*
X1664173D01*
G01Y136969D02*
X1659825D01*
G01X1664173Y135630D02*
X1658840D01*
G01X1658839Y135138D02*
X1659823D01*
G01Y132500D02*
X1658839D01*
G01X1658840Y132008D02*
X1664173D01*
G01Y131969D02*
X1659825D01*
G01X1664173Y130630D02*
X1658840D01*
G01X1658839Y130138D02*
X1659823D01*
G01Y127500D02*
X1658839D01*
G01X1658840Y127008D02*
X1664173D01*
G01Y126969D02*
X1659825D01*
G01X1664173Y125630D02*
X1658840D01*
G01X1658839Y125138D02*
X1659823D01*
G01Y122500D02*
X1658839D01*
G01X1658840Y122008D02*
X1664173D01*
G01Y121969D02*
X1659825D01*
G01X1664173Y120630D02*
X1658840D01*
G01X1658839Y120138D02*
X1659823D01*
G01Y117500D02*
X1658839D01*
G01Y177204D02*
X1659794Y177205D01*
G01X1659823Y175434D02*
X1658839Y175433D01*
G01Y172204D02*
X1659794Y172205D01*
G01X1659823Y170434D02*
X1658839Y170433D01*
G01Y167204D02*
X1659794Y167205D01*
G01X1659823Y165434D02*
X1658839Y165433D01*
G01Y162204D02*
X1659794Y162205D01*
G01X1659823Y160434D02*
X1658839Y160433D01*
G01Y157204D02*
X1659794Y157205D01*
G01X1659823Y155434D02*
X1658839Y155433D01*
G01Y152204D02*
X1659794Y152205D01*
G01X1659823Y150434D02*
X1658839Y150433D01*
G01Y147204D02*
X1659794Y147205D01*
G01X1659823Y145434D02*
X1658839Y145433D01*
G01Y142204D02*
X1659794Y142205D01*
G01X1659823Y140434D02*
X1658839Y140433D01*
G01Y137204D02*
X1659794Y137205D01*
G01X1659823Y135434D02*
X1658839Y135433D01*
G01Y132204D02*
X1659794Y132205D01*
G01X1659823Y130434D02*
X1658839Y130433D01*
G01Y127204D02*
X1659794Y127205D01*
G01X1659823Y125434D02*
X1658839Y125433D01*
G01Y122204D02*
X1659794Y122205D01*
G01X1659823Y120434D02*
X1658839Y120433D01*
G01X1658840Y117008D02*
X1664173D01*
G01Y116969D02*
X1659825D01*
G01X1664173Y115630D02*
X1658840D01*
G01X1658839Y115138D02*
X1659823D01*
G01Y112500D02*
X1658839D01*
G01X1658840Y112008D02*
X1664173D01*
G01Y111969D02*
X1659825D01*
G01X1664173Y110630D02*
X1658840D01*
G01X1658839Y110138D02*
X1659823D01*
G01Y107500D02*
X1658839D01*
G01X1658840Y107008D02*
X1664173D01*
G01Y106969D02*
X1659825D01*
G01X1646850Y106024D02*
X1643504D01*
G01X1664173Y105630D02*
X1658840D01*
G01X1658839Y105138D02*
X1659823D01*
G01X1656496Y104862D02*
X1660433D01*
G01X1646358Y104055D02*
X1645453D01*
G01X1646398Y104016D02*
X1645413D01*
G01X1646357Y103858D02*
X1640472D01*
G01Y103819D02*
X1646396D01*
G01X1655315Y103681D02*
X1659252D01*
G01X1646396Y102717D02*
X1640472D01*
G01X1646357Y102677D02*
X1640472D01*
G01X1645413Y102520D02*
X1646398D01*
G01X1645453Y102480D02*
X1646358D01*
G01Y100906D02*
X1645453D01*
G01X1646398Y100866D02*
X1645413D01*
G01X1646357Y100709D02*
X1640472D01*
G01Y100669D02*
X1646396D01*
G01Y99567D02*
X1640472D01*
G01X1646357Y99528D02*
X1640472D01*
G01X1645413Y99370D02*
X1646398D01*
G01X1645453Y99331D02*
X1646358D01*
G01Y97756D02*
X1645453D01*
G01X1646398Y97717D02*
X1645413D01*
G01X1646357Y97559D02*
X1640472D01*
G01Y97520D02*
X1646396D01*
G01X1644666Y96417D02*
X1644232D01*
G01X1646396D02*
X1640472D01*
G01X1646357Y96378D02*
X1640472D01*
G01X1645413Y96220D02*
X1646398D01*
G01X1645453Y96181D02*
X1646358D01*
G01Y94606D02*
X1645453D01*
G01X1646398Y94567D02*
X1645413D01*
G01X1646357Y94409D02*
X1640472D01*
G01Y94370D02*
X1646396D01*
G01X1658839Y117204D02*
X1659794Y117205D01*
G01X1659823Y115434D02*
X1658839Y115433D01*
G01Y112204D02*
X1659794Y112205D01*
G01X1659823Y110434D02*
X1658839Y110433D01*
G01Y107204D02*
X1659794Y107205D01*
G01X1659823Y105434D02*
X1658839Y105433D01*
G01X1693996Y262992D02*
G03X1653839I-20078J0D01*
G01D02*
G03X1693996I20078J0D01*
G01D02*
G03I-20079J0D01*
G01X1658268Y202500D02*
G03X1657677Y203091I-591J0D01*
G01X1650984D02*
G03X1650394Y202500I1J-591D01*
G01X1653150Y201319D02*
G03Y199350I0J-985D01*
G01X1655512D02*
G03Y201319I0J984D01*
G01X1651772Y193406D02*
G03X1650591Y192224I0J-1181D01*
G01X1658071D02*
G03X1656890Y193406I-1181J1D01*
G01X1665157Y201909D02*
G03X1663189Y203878I-1968J1D01*
G01X1645472D02*
G03X1643504Y201909I1J-1969D01*
G01X1658268Y196398D02*
Y202500D01*
G01X1650394Y196398D02*
Y202500D01*
G01X1663189Y203878D02*
X1645472D01*
G01X1657677Y203091D02*
X1650984D01*
G01X1655512Y201319D02*
X1653150D01*
G01Y199350D02*
X1655512D01*
G01X1658268Y197972D02*
X1650394D01*
G01Y196398D02*
X1658268D01*
G01X1665157Y193445D02*
X1643504D01*
G01X1651772Y193406D02*
X1656890D01*
G01X1653150Y188720D02*
X1655512D01*
G01X1645416Y537697D02*
X1645411Y537677D01*
G01X1645431Y537711D02*
X1645416Y537697D01*
G01X1645450Y537717D02*
X1645431Y537711D01*
G01X1645416Y540846D02*
X1645411Y540827D01*
G01X1645431Y540861D02*
X1645416Y540846D01*
G01X1645450Y540866D02*
X1645431Y540861D01*
G01X1645416Y543996D02*
X1645411Y543976D01*
G01X1645431Y544010D02*
X1645416Y543996D01*
G01X1645450Y544016D02*
X1645431Y544010D01*
G01X1645416Y547146D02*
X1645411Y547126D01*
G01X1645431Y547160D02*
X1645416Y547146D01*
G01X1645450Y547165D02*
X1645431Y547160D01*
G01X1645416Y550295D02*
X1645411Y550276D01*
G01X1645431Y550309D02*
X1645416Y550295D01*
G01X1645450Y550315D02*
X1645431Y550309D01*
G01X1645416Y553445D02*
X1645411Y553425D01*
G01X1645431Y553459D02*
X1645416Y553445D01*
G01X1645450Y553465D02*
X1645431Y553459D01*
G01X1645416Y556594D02*
X1645411Y556575D01*
G01X1645431Y556609D02*
X1645416Y556594D01*
G01X1645450Y556614D02*
X1645431Y556609D01*
G01X1646391Y536555D02*
X1646396Y536575D01*
G01X1646376Y536541D02*
X1646391Y536555D01*
G01X1646357Y536535D02*
X1646376Y536541D01*
G01X1646391Y539705D02*
X1646396Y539724D01*
G01X1646376Y539690D02*
X1646391Y539705D01*
G01X1646357Y539685D02*
X1646376Y539690D01*
G01X1646391Y542854D02*
X1646396Y542874D01*
G01X1646376Y542840D02*
X1646391Y542854D01*
G01X1646357Y542835D02*
X1646376Y542840D01*
G01X1646391Y546004D02*
X1646396Y546024D01*
G01X1646376Y545989D02*
X1646391Y546004D01*
G01X1646357Y545984D02*
X1646376Y545989D01*
G01X1646391Y549154D02*
X1646396Y549173D01*
G01X1646376Y549139D02*
X1646391Y549154D01*
G01X1646357Y549134D02*
X1646376Y549139D01*
G01X1646391Y552303D02*
X1646396Y552323D01*
G01X1646376Y552289D02*
X1646391Y552303D01*
G01X1646357Y552283D02*
X1646376Y552289D01*
G01X1646391Y555453D02*
X1646396Y555472D01*
G01X1646376Y555438D02*
X1646391Y555453D01*
G01X1646357Y555433D02*
X1646376Y555438D01*
G01X1646397Y552302D02*
X1646398Y552309D01*
G01X1646394Y552295D02*
X1646397Y552302D01*
G01X1646391Y552289D02*
X1646394Y552295D01*
G01X1646386Y552283D02*
X1646391Y552289D01*
G01X1646380Y552278D02*
X1646386Y552283D01*
G01X1646373Y552275D02*
X1646380Y552278D01*
G01X1646366Y552273D02*
X1646373Y552275D01*
G01X1646358Y552272D02*
X1646366Y552273D01*
G01X1646375Y536528D02*
X1646378Y536530D01*
G01X1646372Y536526D02*
X1646375Y536528D01*
G01X1646369Y536526D02*
X1646372D01*
G01X1646365Y536525D02*
X1646369Y536526D01*
G01X1646362Y536524D02*
X1646365Y536525D01*
G01X1646358Y536524D02*
X1646362D01*
G01X1645436Y537724D02*
X1645433Y537722D01*
G01X1645439Y537725D02*
X1645436Y537724D01*
G01X1645443Y537726D02*
X1645439Y537725D01*
G01X1645446Y537727D02*
X1645443Y537726D01*
G01X1645449Y537728D02*
X1645446Y537727D01*
G01X1645453Y537728D02*
X1645449D01*
G01X1646375Y539677D02*
X1646378Y539679D01*
G01X1646372Y539676D02*
X1646375Y539677D01*
G01X1646369Y539675D02*
X1646372Y539676D01*
G01X1646365Y539674D02*
X1646369Y539675D01*
G01X1646362Y539674D02*
X1646365D01*
G01X1646358D02*
X1646362D01*
G01X1645436Y540874D02*
X1645433Y540872D01*
G01X1645439Y540875D02*
X1645436Y540874D01*
G01X1645443Y540876D02*
X1645439Y540875D01*
G01X1645446Y540877D02*
X1645443Y540876D01*
G01X1645449Y540877D02*
X1645446D01*
G01X1645453D02*
X1645449D01*
G01X1646375Y542827D02*
X1646378Y542829D01*
G01X1646372Y542826D02*
X1646375Y542827D01*
G01X1646369Y542825D02*
X1646372Y542826D01*
G01X1646365Y542824D02*
X1646369Y542825D01*
G01X1646362Y542824D02*
X1646365D01*
G01X1646358Y542823D02*
X1646362Y542824D01*
G01X1645436Y544023D02*
X1645433Y544022D01*
G01X1645439Y544024D02*
X1645436Y544023D01*
G01X1645443Y544026D02*
X1645439Y544024D01*
G01X1645446Y544026D02*
X1645443D01*
G01X1645449Y544027D02*
X1645446Y544026D01*
G01X1645453Y544027D02*
X1645449D01*
G01X1646375Y545976D02*
X1646378Y545978D01*
G01X1646372Y545975D02*
X1646375Y545976D01*
G01X1646369Y545974D02*
X1646372Y545975D01*
G01X1646365Y545974D02*
X1646369D01*
G01X1646362Y545973D02*
X1646365Y545974D01*
G01X1646358Y545973D02*
X1646362D01*
G01X1645436Y547173D02*
X1645433Y547171D01*
G01X1645439Y547174D02*
X1645436Y547173D01*
G01X1645443Y547175D02*
X1645439Y547174D01*
G01X1645446Y547176D02*
X1645443Y547175D01*
G01X1645449Y547176D02*
X1645446D01*
G01X1645453D02*
X1645449D01*
G01X1646375Y549126D02*
X1646378Y549128D01*
G01X1646372Y549125D02*
X1646375Y549126D01*
G01X1646369Y549124D02*
X1646372Y549125D01*
G01X1646365Y549123D02*
X1646369Y549124D01*
G01X1646362Y549123D02*
X1646365D01*
G01X1646358Y549122D02*
X1646362Y549123D01*
G01X1645436Y550322D02*
X1645433Y550321D01*
G01X1645439Y550324D02*
X1645436Y550322D01*
G01X1645443Y550325D02*
X1645439Y550324D01*
G01X1645446Y550326D02*
X1645443Y550325D01*
G01X1645449Y550326D02*
X1645446D01*
G01X1645453D02*
X1645449D01*
G01X1645436Y553472D02*
X1645433Y553470D01*
G01X1645439Y553473D02*
X1645436Y553472D01*
G01X1645443Y553474D02*
X1645439Y553473D01*
G01X1645446Y553475D02*
X1645443Y553474D01*
G01X1645449Y553476D02*
X1645446Y553475D01*
G01X1645453Y553476D02*
X1645449D01*
G01X1646375Y555425D02*
X1646378Y555427D01*
G01X1646372Y555424D02*
X1646375Y555425D01*
G01X1646369Y555423D02*
X1646372Y555424D01*
G01X1646365Y555422D02*
X1646369Y555423D01*
G01X1646362Y555422D02*
X1646365D01*
G01X1646358D02*
X1646362D01*
G01X1645436Y556622D02*
X1645433Y556620D01*
G01X1645439Y556623D02*
X1645436Y556622D01*
G01X1645443Y556624D02*
X1645439Y556623D01*
G01X1645446Y556625D02*
X1645443Y556624D01*
G01X1645449Y556625D02*
X1645446D01*
G01X1645453D02*
X1645449D01*
G01X1646388Y537715D02*
X1646392Y537709D01*
G01X1646383Y537719D02*
X1646388Y537715D01*
G01X1646378Y537723D02*
X1646383Y537719D01*
G01X1646372Y537726D02*
X1646378Y537723D01*
G01X1646365Y537727D02*
X1646372Y537726D01*
G01X1646358Y537728D02*
X1646365Y537727D01*
G01X1646388Y540865D02*
X1646392Y540859D01*
G01X1646383Y540869D02*
X1646388Y540865D01*
G01X1646378Y540872D02*
X1646383Y540869D01*
G01X1646372Y540875D02*
X1646378Y540872D01*
G01X1646365Y540877D02*
X1646372Y540875D01*
G01X1646358Y540877D02*
X1646365D01*
G01X1646388Y544014D02*
X1646392Y544009D01*
G01X1646383Y544019D02*
X1646388Y544014D01*
G01X1646378Y544022D02*
X1646383Y544019D01*
G01X1646372Y544025D02*
X1646378Y544022D01*
G01X1646365Y544026D02*
X1646372Y544025D01*
G01X1646358Y544027D02*
X1646365Y544026D01*
G01X1646388Y547164D02*
X1646392Y547158D01*
G01X1646383Y547168D02*
X1646388Y547164D01*
G01X1646378Y547172D02*
X1646383Y547168D01*
G01X1646372Y547174D02*
X1646378Y547172D01*
G01X1646365Y547176D02*
X1646372Y547174D01*
G01X1646358Y547176D02*
X1646365D01*
G01X1646388Y550313D02*
X1646392Y550308D01*
G01X1646383Y550318D02*
X1646388Y550313D01*
G01X1646378Y550321D02*
X1646383Y550318D01*
G01X1646372Y550324D02*
X1646378Y550321D01*
G01X1646365Y550326D02*
X1646372Y550324D01*
G01X1646358Y550326D02*
X1646365D01*
G01X1646388Y553463D02*
X1646392Y553457D01*
G01X1646383Y553467D02*
X1646388Y553463D01*
G01X1646378Y553471D02*
X1646383Y553467D01*
G01X1646372Y553474D02*
X1646378Y553471D01*
G01X1646365Y553475D02*
X1646372Y553474D01*
G01X1646358Y553476D02*
X1646365Y553475D01*
G01X1645414Y536554D02*
X1645413Y536561D01*
G01X1645417Y536547D02*
X1645414Y536554D01*
G01X1645420Y536541D02*
X1645417Y536547D01*
G01X1645425Y536535D02*
X1645420Y536541D01*
G01X1645431Y536530D02*
X1645425Y536535D01*
G01X1645438Y536527D02*
X1645431Y536530D01*
G01X1645445Y536525D02*
X1645438Y536527D01*
G01X1645453Y536524D02*
X1645445Y536525D01*
G01X1645414Y539704D02*
X1645413Y539711D01*
G01X1645417Y539696D02*
X1645414Y539704D01*
G01X1645420Y539690D02*
X1645417Y539696D01*
G01X1645425Y539685D02*
X1645420Y539690D01*
G01X1645431Y539680D02*
X1645425Y539685D01*
G01X1645438Y539676D02*
X1645431Y539680D01*
G01X1645445Y539674D02*
X1645438Y539676D01*
G01X1645453Y539674D02*
X1645445D01*
G01X1645414Y542853D02*
X1645413Y542860D01*
G01X1645417Y542846D02*
X1645414Y542853D01*
G01X1645420Y542840D02*
X1645417Y542846D01*
G01X1645425Y542834D02*
X1645420Y542840D01*
G01X1645431Y542830D02*
X1645425Y542834D01*
G01X1645438Y542826D02*
X1645431Y542830D01*
G01X1645445Y542824D02*
X1645438Y542826D01*
G01X1645453Y542823D02*
X1645445Y542824D01*
G01X1645414Y546003D02*
X1645413Y546010D01*
G01X1645417Y545996D02*
X1645414Y546003D01*
G01X1645420Y545989D02*
X1645417Y545996D01*
G01X1645425Y545984D02*
X1645420Y545989D01*
G01X1645431Y545979D02*
X1645425Y545984D01*
G01X1645438Y545976D02*
X1645431Y545979D01*
G01X1645445Y545974D02*
X1645438Y545976D01*
G01X1645453Y545973D02*
X1645445Y545974D01*
G01X1646388Y556613D02*
X1646392Y556607D01*
G01X1646383Y556617D02*
X1646388Y556613D01*
G01X1646378Y556620D02*
X1646383Y556617D01*
G01X1646372Y556623D02*
X1646378Y556620D01*
G01X1646365Y556625D02*
X1646372Y556623D01*
G01X1646358Y556625D02*
X1646365D01*
G01X1645414Y549152D02*
X1645413Y549159D01*
G01X1645417Y549145D02*
X1645414Y549152D01*
G01X1645420Y549139D02*
X1645417Y549145D01*
G01X1645425Y549133D02*
X1645420Y549139D01*
G01X1645431Y549129D02*
X1645425Y549133D01*
G01X1645438Y549125D02*
X1645431Y549129D01*
G01X1645445Y549123D02*
X1645438Y549125D01*
G01X1645453Y549122D02*
X1645445Y549123D01*
G01X1645414Y552302D02*
X1645413Y552309D01*
G01X1645417Y552295D02*
X1645414Y552302D01*
G01X1645420Y552289D02*
X1645417Y552295D01*
G01X1645425Y552283D02*
X1645420Y552289D01*
G01X1645431Y552278D02*
X1645425Y552283D01*
G01X1645438Y552275D02*
X1645431Y552278D01*
G01X1645445Y552273D02*
X1645438Y552275D01*
G01X1645453Y552272D02*
X1645445Y552273D01*
G01X1645414Y555452D02*
X1645413Y555459D01*
G01X1645417Y555444D02*
X1645414Y555452D01*
G01X1645420Y555438D02*
X1645417Y555444D01*
G01X1645425Y555433D02*
X1645420Y555438D01*
G01X1645431Y555428D02*
X1645425Y555433D01*
G01X1645438Y555424D02*
X1645431Y555428D01*
G01X1645445Y555422D02*
X1645438Y555424D01*
G01X1645453Y555422D02*
X1645445D01*
G01X1646367Y537715D02*
X1646377Y537711D01*
G01X1646357Y537717D02*
X1646367Y537715D01*
G01Y540865D02*
X1646377Y540861D01*
G01X1646357Y540866D02*
X1646367Y540865D01*
G01Y544014D02*
X1646377Y544010D01*
G01X1646357Y544016D02*
X1646367Y544014D01*
G01Y547164D02*
X1646377Y547160D01*
G01X1646357Y547165D02*
X1646367Y547164D01*
G01Y550313D02*
X1646377Y550309D01*
G01X1646357Y550315D02*
X1646367Y550313D01*
G01Y553463D02*
X1646377Y553459D01*
G01X1646357Y553465D02*
X1646367Y553463D01*
G01Y556613D02*
X1646377Y556609D01*
G01X1646357Y556614D02*
X1646367Y556613D01*
G01X1645413Y539715D02*
Y539711D01*
G01X1645415Y539708D02*
X1645413Y539715D01*
G01X1645427Y539693D02*
X1645415Y539708D01*
G01X1645452Y539685D02*
X1645427Y539693D01*
G01X1645413Y542864D02*
Y542860D01*
G01X1645415Y542858D02*
X1645413Y542864D01*
G01X1645426Y542843D02*
X1645415Y542858D01*
G01X1645451Y542835D02*
X1645426Y542843D01*
G01X1645413Y536565D02*
Y536561D01*
G01X1645415Y536559D02*
X1645413Y536565D01*
G01X1645426Y536544D02*
X1645415Y536559D01*
G01X1645451Y536535D02*
X1645426Y536544D01*
G01X1659810Y504755D02*
X1659821Y504740D01*
G01X1659786Y504764D02*
X1659810Y504755D01*
G01Y509755D02*
X1659821Y509740D01*
G01X1659786Y509764D02*
X1659810Y509755D01*
G01Y514755D02*
X1659821Y514740D01*
G01X1659786Y514764D02*
X1659810Y514755D01*
G01Y519755D02*
X1659821Y519740D01*
G01X1659786Y519764D02*
X1659810Y519755D01*
G01Y524755D02*
X1659821Y524740D01*
G01X1659786Y524764D02*
X1659810Y524755D01*
G01Y529755D02*
X1659821Y529740D01*
G01X1659786Y529764D02*
X1659810Y529755D01*
G01X1645413Y549163D02*
Y549159D01*
G01X1645415Y549157D02*
X1645413Y549163D01*
G01X1645426Y549142D02*
X1645415Y549157D01*
G01X1645451Y549134D02*
X1645426Y549142D01*
G01X1645413Y552313D02*
Y552309D01*
G01X1645415Y552307D02*
X1645413Y552313D01*
G01X1645426Y552292D02*
X1645415Y552307D01*
G01X1645451Y552283D02*
X1645426Y552292D01*
G01X1645413Y555463D02*
Y555459D01*
G01X1645415Y555457D02*
X1645413Y555463D01*
G01X1645426Y555441D02*
X1645415Y555457D01*
G01X1645451Y555433D02*
X1645426Y555441D01*
G01X1659810Y534755D02*
X1659821Y534740D01*
G01X1659786Y534764D02*
X1659810Y534755D01*
G01Y559755D02*
X1659821Y559740D01*
G01X1659786Y559764D02*
X1659810Y559755D01*
G01Y564755D02*
X1659821Y564740D01*
G01X1659786Y564764D02*
X1659810Y564755D01*
G01Y569755D02*
X1659821Y569740D01*
G01X1659786Y569764D02*
X1659810Y569755D01*
G01X1645413Y546014D02*
Y546010D01*
G01X1645415Y546008D02*
X1645413Y546014D01*
G01X1645425Y545994D02*
X1645415Y546008D01*
G01X1645448Y545984D02*
X1645425Y545994D01*
G01X1646366Y544015D02*
X1646357Y544016D01*
G01X1646375Y544011D02*
X1646366Y544015D01*
G01X1646383Y544006D02*
X1646375Y544011D01*
G01X1646366Y537715D02*
X1646357Y537717D01*
G01X1646375Y537712D02*
X1646366Y537715D01*
G01X1646383Y537707D02*
X1646375Y537712D01*
G01X1646366Y540865D02*
X1646357Y540866D01*
G01X1646375Y540862D02*
X1646366Y540865D01*
G01X1646383Y540856D02*
X1646375Y540862D01*
G01X1646366Y547164D02*
X1646357Y547165D01*
G01X1646375Y547161D02*
X1646366Y547164D01*
G01X1646383Y547156D02*
X1646375Y547161D01*
G01X1646366Y550314D02*
X1646357Y550315D01*
G01X1646375Y550311D02*
X1646366Y550314D01*
G01X1646383Y550305D02*
X1646375Y550311D01*
G01X1646366Y553463D02*
X1646357Y553465D01*
G01X1646375Y553460D02*
X1646366Y553463D01*
G01X1646383Y553455D02*
X1646375Y553460D01*
G01X1646366Y556613D02*
X1646357Y556614D01*
G01X1646375Y556610D02*
X1646366Y556613D01*
G01X1646383Y556604D02*
X1646375Y556610D01*
G01X1645452Y536530D02*
X1645453Y536524D01*
G01X1645452Y536534D02*
Y536530D01*
G01X1645450Y536535D02*
X1645452Y536534D01*
G01Y539680D02*
X1645453Y539674D01*
G01X1645452Y539684D02*
Y539680D01*
G01X1645450Y539685D02*
X1645452Y539684D01*
G01Y542830D02*
X1645453Y542823D01*
G01X1645452Y542833D02*
Y542830D01*
G01X1645450Y542835D02*
X1645452Y542833D01*
G01Y545979D02*
X1645453Y545973D01*
G01X1645452Y545983D02*
Y545979D01*
G01X1645450Y545984D02*
X1645452Y545983D01*
G01Y549129D02*
X1645453Y549122D01*
G01X1645452Y549133D02*
Y549129D01*
G01X1645450Y549134D02*
X1645452Y549133D01*
G01Y552278D02*
X1645453Y552272D01*
G01X1645452Y552282D02*
Y552278D01*
G01X1645450Y552283D02*
X1645452Y552282D01*
G01Y555428D02*
X1645453Y555422D01*
G01X1645452Y555432D02*
Y555428D01*
G01X1645450Y555433D02*
X1645452Y555432D01*
G01X1659823Y504731D02*
Y504738D01*
G01X1659824Y504726D02*
X1659823Y504731D01*
G01X1659825Y504724D02*
X1659824Y504726D01*
G01X1659823Y509731D02*
Y509738D01*
G01X1659824Y509726D02*
X1659823Y509731D01*
G01X1659825Y509724D02*
X1659824Y509726D01*
G01X1659823Y514731D02*
Y514738D01*
G01X1659824Y514726D02*
X1659823Y514731D01*
G01X1659825Y514724D02*
X1659824Y514726D01*
G01X1659823Y519731D02*
Y519738D01*
G01X1659824Y519726D02*
X1659823Y519731D01*
G01X1659825Y519724D02*
X1659824Y519726D01*
G01X1659823Y524731D02*
Y524738D01*
G01X1659824Y524726D02*
X1659823Y524731D01*
G01X1659825Y524724D02*
X1659824Y524726D01*
G01X1659823Y529731D02*
Y529738D01*
G01X1659824Y529726D02*
X1659823Y529731D01*
G01X1659825Y529724D02*
X1659824Y529726D01*
G01X1659823Y534731D02*
Y534738D01*
G01X1659824Y534726D02*
X1659823Y534731D01*
G01X1659825Y534724D02*
X1659824Y534726D01*
G01X1646369Y555435D02*
X1646357Y555433D01*
G01X1646379Y555440D02*
X1646369Y555435D01*
G01Y552285D02*
X1646357Y552283D01*
G01X1646379Y552290D02*
X1646369Y552285D01*
G01Y549136D02*
X1646357Y549134D01*
G01X1646379Y549141D02*
X1646369Y549136D01*
G01Y545986D02*
X1646357Y545984D01*
G01X1646379Y545991D02*
X1646369Y545986D01*
G01Y542837D02*
X1646357Y542835D01*
G01X1646379Y542841D02*
X1646369Y542837D01*
G01Y539687D02*
X1646357Y539685D01*
G01X1646379Y539692D02*
X1646369Y539687D01*
G01X1659823Y559731D02*
Y559738D01*
G01X1659824Y559726D02*
X1659823Y559731D01*
G01X1659825Y559724D02*
X1659824Y559726D01*
G01X1659823Y564731D02*
Y564738D01*
G01X1659824Y564726D02*
X1659823Y564731D01*
G01X1659825Y564724D02*
X1659824Y564726D01*
G01X1659823Y569731D02*
Y569738D01*
G01X1659824Y569726D02*
X1659823Y569731D01*
G01X1659825Y569724D02*
X1659824Y569726D01*
G01X1645436Y539687D02*
X1645450Y539685D01*
G01X1645425Y539694D02*
X1645436Y539687D01*
G01X1645413Y539713D02*
X1645425Y539694D01*
G01X1645436Y549136D02*
X1645450Y549134D01*
G01X1645424Y549144D02*
X1645436Y549136D01*
G01X1645413Y549162D02*
X1645424Y549144D01*
G01X1645436Y542837D02*
X1645450Y542835D01*
G01X1645424Y542845D02*
X1645436Y542837D01*
G01X1645412Y542865D02*
X1645424Y542845D01*
G01X1645436Y552286D02*
X1645450Y552283D01*
G01X1645424Y552294D02*
X1645436Y552286D01*
G01X1645412Y552314D02*
X1645424Y552294D01*
G01X1646398Y536569D02*
Y536561D01*
G01X1646397Y536573D02*
X1646398Y536569D01*
G01X1646396Y536575D02*
X1646397Y536573D01*
G01X1646398Y539719D02*
Y539711D01*
G01X1646397Y539723D02*
X1646398Y539719D01*
G01X1646396Y539724D02*
X1646397Y539723D01*
G01X1646398Y542868D02*
Y542860D01*
G01X1646397Y542872D02*
X1646398Y542868D01*
G01X1646396Y542874D02*
X1646397Y542872D01*
G01X1646398Y546018D02*
Y546010D01*
G01X1646397Y546022D02*
X1646398Y546018D01*
G01X1646396Y546024D02*
X1646397Y546022D01*
G01X1646398Y549167D02*
Y549159D01*
G01X1646397Y549172D02*
X1646398Y549167D01*
G01X1646396Y549173D02*
X1646397Y549172D01*
G01X1646398Y552317D02*
Y552309D01*
G01X1646397Y552321D02*
X1646398Y552317D01*
G01X1646396Y552323D02*
X1646397Y552321D01*
G01X1646398Y555467D02*
Y555459D01*
G01X1646397Y555471D02*
X1646398Y555467D01*
G01X1646396Y555472D02*
X1646397Y555471D01*
G01X1645436Y555436D02*
X1645450Y555433D01*
G01X1645423Y555444D02*
X1645436Y555436D01*
G01X1645412Y555464D02*
X1645423Y555444D01*
G01X1645435Y536538D02*
X1645450Y536535D01*
G01X1645422Y536547D02*
X1645435Y536538D01*
G01X1645412Y536567D02*
X1645422Y536547D01*
G01X1646397Y537697D02*
X1646398Y537691D01*
G01X1646395Y537704D02*
X1646397Y537697D01*
G01X1646392Y537709D02*
X1646395Y537704D01*
G01X1646397Y540847D02*
X1646398Y540840D01*
G01X1646395Y540853D02*
X1646397Y540847D01*
G01X1646392Y540859D02*
X1646395Y540853D01*
G01X1645452Y556619D02*
Y556625D01*
G01Y556615D02*
Y556619D01*
G01X1645450Y556614D02*
X1645452Y556615D01*
G01Y553469D02*
Y553476D01*
G01Y553466D02*
Y553469D01*
G01X1645450Y553465D02*
X1645452Y553466D01*
G01Y550320D02*
Y550326D01*
G01Y550316D02*
Y550320D01*
G01X1645450Y550315D02*
X1645452Y550316D01*
G01Y547170D02*
Y547176D01*
G01Y547167D02*
Y547170D01*
G01X1645450Y547165D02*
X1645452Y547167D01*
G01Y544020D02*
Y544027D01*
G01Y544017D02*
Y544020D01*
G01X1645450Y544016D02*
X1645452Y544017D01*
G01Y540871D02*
Y540877D01*
G01Y540867D02*
Y540871D01*
G01X1645450Y540866D02*
X1645452Y540867D01*
G01Y537721D02*
Y537728D01*
G01Y537718D02*
Y537721D01*
G01X1645450Y537717D02*
X1645452Y537718D01*
G01X1645414Y556594D02*
X1645413Y556588D01*
G01X1645416Y556601D02*
X1645414Y556594D01*
G01X1645419Y556607D02*
X1645416Y556601D01*
G01X1645422Y556612D02*
X1645419Y556607D01*
G01X1645427Y556617D02*
X1645422Y556612D01*
G01X1645433Y556620D02*
X1645427Y556617D01*
G01X1645414Y553445D02*
X1645413Y553439D01*
G01X1645416Y553451D02*
X1645414Y553445D01*
G01X1645419Y553457D02*
X1645416Y553451D01*
G01X1645422Y553462D02*
X1645419Y553457D01*
G01X1645427Y553467D02*
X1645422Y553462D01*
G01X1645433Y553470D02*
X1645427Y553467D01*
G01X1645414Y550295D02*
X1645413Y550289D01*
G01X1645416Y550302D02*
X1645414Y550295D01*
G01X1645419Y550307D02*
X1645416Y550302D01*
G01X1645422Y550313D02*
X1645419Y550307D01*
G01X1645427Y550317D02*
X1645422Y550313D01*
G01X1645433Y550321D02*
X1645427Y550317D01*
G01X1645414Y547146D02*
X1645413Y547139D01*
G01X1645416Y547152D02*
X1645414Y547146D01*
G01X1645419Y547158D02*
X1645416Y547152D01*
G01X1645422Y547163D02*
X1645419Y547158D01*
G01X1645427Y547168D02*
X1645422Y547163D01*
G01X1645433Y547171D02*
X1645427Y547168D01*
G01X1645414Y543996D02*
X1645413Y543990D01*
G01X1645416Y544002D02*
X1645414Y543996D01*
G01X1645419Y544008D02*
X1645416Y544002D01*
G01X1645422Y544013D02*
X1645419Y544008D01*
G01X1645427Y544018D02*
X1645422Y544013D01*
G01X1645433Y544022D02*
X1645427Y544018D01*
G01X1645414Y540846D02*
X1645413Y540840D01*
G01X1645416Y540853D02*
X1645414Y540846D01*
G01X1645419Y540859D02*
X1645416Y540853D01*
G01X1645422Y540864D02*
X1645419Y540859D01*
G01X1645427Y540869D02*
X1645422Y540864D01*
G01X1645433Y540872D02*
X1645427Y540869D01*
G01X1645414Y537697D02*
X1645413Y537691D01*
G01X1645416Y537703D02*
X1645414Y537697D01*
G01X1645419Y537709D02*
X1645416Y537703D01*
G01X1645422Y537714D02*
X1645419Y537709D01*
G01X1645427Y537719D02*
X1645422Y537714D01*
G01X1645433Y537722D02*
X1645427Y537719D01*
G01X1646369Y536537D02*
X1646357Y536535D01*
G01X1646379Y536542D02*
X1646369Y536537D01*
G01X1646397Y543996D02*
X1646398Y543990D01*
G01X1646395Y544003D02*
X1646397Y543996D01*
G01X1646392Y544009D02*
X1646395Y544003D01*
G01X1646397Y547146D02*
X1646398Y547139D01*
G01X1646395Y547152D02*
X1646397Y547146D01*
G01X1646392Y547158D02*
X1646395Y547152D01*
G01X1646397Y550296D02*
X1646398Y550289D01*
G01X1646395Y550302D02*
X1646397Y550296D01*
G01X1646392Y550308D02*
X1646395Y550302D01*
G01X1646397Y553445D02*
X1646398Y553439D01*
G01X1646395Y553452D02*
X1646397Y553445D01*
G01X1646392Y553457D02*
X1646395Y553452D01*
G01X1646397Y556595D02*
X1646398Y556588D01*
G01X1646395Y556601D02*
X1646397Y556595D01*
G01X1646392Y556607D02*
X1646395Y556601D01*
G01X1646359Y536530D02*
Y536524D01*
G01X1646357Y536534D02*
X1646359Y536530D01*
G01X1646357Y536535D02*
Y536534D01*
G01X1646359Y539680D02*
Y539674D01*
G01X1646357Y539683D02*
X1646359Y539680D01*
G01X1646357Y539685D02*
Y539683D01*
G01X1646359Y542830D02*
Y542823D01*
G01X1646357Y542833D02*
X1646359Y542830D01*
G01X1646357Y542835D02*
Y542833D01*
G01X1646359Y545979D02*
Y545973D01*
G01X1646357Y545983D02*
X1646359Y545979D01*
G01X1646357Y545984D02*
Y545983D01*
G01X1646359Y549129D02*
Y549122D01*
G01X1646357Y549132D02*
X1646359Y549129D01*
G01X1646357Y549134D02*
Y549132D01*
G01X1646359Y555428D02*
Y555422D01*
G01X1646357Y555431D02*
X1646359Y555428D01*
G01X1646357Y555433D02*
Y555431D01*
G01X1658839Y504771D02*
Y504780D01*
G01Y504765D02*
Y504771D01*
G01X1658840Y504764D02*
X1658839Y504765D01*
G01Y509771D02*
Y509780D01*
G01Y509765D02*
Y509771D01*
G01X1658840Y509764D02*
X1658839Y509765D01*
G01Y514771D02*
Y514780D01*
G01Y514765D02*
Y514771D01*
G01X1658840Y514764D02*
X1658839Y514765D01*
G01Y519771D02*
Y519780D01*
G01Y519765D02*
Y519771D01*
G01X1658840Y519764D02*
X1658839Y519765D01*
G01Y524771D02*
Y524780D01*
G01Y524765D02*
Y524771D01*
G01X1658840Y524764D02*
X1658839Y524765D01*
G01Y529771D02*
Y529780D01*
G01Y529765D02*
Y529771D01*
G01X1658840Y529764D02*
X1658839Y529765D01*
G01Y534771D02*
Y534780D01*
G01Y534765D02*
Y534771D01*
G01X1658840Y534764D02*
X1658839Y534765D01*
G01Y559771D02*
Y559780D01*
G01Y559765D02*
Y559771D01*
G01X1658840Y559764D02*
X1658839Y559765D01*
G01Y564771D02*
Y564780D01*
G01Y564765D02*
Y564771D01*
G01X1658840Y564764D02*
X1658839Y564765D01*
G01Y569771D02*
Y569780D01*
G01Y569765D02*
Y569771D01*
G01X1658840Y569764D02*
X1658839Y569765D01*
G01X1659815Y504907D02*
X1659823Y504881D01*
G01X1659805Y504934D02*
X1659815Y504907D01*
G01X1659794Y504961D02*
X1659805Y504934D01*
G01X1659815Y509907D02*
X1659823Y509881D01*
G01X1659805Y509934D02*
X1659815Y509907D01*
G01X1659794Y509961D02*
X1659805Y509934D01*
G01X1659815Y514907D02*
X1659823Y514881D01*
G01X1659805Y514934D02*
X1659815Y514907D01*
G01X1659794Y514961D02*
X1659805Y514934D01*
G01X1659815Y519907D02*
X1659823Y519881D01*
G01X1659805Y519934D02*
X1659815Y519907D01*
G01X1659794Y519961D02*
X1659805Y519934D01*
G01X1659815Y524907D02*
X1659823Y524881D01*
G01X1659805Y524934D02*
X1659815Y524907D01*
G01X1659794Y524961D02*
X1659805Y524934D01*
G01X1659815Y529907D02*
X1659823Y529881D01*
G01X1659805Y529934D02*
X1659815Y529907D01*
G01X1659794Y529961D02*
X1659805Y529934D01*
G01X1659815Y534907D02*
X1659823Y534881D01*
G01X1659805Y534934D02*
X1659815Y534907D01*
G01X1659794Y534961D02*
X1659805Y534934D01*
G01X1659815Y559907D02*
X1659823Y559881D01*
G01X1659805Y559934D02*
X1659815Y559907D01*
G01X1659794Y559961D02*
X1659805Y559934D01*
G01X1659815Y564907D02*
X1659823Y564881D01*
G01X1659805Y564934D02*
X1659815Y564907D01*
G01X1659794Y564961D02*
X1659805Y564934D01*
G01X1659815Y569907D02*
X1659823Y569881D01*
G01X1659805Y569934D02*
X1659815Y569907D01*
G01X1659794Y569961D02*
X1659805Y569934D01*
G01X1645431Y545989D02*
X1645450Y545984D01*
G01X1645418Y546002D02*
X1645431Y545989D01*
G01X1645411Y546019D02*
X1645418Y546002D01*
G01X1659823Y568378D02*
Y568369D01*
G01X1659824Y568384D02*
X1659823Y568378D01*
G01X1659826Y568386D02*
X1659824Y568384D01*
G01X1659823Y563378D02*
Y563369D01*
G01X1659824Y563384D02*
X1659823Y563378D01*
G01X1659826Y563386D02*
X1659824Y563384D01*
G01X1659823Y558378D02*
Y558369D01*
G01X1659824Y558384D02*
X1659823Y558378D01*
G01X1659826Y558386D02*
X1659824Y558384D01*
G01X1645413Y556581D02*
Y556588D01*
G01X1645412Y556576D02*
X1645413Y556581D01*
G01X1645411Y556575D02*
X1645412Y556576D01*
G01X1645413Y553431D02*
Y553439D01*
G01X1645412Y553427D02*
X1645413Y553431D01*
G01X1645411Y553425D02*
X1645412Y553427D01*
G01X1645413Y550281D02*
Y550289D01*
G01X1645412Y550277D02*
X1645413Y550281D01*
G01X1645411Y550276D02*
X1645412Y550277D01*
G01X1645413Y547132D02*
Y547139D01*
G01X1645412Y547128D02*
X1645413Y547132D01*
G01X1645411Y547126D02*
X1645412Y547128D01*
G01X1645413Y543982D02*
Y543990D01*
G01X1645412Y543978D02*
X1645413Y543982D01*
G01X1645411Y543976D02*
X1645412Y543978D01*
G01X1645413Y540833D02*
Y540840D01*
G01X1645412Y540828D02*
X1645413Y540833D01*
G01X1645411Y540827D02*
X1645412Y540828D01*
G01X1645413Y537683D02*
Y537691D01*
G01X1645412Y537679D02*
X1645413Y537683D01*
G01X1645411Y537677D02*
X1645412Y537679D01*
G01X1646395Y555446D02*
X1646398Y555459D01*
G01X1646389Y555435D02*
X1646395Y555446D01*
G01X1646378Y555427D02*
X1646389Y555435D01*
G01X1646395Y549147D02*
X1646398Y549159D01*
G01X1646389Y549136D02*
X1646395Y549147D01*
G01X1646378Y549128D02*
X1646389Y549136D01*
G01X1646395Y545998D02*
X1646398Y546010D01*
G01X1646389Y545986D02*
X1646395Y545998D01*
G01X1646378Y545978D02*
X1646389Y545986D01*
G01X1646395Y542848D02*
X1646398Y542860D01*
G01X1646389Y542837D02*
X1646395Y542848D01*
G01X1646378Y542829D02*
X1646389Y542837D01*
G01X1646395Y539698D02*
X1646398Y539711D01*
G01X1646389Y539687D02*
X1646395Y539698D01*
G01X1646378Y539679D02*
X1646389Y539687D01*
G01X1646395Y536549D02*
X1646398Y536561D01*
G01X1646389Y536537D02*
X1646395Y536549D01*
G01X1646378Y536530D02*
X1646389Y536537D01*
G01X1659806Y504759D02*
X1659786Y504764D01*
G01X1659820Y504744D02*
X1659806Y504759D01*
G01X1659825Y504724D02*
X1659820Y504744D01*
G01X1659806Y509759D02*
X1659786Y509764D01*
G01X1659820Y509744D02*
X1659806Y509759D01*
G01X1659825Y509724D02*
X1659820Y509744D01*
G01X1659806Y514759D02*
X1659786Y514764D01*
G01X1659820Y514744D02*
X1659806Y514759D01*
G01X1659825Y514724D02*
X1659820Y514744D01*
G01X1659806Y519759D02*
X1659786Y519764D01*
G01X1659820Y519744D02*
X1659806Y519759D01*
G01X1659825Y519724D02*
X1659820Y519744D01*
G01X1659806Y524759D02*
X1659786Y524764D01*
G01X1659820Y524744D02*
X1659806Y524759D01*
G01X1659825Y524724D02*
X1659820Y524744D01*
G01X1659806Y529759D02*
X1659786Y529764D01*
G01X1659820Y529744D02*
X1659806Y529759D01*
G01X1659825Y529724D02*
X1659820Y529744D01*
G01X1659806Y534759D02*
X1659786Y534764D01*
G01X1659820Y534744D02*
X1659806Y534759D01*
G01X1659825Y534724D02*
X1659820Y534744D01*
G01X1659806Y559759D02*
X1659786Y559764D01*
G01X1659820Y559744D02*
X1659806Y559759D01*
G01X1659825Y559724D02*
X1659820Y559744D01*
G01X1659806Y564759D02*
X1659786Y564764D01*
G01X1659820Y564744D02*
X1659806Y564759D01*
G01X1659825Y564724D02*
X1659820Y564744D01*
G01X1659806Y569759D02*
X1659786Y569764D01*
G01X1659820Y569744D02*
X1659806Y569759D01*
G01X1659825Y569724D02*
X1659820Y569744D01*
G01X1646390Y543998D02*
X1646383Y544006D01*
G01X1646395Y543987D02*
X1646390Y543998D01*
G01X1646396Y543976D02*
X1646395Y543987D01*
G01X1646390Y537698D02*
X1646383Y537707D01*
G01X1646395Y537688D02*
X1646390Y537698D01*
G01X1646396Y537677D02*
X1646395Y537688D01*
G01X1646390Y540848D02*
X1646383Y540856D01*
G01X1646395Y540838D02*
X1646390Y540848D01*
G01X1646396Y540827D02*
X1646395Y540838D01*
G01X1646390Y547147D02*
X1646383Y547156D01*
G01X1646395Y547137D02*
X1646390Y547147D01*
G01X1646396Y547126D02*
X1646395Y547137D01*
G01X1646390Y550297D02*
X1646383Y550305D01*
G01X1646395Y550287D02*
X1646390Y550297D01*
G01X1646396Y550276D02*
X1646395Y550287D01*
G01X1646390Y553446D02*
X1646383Y553455D01*
G01X1646395Y553436D02*
X1646390Y553446D01*
G01X1646396Y553425D02*
X1646395Y553436D01*
G01X1646390Y556596D02*
X1646383Y556604D01*
G01X1646395Y556586D02*
X1646390Y556596D01*
G01X1646396Y556575D02*
X1646395Y556586D01*
G01X1659790Y504862D02*
X1659794Y504961D01*
G01X1659784Y504790D02*
X1659790Y504862D01*
G01X1659786Y504764D02*
X1659784Y504790D01*
G01X1659790Y509862D02*
X1659794Y509961D01*
G01X1659784Y509790D02*
X1659790Y509862D01*
G01X1659786Y509764D02*
X1659784Y509790D01*
G01X1659790Y514862D02*
X1659794Y514961D01*
G01X1659784Y514790D02*
X1659790Y514862D01*
G01X1659786Y514764D02*
X1659784Y514790D01*
G01X1659790Y519862D02*
X1659794Y519961D01*
G01X1659784Y519790D02*
X1659790Y519862D01*
G01X1659786Y519764D02*
X1659784Y519790D01*
G01X1659790Y524862D02*
X1659794Y524961D01*
G01X1659784Y524790D02*
X1659790Y524862D01*
G01X1659786Y524764D02*
X1659784Y524790D01*
G01X1659790Y529862D02*
X1659794Y529961D01*
G01X1659784Y529790D02*
X1659790Y529862D01*
G01X1659786Y529764D02*
X1659784Y529790D01*
G01X1659790Y534862D02*
X1659794Y534961D01*
G01X1659784Y534790D02*
X1659790Y534862D01*
G01X1659786Y534764D02*
X1659784Y534790D01*
G01X1659790Y559862D02*
X1659794Y559961D01*
G01X1659784Y559790D02*
X1659790Y559862D01*
G01X1659786Y559764D02*
X1659784Y559790D01*
G01X1659790Y564862D02*
X1659794Y564961D01*
G01X1659784Y564790D02*
X1659790Y564862D01*
G01X1659786Y564764D02*
X1659784Y564790D01*
G01X1659790Y569862D02*
X1659794Y569961D01*
G01X1659784Y569790D02*
X1659790Y569862D01*
G01X1659786Y569764D02*
X1659784Y569790D01*
G01X1645413Y549167D02*
Y549160D01*
G01X1645412Y549172D02*
X1645413Y549167D01*
G01Y549162D02*
X1645412Y549172D01*
G01X1645454Y556798D02*
X1645453Y556811D01*
G01X1645450Y556785D02*
X1645454Y556798D01*
G01X1645450Y556772D02*
Y556785D01*
G01X1645454Y553649D02*
X1645453Y553661D01*
G01X1645450Y553636D02*
X1645454Y553649D01*
G01X1645450Y553622D02*
Y553636D01*
G01X1645454Y550499D02*
X1645453Y550512D01*
G01X1645450Y550486D02*
X1645454Y550499D01*
G01X1645450Y550472D02*
Y550486D01*
G01X1645454Y547350D02*
X1645453Y547362D01*
G01X1645450Y547337D02*
X1645454Y547350D01*
G01X1645450Y547323D02*
Y547337D01*
G01X1645454Y544200D02*
X1645453Y544213D01*
G01X1645450Y544187D02*
X1645454Y544200D01*
G01X1645450Y544173D02*
Y544187D01*
G01X1645454Y541050D02*
X1645453Y541063D01*
G01X1645450Y541037D02*
X1645454Y541050D01*
G01X1645450Y541024D02*
Y541037D01*
G01X1645454Y537901D02*
X1645453Y537913D01*
G01X1645450Y537888D02*
X1645454Y537901D01*
G01X1645450Y537874D02*
Y537888D01*
G01X1658839Y568384D02*
X1658840Y568386D01*
G01X1658839Y568378D02*
Y568384D01*
G01Y568370D02*
Y568378D01*
G01Y563384D02*
X1658840Y563386D01*
G01X1658839Y563378D02*
Y563384D01*
G01Y563370D02*
Y563378D01*
G01Y558384D02*
X1658840Y558386D01*
G01X1658839Y558378D02*
Y558384D01*
G01Y558370D02*
Y558378D01*
G01Y533384D02*
X1658840Y533386D01*
G01X1658839Y533378D02*
Y533384D01*
G01Y533370D02*
Y533378D01*
G01Y528384D02*
X1658840Y528386D01*
G01X1658839Y528378D02*
Y528384D01*
G01Y528370D02*
Y528378D01*
G01Y523384D02*
X1658840Y523386D01*
G01X1658839Y523378D02*
Y523384D01*
G01Y523370D02*
Y523378D01*
G01Y518384D02*
X1658840Y518386D01*
G01X1658839Y518378D02*
Y518384D01*
G01Y518370D02*
Y518378D01*
G01Y513384D02*
X1658840Y513386D01*
G01X1658839Y513378D02*
Y513384D01*
G01Y513370D02*
Y513378D01*
G01Y508384D02*
X1658840Y508386D01*
G01X1658839Y508378D02*
Y508384D01*
G01Y508370D02*
Y508378D01*
G01Y503384D02*
X1658840Y503386D01*
G01X1658839Y503378D02*
Y503384D01*
G01Y503370D02*
Y503378D01*
G01X1645413Y555467D02*
Y555459D01*
G01X1645412Y555471D02*
X1645413Y555467D01*
G01X1645412Y555463D02*
Y555471D01*
G01X1645450Y555261D02*
X1645449Y555275D01*
G01X1645454Y555249D02*
X1645450Y555261D01*
G01X1645453Y555236D02*
X1645454Y555249D01*
G01X1645450Y552112D02*
X1645449Y552126D01*
G01X1645454Y552099D02*
X1645450Y552112D01*
G01X1645453Y552087D02*
X1645454Y552099D01*
G01X1645450Y548962D02*
X1645449Y548976D01*
G01X1645454Y548950D02*
X1645450Y548962D01*
G01X1645453Y548937D02*
X1645454Y548950D01*
G01X1645450Y545813D02*
X1645449Y545826D01*
G01X1645454Y545800D02*
X1645450Y545813D01*
G01X1645453Y545787D02*
X1645454Y545800D01*
G01X1645450Y542663D02*
X1645449Y542677D01*
G01X1645454Y542650D02*
X1645450Y542663D01*
G01X1645453Y542638D02*
X1645454Y542650D01*
G01X1645450Y539513D02*
X1645449Y539527D01*
G01X1645454Y539501D02*
X1645450Y539513D01*
G01X1645453Y539488D02*
X1645454Y539501D01*
G01X1645450Y536364D02*
X1645449Y536378D01*
G01X1645454Y536351D02*
X1645450Y536364D01*
G01X1645453Y536339D02*
X1645454Y536351D01*
G01X1646361Y556785D02*
X1646362Y556772D01*
G01X1646357Y556798D02*
X1646361Y556785D01*
G01X1646358Y556811D02*
X1646357Y556798D01*
G01X1646361Y553636D02*
X1646362Y553622D01*
G01X1646357Y553649D02*
X1646361Y553636D01*
G01X1646358Y553661D02*
X1646357Y553649D01*
G01X1646361Y550486D02*
X1646362Y550472D01*
G01X1646357Y550499D02*
X1646361Y550486D01*
G01X1646358Y550512D02*
X1646357Y550499D01*
G01X1646361Y547337D02*
X1646362Y547323D01*
G01X1646357Y547350D02*
X1646361Y547337D01*
G01X1646358Y547362D02*
X1646357Y547350D01*
G01X1646361Y544187D02*
X1646362Y544173D01*
G01X1646357Y544200D02*
X1646361Y544187D01*
G01X1646358Y544213D02*
X1646357Y544200D01*
G01X1646361Y541037D02*
X1646362Y541024D01*
G01X1646357Y541050D02*
X1646361Y541037D01*
G01X1646358Y541063D02*
X1646357Y541050D01*
G01X1646361Y537888D02*
X1646362Y537874D01*
G01X1646357Y537901D02*
X1646361Y537888D01*
G01X1646358Y537913D02*
X1646357Y537901D01*
G01X1645413Y542868D02*
Y542861D01*
G01X1645412Y542872D02*
X1645413Y542868D01*
G01X1645412Y542865D02*
Y542872D01*
G01X1645413Y552317D02*
Y552309D01*
G01X1645412Y552321D02*
X1645413Y552317D01*
G01X1645412Y552314D02*
Y552321D01*
G01X1646357Y555249D02*
X1646358Y555236D01*
G01X1646360Y555261D02*
X1646357Y555249D01*
G01X1646361Y555275D02*
X1646360Y555261D01*
G01X1646357Y552099D02*
X1646358Y552087D01*
G01X1646360Y552112D02*
X1646357Y552099D01*
G01X1646361Y552126D02*
X1646360Y552112D01*
G01X1646357Y548950D02*
X1646358Y548937D01*
G01X1646360Y548962D02*
X1646357Y548950D01*
G01X1646361Y548976D02*
X1646360Y548962D01*
G01X1646357Y545800D02*
X1646358Y545787D01*
G01X1646360Y545813D02*
X1646357Y545800D01*
G01X1646361Y545826D02*
X1646360Y545813D01*
G01X1646357Y542650D02*
X1646358Y542638D01*
G01X1646360Y542663D02*
X1646357Y542650D01*
G01X1646361Y542677D02*
X1646360Y542663D01*
G01X1646357Y539501D02*
X1646358Y539488D01*
G01X1646360Y539513D02*
X1646357Y539501D01*
G01X1646361Y539527D02*
X1646360Y539513D01*
G01X1646357Y536351D02*
X1646358Y536339D01*
G01X1646360Y536364D02*
X1646357Y536351D01*
G01X1646361Y536378D02*
X1646360Y536364D01*
G01X1645413Y536569D02*
Y536561D01*
G01X1645412Y536573D02*
X1645413Y536569D01*
G01X1645412Y536567D02*
Y536573D01*
G01X1645426Y556606D02*
X1645450Y556614D01*
G01X1645415Y556591D02*
X1645426Y556606D01*
G01X1645413Y556584D02*
X1645415Y556591D01*
G01X1645426Y553456D02*
X1645450Y553465D01*
G01X1645415Y553441D02*
X1645426Y553456D01*
G01X1645413Y553435D02*
X1645415Y553441D01*
G01X1645426Y550306D02*
X1645450Y550315D01*
G01X1645415Y550292D02*
X1645426Y550306D01*
G01X1645413Y550285D02*
X1645415Y550292D01*
G01X1645426Y547157D02*
X1645450Y547165D01*
G01X1645415Y547142D02*
X1645426Y547157D01*
G01X1645413Y547135D02*
X1645415Y547142D01*
G01X1645426Y544007D02*
X1645450Y544016D01*
G01X1645415Y543993D02*
X1645426Y544007D01*
G01X1645413Y543986D02*
X1645415Y543993D01*
G01X1645426Y540857D02*
X1645450Y540866D01*
G01X1645415Y540843D02*
X1645426Y540857D01*
G01X1645413Y540836D02*
X1645415Y540843D01*
G01X1645426Y537708D02*
X1645450Y537717D01*
G01X1645415Y537693D02*
X1645426Y537708D01*
G01X1645413Y537687D02*
X1645415Y537693D01*
G01X1646398Y556581D02*
Y556588D01*
G01X1646397Y556576D02*
X1646398Y556581D01*
G01X1646396Y556575D02*
X1646397Y556576D01*
G01X1646398Y553431D02*
Y553439D01*
G01X1646397Y553427D02*
X1646398Y553431D01*
G01X1646396Y553425D02*
X1646397Y553427D01*
G01X1646398Y550282D02*
Y550289D01*
G01X1646397Y550277D02*
X1646398Y550282D01*
G01X1646396Y550276D02*
X1646397Y550277D01*
G01X1646398Y547132D02*
Y547139D01*
G01X1646397Y547128D02*
X1646398Y547132D01*
G01X1646396Y547126D02*
X1646397Y547128D01*
G01X1646398Y543983D02*
Y543990D01*
G01X1646397Y543978D02*
X1646398Y543983D01*
G01X1646396Y543976D02*
X1646397Y543978D01*
G01X1646398Y540833D02*
Y540840D01*
G01X1646397Y540828D02*
X1646398Y540833D01*
G01X1646396Y540827D02*
X1646397Y540828D01*
G01X1646398Y537683D02*
Y537691D01*
G01X1646397Y537679D02*
X1646398Y537683D01*
G01X1646396Y537677D02*
X1646397Y537679D01*
G01X1645413Y546018D02*
Y546010D01*
G01X1645412Y546022D02*
X1645413Y546018D01*
G01X1645411Y546019D02*
X1645412Y546022D01*
G01X1645413Y539719D02*
Y539711D01*
G01X1645412Y539723D02*
X1645413Y539719D01*
G01X1645411Y539721D02*
X1645412Y539723D01*
G01X1646358Y556619D02*
Y556625D01*
G01X1646357Y556615D02*
X1646358Y556619D01*
G01X1646357Y556614D02*
Y556615D01*
G01X1646358Y553470D02*
Y553476D01*
G01X1646357Y553466D02*
X1646358Y553470D01*
G01X1646357Y553465D02*
Y553466D01*
G01X1646358Y550320D02*
Y550326D01*
G01X1646357Y550316D02*
X1646358Y550320D01*
G01X1646357Y550315D02*
Y550316D01*
G01X1646358Y547170D02*
Y547176D01*
G01X1646357Y547167D02*
X1646358Y547170D01*
G01X1646357Y547165D02*
Y547167D01*
G01X1646358Y544021D02*
Y544027D01*
G01X1646357Y544017D02*
X1646358Y544021D01*
G01X1646357Y544016D02*
Y544017D01*
G01X1646358Y540871D02*
Y540877D01*
G01X1646357Y540867D02*
X1646358Y540871D01*
G01X1646357Y540866D02*
Y540867D01*
G01X1646358Y537722D02*
Y537728D01*
G01X1646357Y537718D02*
X1646358Y537722D01*
G01X1646357Y537717D02*
Y537718D01*
G01X1659823Y533378D02*
Y533369D01*
G01X1659824Y533384D02*
X1659823Y533378D01*
G01X1659826Y533386D02*
X1659824Y533384D01*
G01X1659823Y528378D02*
Y528369D01*
G01X1659824Y528384D02*
X1659823Y528378D01*
G01X1659826Y528386D02*
X1659824Y528384D01*
G01X1659823Y523378D02*
Y523369D01*
G01X1659824Y523384D02*
X1659823Y523378D01*
G01X1659826Y523386D02*
X1659824Y523384D01*
G01X1659823Y518378D02*
Y518369D01*
G01X1659824Y518384D02*
X1659823Y518378D01*
G01X1659826Y518386D02*
X1659824Y518384D01*
G01X1659823Y513378D02*
Y513369D01*
G01X1659824Y513384D02*
X1659823Y513378D01*
G01X1659826Y513386D02*
X1659824Y513384D01*
G01X1659823Y508378D02*
Y508369D01*
G01X1659824Y508384D02*
X1659823Y508378D01*
G01X1659826Y508386D02*
X1659824Y508384D01*
G01X1659823Y503378D02*
Y503369D01*
G01X1659824Y503384D02*
X1659823Y503378D01*
G01X1659826Y503386D02*
X1659824Y503384D01*
G01X1655433Y492264D02*
G03I-1102J0D01*
G01X1656890Y486988D02*
G03X1658071Y488169I0J1181D01*
G01X1650591D02*
G03X1651772Y486988I1181J0D01*
G01X1655906Y492264D02*
G03I-1575J0D01*
G01X1650394Y477894D02*
G03X1650984Y477303I590J-1D01*
G01X1657677D02*
G03X1658268Y477894I0J591D01*
G01X1655512Y479075D02*
G03Y481043I0J984D01*
G01X1653150D02*
G03Y479075I0J-984D01*
G01X1643504Y478484D02*
G03X1645472Y476516I1968J0D01*
G01X1663189D02*
G03X1665157Y478484I0J1968D01*
G01X1649803Y500256D02*
X1648622Y499075D01*
G01X1646850Y497579D02*
X1643504Y494232D01*
G01X1656815Y495335D02*
X1655512Y493366D01*
G01X1650839Y487444D02*
X1653150Y491673D01*
G01X1646397Y537679D02*
X1646398Y537691D01*
G01X1646397Y540829D02*
X1646398Y540840D01*
G01X1646397Y543978D02*
X1646398Y543990D01*
G01X1646397Y547128D02*
X1646398Y547139D01*
G01X1646397Y550278D02*
X1646398Y550289D01*
G01X1646397Y553427D02*
X1646398Y553439D01*
G01X1646397Y556577D02*
X1646398Y556588D01*
G01X1659823Y504738D02*
Y504746D01*
G01Y509738D02*
Y509746D01*
G01Y514738D02*
Y514746D01*
G01Y519738D02*
Y519746D01*
G01Y524738D02*
Y524746D01*
G01Y529738D02*
Y529746D01*
G01Y534738D02*
Y534746D01*
G01Y559738D02*
Y559746D01*
G01Y564738D02*
Y564746D01*
G01Y569738D02*
Y569746D01*
G01X1665157Y478484D02*
Y494232D01*
G01X1664173Y568386D02*
Y569764D01*
G01Y563386D02*
Y564764D01*
G01Y558386D02*
Y559764D01*
G01Y533386D02*
Y534764D01*
G01Y528386D02*
Y529764D01*
G01Y523386D02*
Y524764D01*
G01Y518386D02*
Y519764D01*
G01Y513386D02*
Y514764D01*
G01Y508386D02*
Y509764D01*
G01Y503386D02*
Y504764D01*
G01X1661811Y635571D02*
Y497579D01*
G01X1661220Y637815D02*
Y495335D01*
G01X1661004Y504764D02*
Y503386D01*
G01Y509764D02*
Y508386D01*
G01Y514764D02*
Y513386D01*
G01Y519764D02*
Y518386D01*
G01Y524764D02*
Y523386D01*
G01Y529764D02*
Y528386D01*
G01Y534764D02*
Y533386D01*
G01Y559764D02*
Y558386D01*
G01Y564764D02*
Y563386D01*
G01Y569764D02*
Y568386D01*
G01X1660433Y557618D02*
Y535531D01*
G01X1659823Y504738D02*
Y504881D01*
G01Y514738D02*
Y514881D01*
G01Y509738D02*
Y509881D01*
G01Y524738D02*
Y524881D01*
G01Y519738D02*
Y519881D01*
G01Y534738D02*
Y534881D01*
G01Y529738D02*
Y529881D01*
G01Y564738D02*
Y564881D01*
G01Y559738D02*
Y559881D01*
G01Y567894D02*
Y570256D01*
G01Y562894D02*
Y565256D01*
G01Y557894D02*
Y560256D01*
G01Y532894D02*
Y535256D01*
G01Y527894D02*
Y530256D01*
G01Y522894D02*
Y525256D01*
G01Y517894D02*
Y520256D01*
G01Y512894D02*
Y515256D01*
G01Y507894D02*
Y510256D01*
G01Y502894D02*
Y505256D01*
G01X1659252Y556437D02*
Y536713D01*
G01X1658839Y505256D02*
Y502894D01*
G01Y510256D02*
Y507894D01*
G01Y515256D02*
Y512894D01*
G01Y520256D02*
Y517894D01*
G01Y525256D02*
Y522894D01*
G01Y530256D02*
Y527894D01*
G01Y535256D02*
Y532894D01*
G01Y560256D02*
Y557894D01*
G01Y565256D02*
Y562894D01*
G01Y570256D02*
Y567894D01*
G01X1658268Y483996D02*
Y477894D01*
G01X1658071Y496713D02*
Y488169D01*
G01X1656496Y535531D02*
Y499075D01*
G01Y634075D02*
Y557618D01*
G01X1655512Y493366D02*
Y491673D01*
G01X1655315Y536713D02*
Y500256D01*
G01Y632894D02*
Y556437D01*
G01X1653150Y491673D02*
Y493366D01*
G01X1650591Y488169D02*
Y496713D01*
G01X1650394Y483996D02*
Y477894D01*
G01X1649803Y500256D02*
Y632894D01*
G01X1648622Y499075D02*
Y634075D01*
G01X1646850Y534370D02*
Y495335D01*
G01Y637815D02*
Y558780D01*
G01X1646398Y555275D02*
Y556772D01*
G01Y552126D02*
Y553622D01*
G01Y548976D02*
Y550472D01*
G01Y545826D02*
Y547323D01*
G01Y542677D02*
Y544173D01*
G01Y539527D02*
Y541024D01*
G01Y536378D02*
Y537874D01*
G01X1646358Y536524D02*
Y536377D01*
G01Y539674D02*
Y539527D01*
G01Y541024D02*
Y540877D01*
G01Y537874D02*
Y537728D01*
G01Y545973D02*
Y545826D01*
G01Y542823D02*
Y542676D01*
G01Y544174D02*
Y544027D01*
G01Y549122D02*
Y548976D01*
G01Y550473D02*
Y550326D01*
G01Y547323D02*
Y547176D01*
G01Y555422D02*
Y555275D01*
G01Y552272D02*
Y552125D01*
G01Y553622D02*
Y553476D01*
G01Y556772D02*
Y556625D01*
G01X1645453D02*
Y556772D01*
G01Y555275D02*
Y555422D01*
G01Y552125D02*
Y552272D01*
G01Y553476D02*
Y553622D01*
G01Y548976D02*
Y549122D01*
G01Y550326D02*
Y550473D01*
G01Y547176D02*
Y547323D01*
G01Y545826D02*
Y545973D01*
G01Y542676D02*
Y542823D01*
G01Y544027D02*
Y544174D01*
G01Y539527D02*
Y539674D01*
G01Y540877D02*
Y541024D01*
G01Y537728D02*
Y537874D01*
G01Y536377D02*
Y536524D01*
G01X1645413Y541024D02*
Y539528D01*
G01Y537874D02*
Y536378D01*
G01Y544173D02*
Y542677D01*
G01Y550472D02*
Y548976D01*
G01Y547323D02*
Y545827D01*
G01Y553622D02*
Y552126D01*
G01Y556772D02*
Y555276D01*
G01X1644232Y537717D02*
Y536535D01*
G01Y540866D02*
Y539685D01*
G01Y547165D02*
Y545984D01*
G01Y544016D02*
Y542835D01*
G01Y550315D02*
Y549134D01*
G01Y556614D02*
Y555433D01*
G01Y553465D02*
Y552283D01*
G01X1643898Y558780D02*
Y534370D01*
G01X1643504D02*
Y558780D01*
G01Y494232D02*
Y478484D01*
G01X1640472Y555433D02*
Y556614D01*
G01Y552283D02*
Y553465D01*
G01Y549134D02*
Y550315D01*
G01Y545984D02*
Y547165D01*
G01Y542835D02*
Y544016D01*
G01Y539685D02*
Y540866D01*
G01Y536535D02*
Y537717D01*
G01X1646398Y555459D02*
X1646397Y555470D01*
G01X1646398Y552309D02*
X1646397Y552320D01*
G01X1646398Y549160D02*
X1646397Y549170D01*
G01X1646398Y546010D02*
X1646397Y546021D01*
G01X1646398Y542861D02*
X1646397Y542871D01*
G01X1646398Y539711D02*
X1646397Y539722D01*
G01X1646398Y536561D02*
X1646397Y536572D01*
G01X1659252Y556437D02*
X1660433Y557618D01*
G01X1655315Y556437D02*
X1656496Y557618D01*
G01X1646357Y552283D02*
X1646360Y552272D01*
G01X1655512Y491673D02*
X1657822Y487444D01*
G01X1653150Y493366D02*
X1651846Y495335D01*
G01X1659252Y536713D02*
X1660433Y535531D01*
G01X1655315Y536713D02*
X1656496Y535531D01*
G01X1661811Y497579D02*
X1665157Y494232D01*
G01X1655315Y500256D02*
X1656496Y499075D01*
G01X1645300Y555472D02*
X1645412Y555464D01*
G01X1645411Y546019D02*
X1645300Y546024D01*
G01X1645411Y539721D02*
X1645300Y539724D01*
G01X1645411Y549170D02*
X1645300Y549173D01*
G01X1659823Y570256D02*
X1658839D01*
G01X1658840Y569764D02*
X1664173D01*
G01Y569724D02*
X1659825D01*
G01X1664173Y568386D02*
X1658840D01*
G01X1658839Y567894D02*
X1659823D01*
G01Y565256D02*
X1658839D01*
G01X1658840Y564764D02*
X1664173D01*
G01Y564724D02*
X1659825D01*
G01X1664173Y563386D02*
X1658840D01*
G01X1658839Y562894D02*
X1659823D01*
G01Y560256D02*
X1658839D01*
G01X1658840Y559764D02*
X1664173D01*
G01Y559724D02*
X1659825D01*
G01X1646850Y558780D02*
X1643504D01*
G01X1664173Y558386D02*
X1658840D01*
G01X1658839Y557894D02*
X1659823D01*
G01X1656496Y557618D02*
X1660433D01*
G01X1646358Y556811D02*
X1645453D01*
G01X1646398Y556772D02*
X1645413D01*
G01X1646357Y556614D02*
X1640472D01*
G01Y556575D02*
X1646396D01*
G01X1655315Y556437D02*
X1659252D01*
G01X1646396Y555472D02*
X1640472D01*
G01X1646357Y555433D02*
X1640472D01*
G01X1645413Y555276D02*
X1646398D01*
G01X1645453Y555236D02*
X1646358D01*
G01Y553661D02*
X1645453D01*
G01X1646398Y553622D02*
X1645413D01*
G01X1646357Y553465D02*
X1640472D01*
G01Y553425D02*
X1646396D01*
G01Y552323D02*
X1640472D01*
G01X1646357Y552283D02*
X1640472D01*
G01X1645413Y552126D02*
X1646398D01*
G01X1645453Y552087D02*
X1646358D01*
G01Y550512D02*
X1645453D01*
G01X1646398Y550472D02*
X1645413D01*
G01X1646357Y550315D02*
X1640472D01*
G01Y550276D02*
X1646396D01*
G01X1644666Y549173D02*
X1644232D01*
G01X1646396D02*
X1640472D01*
G01X1646357Y549134D02*
X1640472D01*
G01X1645413Y548976D02*
X1646398D01*
G01X1645453Y548937D02*
X1646358D01*
G01Y547362D02*
X1645453D01*
G01X1646398Y547323D02*
X1645413D01*
G01X1646357Y547165D02*
X1640472D01*
G01Y547126D02*
X1646396D01*
G01X1644666Y546024D02*
X1644232D01*
G01X1646396D02*
X1640472D01*
G01X1646357Y545984D02*
X1640472D01*
G01X1645413Y545827D02*
X1646398D01*
G01X1645453Y545787D02*
X1646358D01*
G01Y544213D02*
X1645453D01*
G01X1646398Y544173D02*
X1645413D01*
G01X1646357Y544016D02*
X1640472D01*
G01Y543976D02*
X1646396D01*
G01Y542874D02*
X1640472D01*
G01X1646357Y542835D02*
X1640472D01*
G01X1645413Y542677D02*
X1646398D01*
G01X1645453Y542638D02*
X1646358D01*
G01Y541063D02*
X1645453D01*
G01X1646398Y541024D02*
X1645413D01*
G01X1646357Y540866D02*
X1640472D01*
G01Y540827D02*
X1646396D01*
G01X1644666Y539724D02*
X1644232D01*
G01X1646396D02*
X1640472D01*
G01X1646357Y539685D02*
X1640472D01*
G01X1645413Y539528D02*
X1646398D01*
G01X1645453Y539488D02*
X1646358D01*
G01Y537913D02*
X1645453D01*
G01X1646398Y537874D02*
X1645413D01*
G01X1646357Y537717D02*
X1640472D01*
G01Y537677D02*
X1646396D01*
G01X1659252Y536713D02*
X1655315D01*
G01X1646396Y536575D02*
X1640472D01*
G01X1646357Y536535D02*
X1640472D01*
G01X1645413Y536378D02*
X1646398D01*
G01X1645453Y536339D02*
X1646358D01*
G01X1660433Y535531D02*
X1656496D01*
G01X1659823Y535256D02*
X1658839D01*
G01X1658840Y534764D02*
X1664173D01*
G01Y534724D02*
X1659825D01*
G01X1646850Y534370D02*
X1643504D01*
G01X1664173Y533386D02*
X1658840D01*
G01X1658839Y532894D02*
X1659823D01*
G01Y530256D02*
X1658839D01*
G01X1658840Y529764D02*
X1664173D01*
G01Y529724D02*
X1659825D01*
G01X1664173Y528386D02*
X1658840D01*
G01X1658839Y569959D02*
X1659794Y569961D01*
G01X1659823Y568190D02*
X1658839Y568189D01*
G01Y564959D02*
X1659794Y564961D01*
G01X1659823Y563190D02*
X1658839Y563189D01*
G01Y559959D02*
X1659794Y559961D01*
G01X1659823Y558190D02*
X1658839Y558189D01*
G01Y534959D02*
X1659794Y534961D01*
G01X1659823Y533190D02*
X1658839Y533189D01*
G01Y529959D02*
X1659794Y529961D01*
G01X1658839Y527894D02*
X1659823D01*
G01Y525256D02*
X1658839D01*
G01X1658840Y524764D02*
X1664173D01*
G01Y524724D02*
X1659825D01*
G01X1664173Y523386D02*
X1658840D01*
G01X1658839Y522894D02*
X1659823D01*
G01Y520256D02*
X1658839D01*
G01X1658840Y519764D02*
X1664173D01*
G01Y519724D02*
X1659825D01*
G01X1664173Y518386D02*
X1658840D01*
G01X1658839Y517894D02*
X1659823D01*
G01Y515256D02*
X1658839D01*
G01X1658840Y514764D02*
X1664173D01*
G01Y514724D02*
X1659825D01*
G01X1664173Y513386D02*
X1658840D01*
G01X1658839Y512894D02*
X1659823D01*
G01Y510256D02*
X1658839D01*
G01X1658840Y509764D02*
X1664173D01*
G01Y509724D02*
X1659825D01*
G01X1664173Y508386D02*
X1658840D01*
G01X1658839Y507894D02*
X1659823D01*
G01Y505256D02*
X1658839D01*
G01X1658840Y504764D02*
X1664173D01*
G01Y504724D02*
X1659825D01*
G01X1664173Y503386D02*
X1658840D01*
G01X1658839Y502894D02*
X1659823D01*
G01X1655315Y500256D02*
X1649803D01*
G01X1656496Y499075D02*
X1648622D01*
G01X1661811Y497579D02*
X1646850D01*
G01X1658071Y496713D02*
X1661220D01*
G01X1650591D02*
X1646850D01*
G01Y495335D02*
X1661220D01*
G01X1655512Y493366D02*
X1653150D01*
G01X1655512Y491673D02*
X1653150D01*
G01X1656890Y486988D02*
X1651772D01*
G01X1665157Y486949D02*
X1643504D01*
G01X1658268Y483996D02*
X1650394D01*
G01Y482421D02*
X1658268D01*
G01X1655512Y481043D02*
X1653150D01*
G01Y479075D02*
X1655512D01*
G01X1657677Y477303D02*
X1650984D01*
G01X1663189Y476516D02*
X1645472D01*
G01X1659823Y528190D02*
X1658839Y528189D01*
G01Y524959D02*
X1659794Y524961D01*
G01X1659823Y523190D02*
X1658839Y523189D01*
G01Y519959D02*
X1659794Y519961D01*
G01X1659823Y518190D02*
X1658839Y518189D01*
G01Y514959D02*
X1659794Y514961D01*
G01X1659823Y513190D02*
X1658839Y513189D01*
G01Y509959D02*
X1659794Y509961D01*
G01X1659823Y508190D02*
X1658839Y508189D01*
G01Y504959D02*
X1659794Y504961D01*
G01X1659823Y503190D02*
X1658839Y503189D01*
G01X1659810Y574755D02*
X1659821Y574740D01*
G01X1659786Y574764D02*
X1659810Y574755D01*
G01Y579755D02*
X1659821Y579740D01*
G01X1659786Y579764D02*
X1659810Y579755D01*
G01Y584755D02*
X1659821Y584740D01*
G01X1659786Y584764D02*
X1659810Y584755D01*
G01Y589755D02*
X1659821Y589740D01*
G01X1659786Y589764D02*
X1659810Y589755D01*
G01Y594755D02*
X1659821Y594740D01*
G01X1659786Y594764D02*
X1659810Y594755D01*
G01Y599755D02*
X1659821Y599740D01*
G01X1659786Y599764D02*
X1659810Y599755D01*
G01Y604755D02*
X1659821Y604740D01*
G01X1659786Y604764D02*
X1659810Y604755D01*
G01Y609755D02*
X1659821Y609740D01*
G01X1659786Y609764D02*
X1659810Y609755D01*
G01Y614755D02*
X1659821Y614740D01*
G01X1659786Y614764D02*
X1659810Y614755D01*
G01Y619755D02*
X1659821Y619740D01*
G01X1659786Y619764D02*
X1659810Y619755D01*
G01Y624755D02*
X1659821Y624740D01*
G01X1659786Y624764D02*
X1659810Y624755D01*
G01Y629755D02*
X1659821Y629740D01*
G01X1659786Y629764D02*
X1659810Y629755D01*
G01X1659823Y574731D02*
Y574738D01*
G01X1659824Y574726D02*
X1659823Y574731D01*
G01X1659825Y574724D02*
X1659824Y574726D01*
G01X1659823Y579731D02*
Y579738D01*
G01X1659824Y579726D02*
X1659823Y579731D01*
G01X1659825Y579724D02*
X1659824Y579726D01*
G01X1659823Y584731D02*
Y584738D01*
G01X1659824Y584726D02*
X1659823Y584731D01*
G01X1659825Y584724D02*
X1659824Y584726D01*
G01X1659823Y589731D02*
Y589738D01*
G01X1659824Y589726D02*
X1659823Y589731D01*
G01X1659825Y589724D02*
X1659824Y589726D01*
G01X1659823Y594731D02*
Y594738D01*
G01X1659824Y594726D02*
X1659823Y594731D01*
G01X1659825Y594724D02*
X1659824Y594726D01*
G01X1659823Y599731D02*
Y599738D01*
G01X1659824Y599726D02*
X1659823Y599731D01*
G01X1659825Y599724D02*
X1659824Y599726D01*
G01X1659823Y604731D02*
Y604738D01*
G01X1659824Y604726D02*
X1659823Y604731D01*
G01X1659825Y604724D02*
X1659824Y604726D01*
G01X1659823Y609731D02*
Y609738D01*
G01X1659824Y609726D02*
X1659823Y609731D01*
G01X1659825Y609724D02*
X1659824Y609726D01*
G01X1659823Y614731D02*
Y614738D01*
G01X1659824Y614726D02*
X1659823Y614731D01*
G01X1659825Y614724D02*
X1659824Y614726D01*
G01X1659823Y619731D02*
Y619738D01*
G01X1659824Y619726D02*
X1659823Y619731D01*
G01X1659825Y619724D02*
X1659824Y619726D01*
G01X1659823Y624731D02*
Y624738D01*
G01X1659824Y624726D02*
X1659823Y624731D01*
G01X1659825Y624724D02*
X1659824Y624726D01*
G01X1659823Y629731D02*
Y629738D01*
G01X1659824Y629726D02*
X1659823Y629731D01*
G01X1659825Y629724D02*
X1659824Y629726D01*
G01X1658839Y574771D02*
Y574780D01*
G01Y574765D02*
Y574771D01*
G01X1658840Y574764D02*
X1658839Y574765D01*
G01Y579771D02*
Y579780D01*
G01Y579765D02*
Y579771D01*
G01X1658840Y579764D02*
X1658839Y579765D01*
G01Y584771D02*
Y584780D01*
G01Y584765D02*
Y584771D01*
G01X1658840Y584764D02*
X1658839Y584765D01*
G01Y589771D02*
Y589780D01*
G01Y589765D02*
Y589771D01*
G01X1658840Y589764D02*
X1658839Y589765D01*
G01Y594771D02*
Y594780D01*
G01Y594765D02*
Y594771D01*
G01X1658840Y594764D02*
X1658839Y594765D01*
G01Y599771D02*
Y599780D01*
G01Y599765D02*
Y599771D01*
G01X1658840Y599764D02*
X1658839Y599765D01*
G01Y604771D02*
Y604780D01*
G01Y604765D02*
Y604771D01*
G01X1658840Y604764D02*
X1658839Y604765D01*
G01Y609771D02*
Y609780D01*
G01Y609765D02*
Y609771D01*
G01X1658840Y609764D02*
X1658839Y609765D01*
G01Y614771D02*
Y614780D01*
G01Y614765D02*
Y614771D01*
G01X1658840Y614764D02*
X1658839Y614765D01*
G01Y619771D02*
Y619780D01*
G01Y619765D02*
Y619771D01*
G01X1658840Y619764D02*
X1658839Y619765D01*
G01Y624771D02*
Y624780D01*
G01Y624765D02*
Y624771D01*
G01X1658840Y624764D02*
X1658839Y624765D01*
G01Y629771D02*
Y629780D01*
G01Y629765D02*
Y629771D01*
G01X1658840Y629764D02*
X1658839Y629765D01*
G01X1659815Y574907D02*
X1659823Y574881D01*
G01X1659805Y574934D02*
X1659815Y574907D01*
G01X1659794Y574961D02*
X1659805Y574934D01*
G01X1659815Y579907D02*
X1659823Y579881D01*
G01X1659805Y579934D02*
X1659815Y579907D01*
G01X1659794Y579961D02*
X1659805Y579934D01*
G01X1659815Y584907D02*
X1659823Y584881D01*
G01X1659805Y584934D02*
X1659815Y584907D01*
G01X1659794Y584961D02*
X1659805Y584934D01*
G01X1659815Y589907D02*
X1659823Y589881D01*
G01X1659805Y589934D02*
X1659815Y589907D01*
G01X1659794Y589961D02*
X1659805Y589934D01*
G01X1659815Y594907D02*
X1659823Y594881D01*
G01X1659805Y594934D02*
X1659815Y594907D01*
G01X1659794Y594961D02*
X1659805Y594934D01*
G01X1659815Y599907D02*
X1659823Y599881D01*
G01X1659805Y599934D02*
X1659815Y599907D01*
G01X1659794Y599961D02*
X1659805Y599934D01*
G01X1659815Y604907D02*
X1659823Y604881D01*
G01X1659805Y604934D02*
X1659815Y604907D01*
G01X1659794Y604961D02*
X1659805Y604934D01*
G01X1659815Y609907D02*
X1659823Y609881D01*
G01X1659805Y609934D02*
X1659815Y609907D01*
G01X1659794Y609961D02*
X1659805Y609934D01*
G01X1659815Y614907D02*
X1659823Y614881D01*
G01X1659805Y614934D02*
X1659815Y614907D01*
G01X1659794Y614961D02*
X1659805Y614934D01*
G01X1659815Y619907D02*
X1659823Y619881D01*
G01X1659805Y619934D02*
X1659815Y619907D01*
G01X1659794Y619961D02*
X1659805Y619934D01*
G01X1659815Y624907D02*
X1659823Y624881D01*
G01X1659805Y624934D02*
X1659815Y624907D01*
G01X1659794Y624961D02*
X1659805Y624934D01*
G01X1659815Y629907D02*
X1659823Y629881D01*
G01X1659805Y629934D02*
X1659815Y629907D01*
G01X1659794Y629961D02*
X1659805Y629934D01*
G01X1659823Y628378D02*
Y628369D01*
G01X1659824Y628384D02*
X1659823Y628378D01*
G01X1659826Y628386D02*
X1659824Y628384D01*
G01X1659823Y623378D02*
Y623369D01*
G01X1659824Y623384D02*
X1659823Y623378D01*
G01X1659826Y623386D02*
X1659824Y623384D01*
G01X1659823Y618378D02*
Y618369D01*
G01X1659824Y618384D02*
X1659823Y618378D01*
G01X1659826Y618386D02*
X1659824Y618384D01*
G01X1659823Y613378D02*
Y613369D01*
G01X1659824Y613384D02*
X1659823Y613378D01*
G01X1659826Y613386D02*
X1659824Y613384D01*
G01X1659823Y608378D02*
Y608369D01*
G01X1659824Y608384D02*
X1659823Y608378D01*
G01X1659826Y608386D02*
X1659824Y608384D01*
G01X1659823Y603378D02*
Y603369D01*
G01X1659824Y603384D02*
X1659823Y603378D01*
G01X1659826Y603386D02*
X1659824Y603384D01*
G01X1659823Y598378D02*
Y598369D01*
G01X1659824Y598384D02*
X1659823Y598378D01*
G01X1659826Y598386D02*
X1659824Y598384D01*
G01X1659823Y593378D02*
Y593369D01*
G01X1659824Y593384D02*
X1659823Y593378D01*
G01X1659826Y593386D02*
X1659824Y593384D01*
G01X1659823Y588378D02*
Y588369D01*
G01X1659824Y588384D02*
X1659823Y588378D01*
G01X1659826Y588386D02*
X1659824Y588384D01*
G01X1659823Y583378D02*
Y583369D01*
G01X1659824Y583384D02*
X1659823Y583378D01*
G01X1659826Y583386D02*
X1659824Y583384D01*
G01X1659823Y578378D02*
Y578369D01*
G01X1659824Y578384D02*
X1659823Y578378D01*
G01X1659826Y578386D02*
X1659824Y578384D01*
G01X1659823Y573378D02*
Y573369D01*
G01X1659824Y573384D02*
X1659823Y573378D01*
G01X1659826Y573386D02*
X1659824Y573384D01*
G01X1659806Y574759D02*
X1659786Y574764D01*
G01X1659820Y574744D02*
X1659806Y574759D01*
G01X1659825Y574724D02*
X1659820Y574744D01*
G01X1659806Y579759D02*
X1659786Y579764D01*
G01X1659820Y579744D02*
X1659806Y579759D01*
G01X1659825Y579724D02*
X1659820Y579744D01*
G01X1659806Y584759D02*
X1659786Y584764D01*
G01X1659820Y584744D02*
X1659806Y584759D01*
G01X1659825Y584724D02*
X1659820Y584744D01*
G01X1659806Y589759D02*
X1659786Y589764D01*
G01X1659820Y589744D02*
X1659806Y589759D01*
G01X1659825Y589724D02*
X1659820Y589744D01*
G01X1659806Y594759D02*
X1659786Y594764D01*
G01X1659820Y594744D02*
X1659806Y594759D01*
G01X1659825Y594724D02*
X1659820Y594744D01*
G01X1659806Y599759D02*
X1659786Y599764D01*
G01X1659820Y599744D02*
X1659806Y599759D01*
G01X1659825Y599724D02*
X1659820Y599744D01*
G01X1659806Y604759D02*
X1659786Y604764D01*
G01X1659820Y604744D02*
X1659806Y604759D01*
G01X1659825Y604724D02*
X1659820Y604744D01*
G01X1659806Y609759D02*
X1659786Y609764D01*
G01X1659820Y609744D02*
X1659806Y609759D01*
G01X1659825Y609724D02*
X1659820Y609744D01*
G01X1659806Y614759D02*
X1659786Y614764D01*
G01X1659820Y614744D02*
X1659806Y614759D01*
G01X1659825Y614724D02*
X1659820Y614744D01*
G01X1659806Y619759D02*
X1659786Y619764D01*
G01X1659820Y619744D02*
X1659806Y619759D01*
G01X1659825Y619724D02*
X1659820Y619744D01*
G01X1659806Y624759D02*
X1659786Y624764D01*
G01X1659820Y624744D02*
X1659806Y624759D01*
G01X1659825Y624724D02*
X1659820Y624744D01*
G01X1659806Y629759D02*
X1659786Y629764D01*
G01X1659820Y629744D02*
X1659806Y629759D01*
G01X1659825Y629724D02*
X1659820Y629744D01*
G01X1659790Y574862D02*
X1659794Y574961D01*
G01X1659784Y574790D02*
X1659790Y574862D01*
G01X1659786Y574764D02*
X1659784Y574790D01*
G01X1659790Y579862D02*
X1659794Y579961D01*
G01X1659784Y579790D02*
X1659790Y579862D01*
G01X1659786Y579764D02*
X1659784Y579790D01*
G01X1659790Y584862D02*
X1659794Y584961D01*
G01X1659784Y584790D02*
X1659790Y584862D01*
G01X1659786Y584764D02*
X1659784Y584790D01*
G01X1659790Y589862D02*
X1659794Y589961D01*
G01X1659784Y589790D02*
X1659790Y589862D01*
G01X1659786Y589764D02*
X1659784Y589790D01*
G01X1659790Y594862D02*
X1659794Y594961D01*
G01X1659784Y594790D02*
X1659790Y594862D01*
G01X1659786Y594764D02*
X1659784Y594790D01*
G01X1659790Y599862D02*
X1659794Y599961D01*
G01X1659784Y599790D02*
X1659790Y599862D01*
G01X1659786Y599764D02*
X1659784Y599790D01*
G01X1659790Y604862D02*
X1659794Y604961D01*
G01X1659784Y604790D02*
X1659790Y604862D01*
G01X1659786Y604764D02*
X1659784Y604790D01*
G01X1659790Y609862D02*
X1659794Y609961D01*
G01X1659784Y609790D02*
X1659790Y609862D01*
G01X1659786Y609764D02*
X1659784Y609790D01*
G01X1659790Y614862D02*
X1659794Y614961D01*
G01X1659784Y614790D02*
X1659790Y614862D01*
G01X1659786Y614764D02*
X1659784Y614790D01*
G01X1659790Y619862D02*
X1659794Y619961D01*
G01X1659784Y619790D02*
X1659790Y619862D01*
G01X1659786Y619764D02*
X1659784Y619790D01*
G01X1659790Y624862D02*
X1659794Y624961D01*
G01X1659784Y624790D02*
X1659790Y624862D01*
G01X1659786Y624764D02*
X1659784Y624790D01*
G01X1659790Y629862D02*
X1659794Y629961D01*
G01X1659784Y629790D02*
X1659790Y629862D01*
G01X1659786Y629764D02*
X1659784Y629790D01*
G01X1658839Y628384D02*
X1658840Y628386D01*
G01X1658839Y628378D02*
Y628384D01*
G01Y628370D02*
Y628378D01*
G01Y623384D02*
X1658840Y623386D01*
G01X1658839Y623378D02*
Y623384D01*
G01Y623370D02*
Y623378D01*
G01Y618384D02*
X1658840Y618386D01*
G01X1658839Y618378D02*
Y618384D01*
G01Y618370D02*
Y618378D01*
G01Y613384D02*
X1658840Y613386D01*
G01X1658839Y613378D02*
Y613384D01*
G01Y613370D02*
Y613378D01*
G01Y608384D02*
X1658840Y608386D01*
G01X1658839Y608378D02*
Y608384D01*
G01Y608370D02*
Y608378D01*
G01Y603384D02*
X1658840Y603386D01*
G01X1658839Y603378D02*
Y603384D01*
G01Y603370D02*
Y603378D01*
G01Y598384D02*
X1658840Y598386D01*
G01X1658839Y598378D02*
Y598384D01*
G01Y598370D02*
Y598378D01*
G01Y593384D02*
X1658840Y593386D01*
G01X1658839Y593378D02*
Y593384D01*
G01Y593370D02*
Y593378D01*
G01Y588384D02*
X1658840Y588386D01*
G01X1658839Y588378D02*
Y588384D01*
G01Y588370D02*
Y588378D01*
G01Y583384D02*
X1658840Y583386D01*
G01X1658839Y583378D02*
Y583384D01*
G01Y583370D02*
Y583378D01*
G01Y578384D02*
X1658840Y578386D01*
G01X1658839Y578378D02*
Y578384D01*
G01Y578370D02*
Y578378D01*
G01Y573384D02*
X1658840Y573386D01*
G01X1658839Y573378D02*
Y573384D01*
G01Y573370D02*
Y573378D01*
G01X1658268Y655256D02*
G03X1657677Y655846I-591J-1D01*
G01X1650984D02*
G03X1650394Y655256I0J-590D01*
G01X1653150Y654075D02*
G03Y652106I0J-985D01*
G01X1655512D02*
G03Y654075I0J984D01*
G01X1651772Y646161D02*
G03X1650591Y644980I0J-1181D01*
G01X1658071D02*
G03X1656890Y646161I-1181J0D01*
G01X1656220Y640886D02*
G03I-1889J0D01*
G01X1665157Y654665D02*
G03X1663189Y656634I-1968J1D01*
G01X1645472D02*
G03X1643504Y654665I1J-1969D01*
G01X1656693Y640886D02*
G03I-2362J0D01*
G01X1659823Y574738D02*
Y574746D01*
G01Y579738D02*
Y579746D01*
G01Y584738D02*
Y584746D01*
G01Y589738D02*
Y589746D01*
G01Y594738D02*
Y594746D01*
G01Y599738D02*
Y599746D01*
G01Y604738D02*
Y604746D01*
G01Y609738D02*
Y609746D01*
G01Y614738D02*
Y614746D01*
G01Y619738D02*
Y619746D01*
G01Y624738D02*
Y624746D01*
G01Y629738D02*
Y629746D01*
G01X1665157Y638917D02*
Y654665D01*
G01X1664173Y628386D02*
Y629764D01*
G01Y623386D02*
Y624764D01*
G01Y618386D02*
Y619764D01*
G01Y613386D02*
Y614764D01*
G01Y608386D02*
Y609764D01*
G01Y603386D02*
Y604764D01*
G01Y598386D02*
Y599764D01*
G01Y593386D02*
Y594764D01*
G01Y588386D02*
Y589764D01*
G01Y583386D02*
Y584764D01*
G01Y578386D02*
Y579764D01*
G01Y573386D02*
Y574764D01*
G01X1661004D02*
Y573386D01*
G01Y579764D02*
Y578386D01*
G01Y584764D02*
Y583386D01*
G01Y589764D02*
Y588386D01*
G01Y594764D02*
Y593386D01*
G01Y599764D02*
Y598386D01*
G01Y604764D02*
Y603386D01*
G01Y609764D02*
Y608386D01*
G01Y614764D02*
Y613386D01*
G01Y619764D02*
Y618386D01*
G01Y624764D02*
Y623386D01*
G01Y629764D02*
Y628386D01*
G01X1659823Y627894D02*
Y630256D01*
G01Y622894D02*
Y625256D01*
G01Y617894D02*
Y620256D01*
G01Y612894D02*
Y615256D01*
G01Y607894D02*
Y610256D01*
G01Y602894D02*
Y605256D01*
G01Y597894D02*
Y600256D01*
G01Y592894D02*
Y595256D01*
G01Y587894D02*
Y590256D01*
G01Y582894D02*
Y585256D01*
G01Y577894D02*
Y580256D01*
G01Y572894D02*
Y575256D01*
G01X1658839D02*
Y572894D01*
G01Y580256D02*
Y577894D01*
G01Y585256D02*
Y582894D01*
G01Y590256D02*
Y587894D01*
G01Y595256D02*
Y592894D01*
G01Y600256D02*
Y597894D01*
G01Y605256D02*
Y602894D01*
G01Y610256D02*
Y607894D01*
G01Y615256D02*
Y612894D01*
G01Y620256D02*
Y617894D01*
G01Y625256D02*
Y622894D01*
G01Y630256D02*
Y627894D01*
G01X1658268Y649154D02*
Y655256D01*
G01X1658071Y644980D02*
Y636437D01*
G01X1655512Y641476D02*
Y639783D01*
G01X1653150D02*
Y641476D01*
G01X1650591Y636437D02*
Y644980D01*
G01X1650394Y649154D02*
Y655256D01*
G01X1643504Y654665D02*
Y638917D01*
G01X1651846Y637815D02*
X1653150Y639783D01*
G01X1657822Y645706D02*
X1655512Y641476D01*
G01X1653150D02*
X1650839Y645706D01*
G01X1655512Y639783D02*
X1656815Y637815D01*
G01X1665157Y638917D02*
X1661811Y635571D01*
G01X1655315Y632894D02*
X1656496Y634075D01*
G01X1648622D02*
X1649803Y632894D01*
G01X1643504Y638917D02*
X1646850Y635571D01*
G01X1663189Y656634D02*
X1645472D01*
G01X1657677Y655846D02*
X1650984D01*
G01X1655512Y654075D02*
X1653150D01*
G01Y652106D02*
X1655512D01*
G01X1658268Y650728D02*
X1650394D01*
G01Y649154D02*
X1658268D01*
G01X1665157Y646201D02*
X1643504D01*
G01X1651772Y646161D02*
X1656890D01*
G01X1653150Y641476D02*
X1655512D01*
G01X1653150Y639783D02*
X1655512D01*
G01X1646850Y637815D02*
X1661220D01*
G01X1646850Y636437D02*
X1650591D01*
G01X1661220D02*
X1658071D01*
G01X1646850Y635571D02*
X1661811D01*
G01X1648622Y634075D02*
X1656496D01*
G01X1649803Y632894D02*
X1655315D01*
G01X1659823Y630256D02*
X1658839D01*
G01X1658840Y629764D02*
X1664173D01*
G01Y629724D02*
X1659825D01*
G01X1664173Y628386D02*
X1658840D01*
G01X1658839Y627894D02*
X1659823D01*
G01Y625256D02*
X1658839D01*
G01X1658840Y624764D02*
X1664173D01*
G01Y624724D02*
X1659825D01*
G01X1664173Y623386D02*
X1658840D01*
G01X1658839Y622894D02*
X1659823D01*
G01Y620256D02*
X1658839D01*
G01X1658840Y619764D02*
X1664173D01*
G01Y619724D02*
X1659825D01*
G01X1664173Y618386D02*
X1658840D01*
G01X1658839Y617894D02*
X1659823D01*
G01Y615256D02*
X1658839D01*
G01X1658840Y614764D02*
X1664173D01*
G01Y614724D02*
X1659825D01*
G01X1664173Y613386D02*
X1658840D01*
G01X1658839Y612894D02*
X1659823D01*
G01Y610256D02*
X1658839D01*
G01Y629959D02*
X1659794Y629961D01*
G01X1659823Y628190D02*
X1658839Y628189D01*
G01Y624959D02*
X1659794Y624961D01*
G01X1659823Y623190D02*
X1658839Y623189D01*
G01Y619959D02*
X1659794Y619961D01*
G01X1659823Y618190D02*
X1658839Y618189D01*
G01Y614959D02*
X1659794Y614961D01*
G01X1659823Y613190D02*
X1658839Y613189D01*
G01X1658840Y609764D02*
X1664173D01*
G01Y609724D02*
X1659825D01*
G01X1664173Y608386D02*
X1658840D01*
G01X1658839Y607894D02*
X1659823D01*
G01Y605256D02*
X1658839D01*
G01X1658840Y604764D02*
X1664173D01*
G01Y604724D02*
X1659825D01*
G01X1664173Y603386D02*
X1658840D01*
G01X1658839Y602894D02*
X1659823D01*
G01Y600256D02*
X1658839D01*
G01X1658840Y599764D02*
X1664173D01*
G01Y599724D02*
X1659825D01*
G01X1664173Y598386D02*
X1658840D01*
G01X1658839Y597894D02*
X1659823D01*
G01Y595256D02*
X1658839D01*
G01X1658840Y594764D02*
X1664173D01*
G01Y594724D02*
X1659825D01*
G01X1664173Y593386D02*
X1658840D01*
G01X1658839Y592894D02*
X1659823D01*
G01Y590256D02*
X1658839D01*
G01X1658840Y589764D02*
X1664173D01*
G01Y589724D02*
X1659825D01*
G01X1664173Y588386D02*
X1658840D01*
G01X1658839Y587894D02*
X1659823D01*
G01Y585256D02*
X1658839D01*
G01X1658840Y584764D02*
X1664173D01*
G01Y584724D02*
X1659825D01*
G01X1664173Y583386D02*
X1658840D01*
G01X1658839Y582894D02*
X1659823D01*
G01Y580256D02*
X1658839D01*
G01X1658840Y579764D02*
X1664173D01*
G01Y579724D02*
X1659825D01*
G01X1664173Y578386D02*
X1658840D01*
G01X1658839Y577894D02*
X1659823D01*
G01Y575256D02*
X1658839D01*
G01X1658840Y574764D02*
X1664173D01*
G01Y574724D02*
X1659825D01*
G01X1664173Y573386D02*
X1658840D01*
G01X1658839Y572894D02*
X1659823D01*
G01X1658839Y609959D02*
X1659794Y609961D01*
G01X1659823Y608190D02*
X1658839Y608189D01*
G01Y604959D02*
X1659794Y604961D01*
G01X1659823Y603190D02*
X1658839Y603189D01*
G01Y599959D02*
X1659794Y599961D01*
G01X1659823Y598190D02*
X1658839Y598189D01*
G01Y594959D02*
X1659794Y594961D01*
G01X1659823Y593190D02*
X1658839Y593189D01*
G01Y589959D02*
X1659794Y589961D01*
G01X1659823Y588190D02*
X1658839Y588189D01*
G01Y584959D02*
X1659794Y584961D01*
G01X1659823Y583190D02*
X1658839Y583189D01*
G01Y579959D02*
X1659794Y579961D01*
G01X1659823Y578190D02*
X1658839Y578189D01*
G01Y574959D02*
X1659794Y574961D01*
G01X1659823Y573190D02*
X1658839Y573189D01*
G01X1655433Y945020D02*
G03I-1102J0D01*
G01X1656890Y939744D02*
G03X1658071Y940925I0J1181D01*
G01X1650591D02*
G03X1651772Y939744I1181J0D01*
G01X1655906Y945020D02*
G03I-1575J0D01*
G01X1650394Y930650D02*
G03X1650984Y930059I590J-1D01*
G01X1657677D02*
G03X1658268Y930650I0J591D01*
G01X1655512Y931831D02*
G03Y933799I0J984D01*
G01X1653150D02*
G03Y931831I0J-984D01*
G01X1643504Y931240D02*
G03X1645472Y929272I1968J0D01*
G01X1663189D02*
G03X1665157Y931240I0J1968D01*
G01X1655512Y944429D02*
X1657822Y940200D01*
G01X1653150Y946122D02*
X1651846Y948091D01*
G01X1665157Y931240D02*
Y946988D01*
G01X1661811Y1088327D02*
Y950335D01*
G01X1661220Y1090571D02*
Y948091D01*
G01X1658268Y936752D02*
Y930650D01*
G01X1658071Y949469D02*
Y940925D01*
G01X1656496Y988287D02*
Y951831D01*
G01X1655512Y946122D02*
Y944429D01*
G01X1653150D02*
Y946122D01*
G01X1650591Y940925D02*
Y949469D01*
G01X1650394Y936752D02*
Y930650D01*
G01X1648622Y951831D02*
Y1086831D01*
G01X1646850Y987126D02*
Y948091D01*
G01X1643504Y946988D02*
Y931240D01*
G01X1661811Y950335D02*
X1665157Y946988D01*
G01X1655315Y953012D02*
X1656496Y951831D01*
G01X1650839Y940200D02*
X1653150Y944429D01*
G01X1656815Y948091D02*
X1655512Y946122D01*
G01X1649803Y953012D02*
X1648622Y951831D01*
G01X1646850Y950335D02*
X1643504Y946988D01*
G01X1656496Y951831D02*
X1648622D01*
G01X1661811Y950335D02*
X1646850D01*
G01X1658071Y949469D02*
X1661220D01*
G01X1650591D02*
X1646850D01*
G01Y948091D02*
X1661220D01*
G01X1655512Y946122D02*
X1653150D01*
G01X1655512Y944429D02*
X1653150D01*
G01X1656890Y939744D02*
X1651772D01*
G01X1665157Y939705D02*
X1643504D01*
G01X1658268Y936752D02*
X1650394D01*
G01Y935177D02*
X1658268D01*
G01X1655512Y933799D02*
X1653150D01*
G01Y931831D02*
X1655512D01*
G01X1657677Y930059D02*
X1650984D01*
G01X1663189Y929272D02*
X1645472D01*
G01X1646369Y1008191D02*
X1646357Y1008189D01*
G01X1646379Y1008196D02*
X1646369Y1008191D01*
G01Y1005041D02*
X1646357Y1005039D01*
G01X1646379Y1005046D02*
X1646369Y1005041D01*
G01Y1001892D02*
X1646357Y1001890D01*
G01X1646379Y1001896D02*
X1646369Y1001892D01*
G01Y998742D02*
X1646357Y998740D01*
G01X1646379Y998747D02*
X1646369Y998742D01*
G01Y995593D02*
X1646357Y995591D01*
G01X1646379Y995597D02*
X1646369Y995593D01*
G01X1645416Y990453D02*
X1645411Y990433D01*
G01X1645431Y990467D02*
X1645416Y990453D01*
G01X1645450Y990472D02*
X1645431Y990467D01*
G01X1645416Y993602D02*
X1645411Y993583D01*
G01X1645431Y993617D02*
X1645416Y993602D01*
G01X1645450Y993622D02*
X1645431Y993617D01*
G01X1645416Y996752D02*
X1645411Y996732D01*
G01X1645431Y996766D02*
X1645416Y996752D01*
G01X1645450Y996772D02*
X1645431Y996766D01*
G01X1645416Y999902D02*
X1645411Y999882D01*
G01X1645431Y999916D02*
X1645416Y999902D01*
G01X1645450Y999921D02*
X1645431Y999916D01*
G01X1645416Y1003051D02*
X1645411Y1003031D01*
G01X1645431Y1003065D02*
X1645416Y1003051D01*
G01X1645450Y1003071D02*
X1645431Y1003065D01*
G01X1645416Y1006201D02*
X1645411Y1006181D01*
G01X1645431Y1006215D02*
X1645416Y1006201D01*
G01X1645450Y1006220D02*
X1645431Y1006215D01*
G01X1645416Y1009350D02*
X1645411Y1009331D01*
G01X1645431Y1009365D02*
X1645416Y1009350D01*
G01X1645450Y1009370D02*
X1645431Y1009365D01*
G01X1646391Y989311D02*
X1646396Y989331D01*
G01X1646376Y989296D02*
X1646391Y989311D01*
G01X1646357Y989291D02*
X1646376Y989296D01*
G01X1646391Y992461D02*
X1646396Y992480D01*
G01X1646376Y992446D02*
X1646391Y992461D01*
G01X1646357Y992441D02*
X1646376Y992446D01*
G01X1646391Y995610D02*
X1646396Y995630D01*
G01X1646376Y995596D02*
X1646391Y995610D01*
G01X1646357Y995591D02*
X1646376Y995596D01*
G01X1646391Y998760D02*
X1646396Y998780D01*
G01X1646376Y998745D02*
X1646391Y998760D01*
G01X1646357Y998740D02*
X1646376Y998745D01*
G01X1646391Y1001909D02*
X1646396Y1001929D01*
G01X1646376Y1001895D02*
X1646391Y1001909D01*
G01X1646357Y1001890D02*
X1646376Y1001895D01*
G01X1646391Y1005059D02*
X1646396Y1005079D01*
G01X1646376Y1005044D02*
X1646391Y1005059D01*
G01X1646357Y1005039D02*
X1646376Y1005044D01*
G01X1646391Y1008209D02*
X1646396Y1008228D01*
G01X1646376Y1008194D02*
X1646391Y1008209D01*
G01X1646357Y1008189D02*
X1646376Y1008194D01*
G01X1646369Y992443D02*
X1646357Y992441D01*
G01X1646379Y992448D02*
X1646369Y992443D01*
G01Y989293D02*
X1646357Y989291D01*
G01X1646379Y989298D02*
X1646369Y989293D01*
G01X1646395Y1008202D02*
X1646398Y1008215D01*
G01X1646389Y1008191D02*
X1646395Y1008202D01*
G01X1646378Y1008183D02*
X1646389Y1008191D01*
G01X1646395Y1001903D02*
X1646398Y1001915D01*
G01X1646389Y1001892D02*
X1646395Y1001903D01*
G01X1646378Y1001884D02*
X1646389Y1001892D01*
G01X1646395Y998754D02*
X1646398Y998766D01*
G01X1646389Y998742D02*
X1646395Y998754D01*
G01X1646378Y998734D02*
X1646389Y998742D01*
G01X1646395Y995604D02*
X1646398Y995616D01*
G01X1646389Y995593D02*
X1646395Y995604D01*
G01X1646378Y995585D02*
X1646389Y995593D01*
G01X1646395Y992454D02*
X1646398Y992467D01*
G01X1646389Y992443D02*
X1646395Y992454D01*
G01X1646378Y992435D02*
X1646389Y992443D01*
G01X1646395Y989305D02*
X1646398Y989317D01*
G01X1646389Y989293D02*
X1646395Y989305D01*
G01X1646378Y989285D02*
X1646389Y989293D01*
G01X1645452Y1009375D02*
Y1009381D01*
G01Y1009371D02*
Y1009375D01*
G01X1645450Y1009370D02*
X1645452Y1009371D01*
G01Y1006225D02*
Y1006231D01*
G01Y1006222D02*
Y1006225D01*
G01X1645450Y1006220D02*
X1645452Y1006222D01*
G01Y1003076D02*
Y1003082D01*
G01Y1003072D02*
Y1003076D01*
G01X1645450Y1003071D02*
X1645452Y1003072D01*
G01Y999926D02*
Y999932D01*
G01Y999922D02*
Y999926D01*
G01X1645450Y999921D02*
X1645452Y999922D01*
G01Y996776D02*
Y996783D01*
G01Y996773D02*
Y996776D01*
G01X1645450Y996772D02*
X1645452Y996773D01*
G01Y993627D02*
Y993633D01*
G01Y993623D02*
Y993627D01*
G01X1645450Y993622D02*
X1645452Y993623D01*
G01Y990477D02*
Y990483D01*
G01Y990474D02*
Y990477D01*
G01X1645450Y990472D02*
X1645452Y990474D01*
G01X1645414Y1009350D02*
X1645413Y1009344D01*
G01X1645416Y1009357D02*
X1645414Y1009350D01*
G01X1645419Y1009363D02*
X1645416Y1009357D01*
G01X1645422Y1009368D02*
X1645419Y1009363D01*
G01X1645427Y1009372D02*
X1645422Y1009368D01*
G01X1645433Y1009376D02*
X1645427Y1009372D01*
G01X1645414Y1006201D02*
X1645413Y1006194D01*
G01X1645416Y1006207D02*
X1645414Y1006201D01*
G01X1645419Y1006213D02*
X1645416Y1006207D01*
G01X1645422Y1006218D02*
X1645419Y1006213D01*
G01X1645427Y1006223D02*
X1645422Y1006218D01*
G01X1645433Y1006226D02*
X1645427Y1006223D01*
G01X1645414Y1003051D02*
X1645413Y1003045D01*
G01X1645416Y1003057D02*
X1645414Y1003051D01*
G01X1645419Y1003063D02*
X1645416Y1003057D01*
G01X1645422Y1003069D02*
X1645419Y1003063D01*
G01X1645427Y1003073D02*
X1645422Y1003069D01*
G01X1645433Y1003077D02*
X1645427Y1003073D01*
G01X1645414Y999902D02*
X1645413Y999895D01*
G01X1645416Y999908D02*
X1645414Y999902D01*
G01X1645419Y999914D02*
X1645416Y999908D01*
G01X1645422Y999919D02*
X1645419Y999914D01*
G01X1645427Y999924D02*
X1645422Y999919D01*
G01X1645433Y999927D02*
X1645427Y999924D01*
G01X1645414Y996752D02*
X1645413Y996746D01*
G01X1645416Y996758D02*
X1645414Y996752D01*
G01X1645419Y996764D02*
X1645416Y996758D01*
G01X1645422Y996769D02*
X1645419Y996764D01*
G01X1645427Y996774D02*
X1645422Y996769D01*
G01X1645433Y996778D02*
X1645427Y996774D01*
G01X1645414Y993602D02*
X1645413Y993596D01*
G01X1645416Y993609D02*
X1645414Y993602D01*
G01X1645419Y993615D02*
X1645416Y993609D01*
G01X1645422Y993620D02*
X1645419Y993615D01*
G01X1645427Y993624D02*
X1645422Y993620D01*
G01X1645433Y993628D02*
X1645427Y993624D01*
G01X1645414Y990453D02*
X1645413Y990446D01*
G01X1645416Y990459D02*
X1645414Y990453D01*
G01X1645419Y990465D02*
X1645416Y990459D01*
G01X1645422Y990470D02*
X1645419Y990465D01*
G01X1645427Y990475D02*
X1645422Y990470D01*
G01X1645433Y990478D02*
X1645427Y990475D01*
G01X1646397Y1005058D02*
X1646398Y1005065D01*
G01X1646394Y1005051D02*
X1646397Y1005058D01*
G01X1646391Y1005044D02*
X1646394Y1005051D01*
G01X1646386Y1005039D02*
X1646391Y1005044D01*
G01X1646380Y1005034D02*
X1646386Y1005039D01*
G01X1646373Y1005031D02*
X1646380Y1005034D01*
G01X1646366Y1005029D02*
X1646373Y1005031D01*
G01X1646358Y1005028D02*
X1646366Y1005029D01*
G01X1646375Y989283D02*
X1646378Y989285D01*
G01X1646372Y989282D02*
X1646375Y989283D01*
G01X1646369Y989281D02*
X1646372Y989282D01*
G01X1646365Y989281D02*
X1646369D01*
G01X1646362Y989280D02*
X1646365Y989281D01*
G01X1646358Y989280D02*
X1646362D01*
G01X1645436Y990480D02*
X1645433Y990478D01*
G01X1645439Y990481D02*
X1645436Y990480D01*
G01X1645443Y990482D02*
X1645439Y990481D01*
G01X1645446Y990483D02*
X1645443Y990482D01*
G01X1645449Y990483D02*
X1645446D01*
G01X1645453D02*
X1645449D01*
G01X1646375Y992433D02*
X1646378Y992435D01*
G01X1646372Y992432D02*
X1646375Y992433D01*
G01X1646369Y992431D02*
X1646372Y992432D01*
G01X1646365Y992430D02*
X1646369Y992431D01*
G01X1646362Y992430D02*
X1646365D01*
G01X1646358D02*
X1646362D01*
G01X1645436Y993630D02*
X1645433Y993628D01*
G01X1645439Y993631D02*
X1645436Y993630D01*
G01X1645443Y993632D02*
X1645439Y993631D01*
G01X1645446Y993633D02*
X1645443Y993632D01*
G01X1645449Y993633D02*
X1645446D01*
G01X1645453D02*
X1645449D01*
G01X1646375Y995583D02*
X1646378Y995585D01*
G01X1646372Y995581D02*
X1646375Y995583D01*
G01X1646369Y995581D02*
X1646372D01*
G01X1646365Y995580D02*
X1646369Y995581D01*
G01X1646362Y995580D02*
X1646365D01*
G01X1646358Y995579D02*
X1646362Y995580D01*
G01X1645436Y996779D02*
X1645433Y996778D01*
G01X1645439Y996780D02*
X1645436Y996779D01*
G01X1645443Y996781D02*
X1645439Y996780D01*
G01X1645446Y996782D02*
X1645443Y996781D01*
G01X1645449Y996783D02*
X1645446Y996782D01*
G01X1645453Y996783D02*
X1645449D01*
G01X1646375Y998732D02*
X1646378Y998734D01*
G01X1646372Y998731D02*
X1646375Y998732D01*
G01X1646369Y998730D02*
X1646372Y998731D01*
G01X1646365Y998730D02*
X1646369D01*
G01X1646362Y998729D02*
X1646365Y998730D01*
G01X1646358Y998729D02*
X1646362D01*
G01X1645436Y999929D02*
X1645433Y999927D01*
G01X1645439Y999930D02*
X1645436Y999929D01*
G01X1645443Y999931D02*
X1645439Y999930D01*
G01X1645446Y999932D02*
X1645443Y999931D01*
G01X1645449Y999932D02*
X1645446D01*
G01X1645453D02*
X1645449D01*
G01X1646375Y1001882D02*
X1646378Y1001884D01*
G01X1646372Y1001881D02*
X1646375Y1001882D01*
G01X1646369Y1001880D02*
X1646372Y1001881D01*
G01X1646365Y1001879D02*
X1646369Y1001880D01*
G01X1646362Y1001879D02*
X1646365D01*
G01X1646358Y1001878D02*
X1646362Y1001879D01*
G01X1645436Y1003078D02*
X1645433Y1003077D01*
G01X1645439Y1003080D02*
X1645436Y1003078D01*
G01X1645443Y1003081D02*
X1645439Y1003080D01*
G01X1645446Y1003081D02*
X1645443D01*
G01X1645449Y1003082D02*
X1645446Y1003081D01*
G01X1645453Y1003082D02*
X1645449D01*
G01X1645436Y1006228D02*
X1645433Y1006226D01*
G01X1645439Y1006229D02*
X1645436Y1006228D01*
G01X1645443Y1006230D02*
X1645439Y1006229D01*
G01X1645446Y1006231D02*
X1645443Y1006230D01*
G01X1645449Y1006231D02*
X1645446D01*
G01X1645453D02*
X1645449D01*
G01X1646375Y1008181D02*
X1646378Y1008183D01*
G01X1646372Y1008180D02*
X1646375Y1008181D01*
G01X1646369Y1008179D02*
X1646372Y1008180D01*
G01X1646365Y1008178D02*
X1646369Y1008179D01*
G01X1646362Y1008178D02*
X1646365D01*
G01X1646358D02*
X1646362D01*
G01X1645436Y1009378D02*
X1645433Y1009376D01*
G01X1645439Y1009379D02*
X1645436Y1009378D01*
G01X1645443Y1009380D02*
X1645439Y1009379D01*
G01X1645446Y1009381D02*
X1645443Y1009380D01*
G01X1645449Y1009381D02*
X1645446D01*
G01X1645453D02*
X1645449D01*
G01X1645413Y1009337D02*
Y1009344D01*
G01X1645412Y1009332D02*
X1645413Y1009337D01*
G01X1645411Y1009331D02*
X1645412Y1009332D01*
G01X1645413Y1006187D02*
Y1006194D01*
G01X1645412Y1006183D02*
X1645413Y1006187D01*
G01X1645411Y1006181D02*
X1645412Y1006183D01*
G01X1645413Y1003037D02*
Y1003045D01*
G01X1645412Y1003033D02*
X1645413Y1003037D01*
G01X1645411Y1003031D02*
X1645412Y1003033D01*
G01X1646388Y990471D02*
X1646392Y990465D01*
G01X1646383Y990475D02*
X1646388Y990471D01*
G01X1646378Y990479D02*
X1646383Y990475D01*
G01X1646372Y990481D02*
X1646378Y990479D01*
G01X1646365Y990483D02*
X1646372Y990481D01*
G01X1646358Y990483D02*
X1646365D01*
G01X1646388Y993620D02*
X1646392Y993615D01*
G01X1646383Y993625D02*
X1646388Y993620D01*
G01X1646378Y993628D02*
X1646383Y993625D01*
G01X1646372Y993631D02*
X1646378Y993628D01*
G01X1646365Y993633D02*
X1646372Y993631D01*
G01X1646358Y993633D02*
X1646365D01*
G01X1646388Y996770D02*
X1646392Y996765D01*
G01X1646383Y996774D02*
X1646388Y996770D01*
G01X1646378Y996778D02*
X1646383Y996774D01*
G01X1646372Y996781D02*
X1646378Y996778D01*
G01X1646365Y996782D02*
X1646372Y996781D01*
G01X1646358Y996783D02*
X1646365Y996782D01*
G01X1646388Y999920D02*
X1646392Y999914D01*
G01X1646383Y999924D02*
X1646388Y999920D01*
G01X1646378Y999928D02*
X1646383Y999924D01*
G01X1646372Y999930D02*
X1646378Y999928D01*
G01X1646365Y999932D02*
X1646372Y999930D01*
G01X1646358Y999932D02*
X1646365D01*
G01X1646388Y1003069D02*
X1646392Y1003064D01*
G01X1646383Y1003074D02*
X1646388Y1003069D01*
G01X1646378Y1003077D02*
X1646383Y1003074D01*
G01X1646372Y1003080D02*
X1646378Y1003077D01*
G01X1646365Y1003081D02*
X1646372Y1003080D01*
G01X1646358Y1003082D02*
X1646365Y1003081D01*
G01X1646388Y1006219D02*
X1646392Y1006213D01*
G01X1646383Y1006223D02*
X1646388Y1006219D01*
G01X1646378Y1006227D02*
X1646383Y1006223D01*
G01X1646372Y1006230D02*
X1646378Y1006227D01*
G01X1646365Y1006231D02*
X1646372Y1006230D01*
G01X1646358Y1006231D02*
X1646365D01*
G01X1646388Y1009369D02*
X1646392Y1009363D01*
G01X1646383Y1009373D02*
X1646388Y1009369D01*
G01X1646378Y1009376D02*
X1646383Y1009373D01*
G01X1646372Y1009379D02*
X1646378Y1009376D01*
G01X1646365Y1009381D02*
X1646372Y1009379D01*
G01X1646358Y1009381D02*
X1646365D01*
G01X1645414Y989310D02*
X1645413Y989317D01*
G01X1645417Y989303D02*
X1645414Y989310D01*
G01X1645420Y989296D02*
X1645417Y989303D01*
G01X1645425Y989291D02*
X1645420Y989296D01*
G01X1645431Y989286D02*
X1645425Y989291D01*
G01X1645438Y989283D02*
X1645431Y989286D01*
G01X1645445Y989281D02*
X1645438Y989283D01*
G01X1645453Y989280D02*
X1645445Y989281D01*
G01X1645414Y992459D02*
X1645413Y992467D01*
G01X1645417Y992452D02*
X1645414Y992459D01*
G01X1645420Y992446D02*
X1645417Y992452D01*
G01X1645425Y992441D02*
X1645420Y992446D01*
G01X1645431Y992436D02*
X1645425Y992441D01*
G01X1645438Y992432D02*
X1645431Y992436D01*
G01X1645445Y992430D02*
X1645438Y992432D01*
G01X1645453Y992430D02*
X1645445D01*
G01X1645414Y995609D02*
X1645413Y995616D01*
G01X1645417Y995602D02*
X1645414Y995609D01*
G01X1645420Y995596D02*
X1645417Y995602D01*
G01X1645425Y995590D02*
X1645420Y995596D01*
G01X1645431Y995585D02*
X1645425Y995590D01*
G01X1645438Y995582D02*
X1645431Y995585D01*
G01X1645445Y995580D02*
X1645438Y995582D01*
G01X1645453Y995579D02*
X1645445Y995580D01*
G01X1645414Y998759D02*
X1645413Y998766D01*
G01X1645417Y998752D02*
X1645414Y998759D01*
G01X1645420Y998745D02*
X1645417Y998752D01*
G01X1645425Y998740D02*
X1645420Y998745D01*
G01X1645431Y998735D02*
X1645425Y998740D01*
G01X1645438Y998731D02*
X1645431Y998735D01*
G01X1645445Y998730D02*
X1645438Y998731D01*
G01X1645453Y998729D02*
X1645445Y998730D01*
G01X1645414Y1001908D02*
X1645413Y1001915D01*
G01X1645417Y1001901D02*
X1645414Y1001908D01*
G01X1645420Y1001895D02*
X1645417Y1001901D01*
G01X1645425Y1001889D02*
X1645420Y1001895D01*
G01X1645431Y1001885D02*
X1645425Y1001889D01*
G01X1645438Y1001881D02*
X1645431Y1001885D01*
G01X1645445Y1001879D02*
X1645438Y1001881D01*
G01X1645453Y1001878D02*
X1645445Y1001879D01*
G01X1645414Y1005058D02*
X1645413Y1005065D01*
G01X1645417Y1005051D02*
X1645414Y1005058D01*
G01X1645420Y1005044D02*
X1645417Y1005051D01*
G01X1645425Y1005039D02*
X1645420Y1005044D01*
G01X1645431Y1005034D02*
X1645425Y1005039D01*
G01X1645438Y1005031D02*
X1645431Y1005034D01*
G01X1645445Y1005029D02*
X1645438Y1005031D01*
G01X1645453Y1005028D02*
X1645445Y1005029D01*
G01X1645414Y1008207D02*
X1645413Y1008215D01*
G01X1645417Y1008200D02*
X1645414Y1008207D01*
G01X1645420Y1008194D02*
X1645417Y1008200D01*
G01X1645425Y1008189D02*
X1645420Y1008194D01*
G01X1645431Y1008184D02*
X1645425Y1008189D01*
G01X1645438Y1008180D02*
X1645431Y1008184D01*
G01X1645445Y1008178D02*
X1645438Y1008180D01*
G01X1645453Y1008178D02*
X1645445D01*
G01X1646367Y990471D02*
X1646377Y990467D01*
G01X1646357Y990472D02*
X1646367Y990471D01*
G01Y993620D02*
X1646377Y993617D01*
G01X1646357Y993622D02*
X1646367Y993620D01*
G01Y996770D02*
X1646377Y996766D01*
G01X1646357Y996772D02*
X1646367Y996770D01*
G01Y999920D02*
X1646377Y999916D01*
G01X1646357Y999921D02*
X1646367Y999920D01*
G01Y1003069D02*
X1646377Y1003065D01*
G01X1646357Y1003071D02*
X1646367Y1003069D01*
G01Y1006219D02*
X1646377Y1006215D01*
G01X1646357Y1006220D02*
X1646367Y1006219D01*
G01Y1009369D02*
X1646377Y1009365D01*
G01X1646357Y1009370D02*
X1646367Y1009369D01*
G01X1659823Y1046134D02*
Y1046125D01*
G01X1659824Y1046140D02*
X1659823Y1046134D01*
G01X1659826Y1046142D02*
X1659824Y1046140D01*
G01X1659823Y1041134D02*
Y1041125D01*
G01X1659824Y1041140D02*
X1659823Y1041134D01*
G01X1659826Y1041142D02*
X1659824Y1041140D01*
G01X1659823Y1036134D02*
Y1036125D01*
G01X1659824Y1036140D02*
X1659823Y1036134D01*
G01X1659826Y1036142D02*
X1659824Y1036140D01*
G01X1659823Y1031134D02*
Y1031125D01*
G01X1659824Y1031140D02*
X1659823Y1031134D01*
G01X1659826Y1031142D02*
X1659824Y1031140D01*
G01X1659823Y1026134D02*
Y1026125D01*
G01X1659824Y1026140D02*
X1659823Y1026134D01*
G01X1659826Y1026142D02*
X1659824Y1026140D01*
G01X1659823Y1021134D02*
Y1021125D01*
G01X1659824Y1021140D02*
X1659823Y1021134D01*
G01X1659826Y1021142D02*
X1659824Y1021140D01*
G01X1659823Y1016134D02*
Y1016125D01*
G01X1659824Y1016140D02*
X1659823Y1016134D01*
G01X1659826Y1016142D02*
X1659824Y1016140D01*
G01X1659823Y1011134D02*
Y1011125D01*
G01X1659824Y1011140D02*
X1659823Y1011134D01*
G01X1659826Y1011142D02*
X1659824Y1011140D01*
G01X1659823Y986134D02*
Y986125D01*
G01X1659824Y986140D02*
X1659823Y986134D01*
G01X1659826Y986142D02*
X1659824Y986140D01*
G01X1659823Y981134D02*
Y981125D01*
G01X1659824Y981140D02*
X1659823Y981134D01*
G01X1659826Y981142D02*
X1659824Y981140D01*
G01X1659823Y976134D02*
Y976125D01*
G01X1659824Y976140D02*
X1659823Y976134D01*
G01X1659826Y976142D02*
X1659824Y976140D01*
G01X1659823Y971134D02*
Y971125D01*
G01X1659824Y971140D02*
X1659823Y971134D01*
G01X1659826Y971142D02*
X1659824Y971140D01*
G01X1659823Y966134D02*
Y966125D01*
G01X1659824Y966140D02*
X1659823Y966134D01*
G01X1659826Y966142D02*
X1659824Y966140D01*
G01X1659823Y961134D02*
Y961125D01*
G01X1659824Y961140D02*
X1659823Y961134D01*
G01X1659826Y961142D02*
X1659824Y961140D01*
G01X1659823Y956134D02*
Y956125D01*
G01X1659824Y956140D02*
X1659823Y956134D01*
G01X1659826Y956142D02*
X1659824Y956140D01*
G01X1645413Y999888D02*
Y999895D01*
G01X1645412Y999883D02*
X1645413Y999888D01*
G01X1645411Y999882D02*
X1645412Y999883D01*
G01X1645413Y996738D02*
Y996746D01*
G01X1645412Y996734D02*
X1645413Y996738D01*
G01X1645411Y996732D02*
X1645412Y996734D01*
G01X1645413Y993589D02*
Y993596D01*
G01X1645412Y993584D02*
X1645413Y993589D01*
G01X1645411Y993583D02*
X1645412Y993584D01*
G01X1645413Y990439D02*
Y990446D01*
G01X1645412Y990435D02*
X1645413Y990439D01*
G01X1645411Y990433D02*
X1645412Y990435D01*
G01X1659810Y957511D02*
X1659821Y957496D01*
G01X1659786Y957520D02*
X1659810Y957511D01*
G01Y962511D02*
X1659821Y962496D01*
G01X1659786Y962520D02*
X1659810Y962511D01*
G01X1645413Y992474D02*
Y992467D01*
G01X1645412Y992479D02*
X1645413Y992474D01*
G01X1645411Y992477D02*
X1645412Y992479D01*
G01X1646358Y1009375D02*
Y1009381D01*
G01X1646357Y1009371D02*
X1646358Y1009375D01*
G01X1646357Y1009370D02*
Y1009371D01*
G01X1646358Y1006226D02*
Y1006231D01*
G01X1646357Y1006222D02*
X1646358Y1006226D01*
G01X1646357Y1006220D02*
Y1006222D01*
G01X1646358Y1003076D02*
Y1003082D01*
G01X1646357Y1003072D02*
X1646358Y1003076D01*
G01X1646357Y1003071D02*
Y1003072D01*
G01X1646358Y999926D02*
Y999932D01*
G01X1646357Y999922D02*
X1646358Y999926D01*
G01X1646357Y999921D02*
Y999922D01*
G01X1646358Y996777D02*
Y996783D01*
G01X1646357Y996773D02*
X1646358Y996777D01*
G01X1646357Y996772D02*
Y996773D01*
G01X1646358Y993627D02*
Y993633D01*
G01X1646357Y993623D02*
X1646358Y993627D01*
G01X1646357Y993622D02*
Y993623D01*
G01X1646358Y990478D02*
Y990483D01*
G01X1646357Y990474D02*
X1646358Y990478D01*
G01X1646357Y990472D02*
Y990474D01*
G01X1645413Y992470D02*
Y992467D01*
G01X1645415Y992464D02*
X1645413Y992470D01*
G01X1645427Y992449D02*
X1645415Y992464D01*
G01X1645452Y992441D02*
X1645427Y992449D01*
G01X1645413Y995620D02*
Y995616D01*
G01X1645415Y995614D02*
X1645413Y995620D01*
G01X1645426Y995599D02*
X1645415Y995614D01*
G01X1645451Y995591D02*
X1645426Y995599D01*
G01X1645413Y1001919D02*
Y1001915D01*
G01X1645415Y1001913D02*
X1645413Y1001919D01*
G01X1645426Y1001898D02*
X1645415Y1001913D01*
G01X1645451Y1001890D02*
X1645426Y1001898D01*
G01X1645413Y1005069D02*
Y1005065D01*
G01X1645415Y1005063D02*
X1645413Y1005069D01*
G01X1645426Y1005048D02*
X1645415Y1005063D01*
G01X1645451Y1005039D02*
X1645426Y1005048D01*
G01X1645413Y989321D02*
Y989317D01*
G01X1645415Y989315D02*
X1645413Y989321D01*
G01X1645426Y989300D02*
X1645415Y989315D01*
G01X1645451Y989291D02*
X1645426Y989300D01*
G01X1645413Y1008219D02*
Y1008215D01*
G01X1645415Y1008213D02*
X1645413Y1008219D01*
G01X1645426Y1008197D02*
X1645415Y1008213D01*
G01X1645451Y1008189D02*
X1645426Y1008197D01*
G01X1659810Y967511D02*
X1659821Y967496D01*
G01X1659786Y967520D02*
X1659810Y967511D01*
G01Y972511D02*
X1659821Y972496D01*
G01X1659786Y972520D02*
X1659810Y972511D01*
G01Y977511D02*
X1659821Y977496D01*
G01X1659786Y977520D02*
X1659810Y977511D01*
G01Y982511D02*
X1659821Y982496D01*
G01X1659786Y982520D02*
X1659810Y982511D01*
G01Y987511D02*
X1659821Y987496D01*
G01X1659786Y987520D02*
X1659810Y987511D01*
G01Y1012511D02*
X1659821Y1012496D01*
G01X1659786Y1012520D02*
X1659810Y1012511D01*
G01Y1017511D02*
X1659821Y1017496D01*
G01X1659786Y1017520D02*
X1659810Y1017511D01*
G01Y1022511D02*
X1659821Y1022496D01*
G01X1659786Y1022520D02*
X1659810Y1022511D01*
G01Y1027511D02*
X1659821Y1027496D01*
G01X1659786Y1027520D02*
X1659810Y1027511D01*
G01Y1032511D02*
X1659821Y1032496D01*
G01X1659786Y1032520D02*
X1659810Y1032511D01*
G01Y1037511D02*
X1659821Y1037496D01*
G01X1659786Y1037520D02*
X1659810Y1037511D01*
G01Y1042511D02*
X1659821Y1042496D01*
G01X1659786Y1042520D02*
X1659810Y1042511D01*
G01Y1047511D02*
X1659821Y1047496D01*
G01X1659786Y1047520D02*
X1659810Y1047511D01*
G01X1645413Y998770D02*
Y998766D01*
G01X1645415Y998764D02*
X1645413Y998770D01*
G01X1645425Y998750D02*
X1645415Y998764D01*
G01X1645448Y998740D02*
X1645425Y998750D01*
G01X1646398Y1009337D02*
Y1009344D01*
G01X1646397Y1009332D02*
X1646398Y1009337D01*
G01X1646396Y1009331D02*
X1646397Y1009332D01*
G01X1646398Y1006187D02*
Y1006194D01*
G01X1646397Y1006183D02*
X1646398Y1006187D01*
G01X1646396Y1006181D02*
X1646397Y1006183D01*
G01X1646398Y1003038D02*
Y1003045D01*
G01X1646397Y1003033D02*
X1646398Y1003038D01*
G01X1646396Y1003031D02*
X1646397Y1003033D01*
G01X1646398Y999888D02*
Y999895D01*
G01X1646397Y999883D02*
X1646398Y999888D01*
G01X1646396Y999882D02*
X1646397Y999883D01*
G01X1646398Y996739D02*
Y996746D01*
G01X1646397Y996734D02*
X1646398Y996739D01*
G01X1646396Y996732D02*
X1646397Y996734D01*
G01X1646398Y993589D02*
Y993596D01*
G01X1646397Y993584D02*
X1646398Y993589D01*
G01X1646396Y993583D02*
X1646397Y993584D01*
G01X1646398Y990439D02*
Y990446D01*
G01X1646397Y990435D02*
X1646398Y990439D01*
G01X1646396Y990433D02*
X1646397Y990435D01*
G01X1645413Y998774D02*
Y998766D01*
G01X1645412Y998778D02*
X1645413Y998774D01*
G01X1645411Y998775D02*
X1645412Y998778D01*
G01X1646366Y996770D02*
X1646357Y996772D01*
G01X1646375Y996767D02*
X1646366Y996770D01*
G01X1646383Y996762D02*
X1646375Y996767D01*
G01X1646366Y990471D02*
X1646357Y990472D01*
G01X1646375Y990468D02*
X1646366Y990471D01*
G01X1646383Y990463D02*
X1646375Y990468D01*
G01X1646366Y993621D02*
X1646357Y993622D01*
G01X1646375Y993618D02*
X1646366Y993621D01*
G01X1646383Y993612D02*
X1646375Y993618D01*
G01X1646366Y999920D02*
X1646357Y999921D01*
G01X1646375Y999917D02*
X1646366Y999920D01*
G01X1646383Y999911D02*
X1646375Y999917D01*
G01X1646366Y1003070D02*
X1646357Y1003071D01*
G01X1646375Y1003067D02*
X1646366Y1003070D01*
G01X1646383Y1003061D02*
X1646375Y1003067D01*
G01X1646366Y1006219D02*
X1646357Y1006220D01*
G01X1646375Y1006216D02*
X1646366Y1006219D01*
G01X1646383Y1006211D02*
X1646375Y1006216D01*
G01X1646366Y1009369D02*
X1646357Y1009370D01*
G01X1646375Y1009366D02*
X1646366Y1009369D01*
G01X1646383Y1009360D02*
X1646375Y1009366D01*
G01X1645450Y1008017D02*
X1645449Y1008031D01*
G01X1645454Y1008005D02*
X1645450Y1008017D01*
G01X1645453Y1007992D02*
X1645454Y1008005D01*
G01X1645450Y1004868D02*
X1645449Y1004881D01*
G01X1645454Y1004855D02*
X1645450Y1004868D01*
G01X1645453Y1004843D02*
X1645454Y1004855D01*
G01X1645450Y1001718D02*
X1645449Y1001732D01*
G01X1645454Y1001706D02*
X1645450Y1001718D01*
G01X1645453Y1001693D02*
X1645454Y1001706D01*
G01X1645450Y998569D02*
X1645449Y998582D01*
G01X1645454Y998556D02*
X1645450Y998569D01*
G01X1645453Y998543D02*
X1645454Y998556D01*
G01X1645450Y995419D02*
X1645449Y995433D01*
G01X1645454Y995406D02*
X1645450Y995419D01*
G01X1645453Y995394D02*
X1645454Y995406D01*
G01X1645450Y992269D02*
X1645449Y992283D01*
G01X1645454Y992257D02*
X1645450Y992269D01*
G01X1645453Y992244D02*
X1645454Y992257D01*
G01X1645450Y989120D02*
X1645449Y989133D01*
G01X1645454Y989107D02*
X1645450Y989120D01*
G01X1645453Y989094D02*
X1645454Y989107D01*
G01X1646361Y1009541D02*
X1646362Y1009528D01*
G01X1646357Y1009554D02*
X1646361Y1009541D01*
G01X1646358Y1009567D02*
X1646357Y1009554D01*
G01X1646361Y1006392D02*
X1646362Y1006378D01*
G01X1646357Y1006405D02*
X1646361Y1006392D01*
G01X1646358Y1006417D02*
X1646357Y1006405D01*
G01X1646361Y1003242D02*
X1646362Y1003228D01*
G01X1646357Y1003255D02*
X1646361Y1003242D01*
G01X1646358Y1003268D02*
X1646357Y1003255D01*
G01X1646361Y1000093D02*
X1646362Y1000079D01*
G01X1646357Y1000106D02*
X1646361Y1000093D01*
G01X1646358Y1000118D02*
X1646357Y1000106D01*
G01X1646361Y996943D02*
X1646362Y996929D01*
G01X1646357Y996956D02*
X1646361Y996943D01*
G01X1646358Y996969D02*
X1646357Y996956D01*
G01X1646361Y993793D02*
X1646362Y993780D01*
G01X1646357Y993806D02*
X1646361Y993793D01*
G01X1646358Y993819D02*
X1646357Y993806D01*
G01X1646361Y990644D02*
X1646362Y990630D01*
G01X1646357Y990657D02*
X1646361Y990644D01*
G01X1646358Y990669D02*
X1646357Y990657D01*
G01X1645413Y995624D02*
Y995617D01*
G01X1645412Y995628D02*
X1645413Y995624D01*
G01X1645412Y995621D02*
Y995628D01*
G01X1645413Y1005073D02*
Y1005065D01*
G01X1645412Y1005077D02*
X1645413Y1005073D01*
G01X1645412Y1005070D02*
Y1005077D01*
G01X1646357Y1008005D02*
X1646358Y1007992D01*
G01X1646360Y1008017D02*
X1646357Y1008005D01*
G01X1646361Y1008031D02*
X1646360Y1008017D01*
G01X1646357Y1004855D02*
X1646358Y1004843D01*
G01X1646360Y1004868D02*
X1646357Y1004855D01*
G01X1646361Y1004881D02*
X1646360Y1004868D01*
G01X1646357Y1001706D02*
X1646358Y1001693D01*
G01X1646360Y1001718D02*
X1646357Y1001706D01*
G01X1646361Y1001732D02*
X1646360Y1001718D01*
G01X1646357Y998556D02*
X1646358Y998543D01*
G01X1646360Y998569D02*
X1646357Y998556D01*
G01X1646361Y998582D02*
X1646360Y998569D01*
G01X1646357Y995406D02*
X1646358Y995394D01*
G01X1646360Y995419D02*
X1646357Y995406D01*
G01X1646361Y995433D02*
X1646360Y995419D01*
G01X1646357Y992257D02*
X1646358Y992244D01*
G01X1646360Y992269D02*
X1646357Y992257D01*
G01X1646361Y992283D02*
X1646360Y992269D01*
G01X1646357Y989107D02*
X1646358Y989094D01*
G01X1646360Y989120D02*
X1646357Y989107D01*
G01X1646361Y989133D02*
X1646360Y989120D01*
G01X1645413Y989325D02*
Y989317D01*
G01X1645412Y989329D02*
X1645413Y989325D01*
G01X1645412Y989323D02*
Y989329D01*
G01X1645426Y1009361D02*
X1645450Y1009370D01*
G01X1645415Y1009347D02*
X1645426Y1009361D01*
G01X1645413Y1009340D02*
X1645415Y1009347D01*
G01X1645426Y1006212D02*
X1645450Y1006220D01*
G01X1645415Y1006197D02*
X1645426Y1006212D01*
G01X1645413Y1006191D02*
X1645415Y1006197D01*
G01X1645426Y1003062D02*
X1645450Y1003071D01*
G01X1645415Y1003048D02*
X1645426Y1003062D01*
G01X1645413Y1003041D02*
X1645415Y1003048D01*
G01X1645426Y999913D02*
X1645450Y999921D01*
G01X1645415Y999898D02*
X1645426Y999913D01*
G01X1645413Y999891D02*
X1645415Y999898D01*
G01X1645426Y996763D02*
X1645450Y996772D01*
G01X1645415Y996748D02*
X1645426Y996763D01*
G01X1645413Y996742D02*
X1645415Y996748D01*
G01X1645426Y993613D02*
X1645450Y993622D01*
G01X1645415Y993599D02*
X1645426Y993613D01*
G01X1645413Y993592D02*
X1645415Y993599D01*
G01X1645426Y990464D02*
X1645450Y990472D01*
G01X1645415Y990449D02*
X1645426Y990464D01*
G01X1645413Y990443D02*
X1645415Y990449D01*
G01X1645452Y989286D02*
X1645453Y989280D01*
G01X1645452Y989290D02*
Y989286D01*
G01X1645450Y989291D02*
X1645452Y989290D01*
G01Y992436D02*
X1645453Y992430D01*
G01X1645452Y992440D02*
Y992436D01*
G01X1645450Y992441D02*
X1645452Y992440D01*
G01Y995585D02*
X1645453Y995579D01*
G01X1645452Y995589D02*
Y995585D01*
G01X1645450Y995591D02*
X1645452Y995589D01*
G01Y998735D02*
X1645453Y998729D01*
G01X1645452Y998739D02*
Y998735D01*
G01X1645450Y998740D02*
X1645452Y998739D01*
G01Y1001885D02*
X1645453Y1001878D01*
G01X1645452Y1001889D02*
Y1001885D01*
G01X1645450Y1001890D02*
X1645452Y1001889D01*
G01Y1005034D02*
X1645453Y1005028D01*
G01X1645452Y1005038D02*
Y1005034D01*
G01X1645450Y1005039D02*
X1645452Y1005038D01*
G01Y1008184D02*
X1645453Y1008178D01*
G01X1645452Y1008188D02*
Y1008184D01*
G01X1645450Y1008189D02*
X1645452Y1008188D01*
G01X1659823Y957487D02*
Y957494D01*
G01X1659824Y957482D02*
X1659823Y957487D01*
G01X1659825Y957480D02*
X1659824Y957482D01*
G01X1659790Y957618D02*
X1659794Y957717D01*
G01X1659784Y957546D02*
X1659790Y957618D01*
G01X1659786Y957520D02*
X1659784Y957546D01*
G01X1659790Y962618D02*
X1659794Y962717D01*
G01X1659784Y962546D02*
X1659790Y962618D01*
G01X1659786Y962520D02*
X1659784Y962546D01*
G01X1659790Y967618D02*
X1659794Y967717D01*
G01X1659784Y967546D02*
X1659790Y967618D01*
G01X1659786Y967520D02*
X1659784Y967546D01*
G01X1659790Y972618D02*
X1659794Y972717D01*
G01X1659784Y972546D02*
X1659790Y972618D01*
G01X1659786Y972520D02*
X1659784Y972546D01*
G01X1659790Y977618D02*
X1659794Y977717D01*
G01X1659784Y977546D02*
X1659790Y977618D01*
G01X1659786Y977520D02*
X1659784Y977546D01*
G01X1659790Y982618D02*
X1659794Y982717D01*
G01X1659784Y982546D02*
X1659790Y982618D01*
G01X1659786Y982520D02*
X1659784Y982546D01*
G01X1659790Y987618D02*
X1659794Y987717D01*
G01X1659784Y987546D02*
X1659790Y987618D01*
G01X1659786Y987520D02*
X1659784Y987546D01*
G01X1659790Y1012618D02*
X1659794Y1012717D01*
G01X1659784Y1012546D02*
X1659790Y1012618D01*
G01X1659786Y1012520D02*
X1659784Y1012546D01*
G01X1659790Y1017618D02*
X1659794Y1017717D01*
G01X1659784Y1017546D02*
X1659790Y1017618D01*
G01X1659786Y1017520D02*
X1659784Y1017546D01*
G01X1659790Y1022618D02*
X1659794Y1022717D01*
G01X1659784Y1022546D02*
X1659790Y1022618D01*
G01X1659786Y1022520D02*
X1659784Y1022546D01*
G01X1659790Y1027618D02*
X1659794Y1027717D01*
G01X1659784Y1027546D02*
X1659790Y1027618D01*
G01X1659786Y1027520D02*
X1659784Y1027546D01*
G01X1659790Y1032618D02*
X1659794Y1032717D01*
G01X1659784Y1032546D02*
X1659790Y1032618D01*
G01X1659786Y1032520D02*
X1659784Y1032546D01*
G01X1659790Y1037618D02*
X1659794Y1037717D01*
G01X1659784Y1037546D02*
X1659790Y1037618D01*
G01X1659786Y1037520D02*
X1659784Y1037546D01*
G01X1659790Y1042618D02*
X1659794Y1042717D01*
G01X1659784Y1042546D02*
X1659790Y1042618D01*
G01X1659786Y1042520D02*
X1659784Y1042546D01*
G01X1645413Y1001923D02*
Y1001916D01*
G01X1645412Y1001928D02*
X1645413Y1001923D01*
G01Y1001918D02*
X1645412Y1001928D01*
G01X1645454Y1009554D02*
X1645453Y1009567D01*
G01X1645450Y1009541D02*
X1645454Y1009554D01*
G01X1645450Y1009528D02*
Y1009541D01*
G01X1645454Y1006405D02*
X1645453Y1006417D01*
G01X1645450Y1006392D02*
X1645454Y1006405D01*
G01X1645450Y1006378D02*
Y1006392D01*
G01X1645454Y1003255D02*
X1645453Y1003268D01*
G01X1645450Y1003242D02*
X1645454Y1003255D01*
G01X1645450Y1003228D02*
Y1003242D01*
G01X1645454Y1000106D02*
X1645453Y1000118D01*
G01X1645450Y1000093D02*
X1645454Y1000106D01*
G01X1645450Y1000079D02*
Y1000093D01*
G01X1645454Y996956D02*
X1645453Y996969D01*
G01X1645450Y996943D02*
X1645454Y996956D01*
G01X1645450Y996929D02*
Y996943D01*
G01X1645454Y993806D02*
X1645453Y993819D01*
G01X1645450Y993793D02*
X1645454Y993806D01*
G01X1645450Y993780D02*
Y993793D01*
G01X1645454Y990657D02*
X1645453Y990669D01*
G01X1645450Y990644D02*
X1645454Y990657D01*
G01X1645450Y990630D02*
Y990644D01*
G01X1658839Y1046140D02*
X1658840Y1046142D01*
G01X1658839Y1046134D02*
Y1046140D01*
G01Y1046126D02*
Y1046134D01*
G01Y1041140D02*
X1658840Y1041142D01*
G01X1658839Y1041134D02*
Y1041140D01*
G01Y1041126D02*
Y1041134D01*
G01Y1036140D02*
X1658840Y1036142D01*
G01X1658839Y1036134D02*
Y1036140D01*
G01Y1036126D02*
Y1036134D01*
G01Y1031140D02*
X1658840Y1031142D01*
G01X1658839Y1031134D02*
Y1031140D01*
G01Y1031126D02*
Y1031134D01*
G01Y1026140D02*
X1658840Y1026142D01*
G01X1658839Y1026134D02*
Y1026140D01*
G01Y1026126D02*
Y1026134D01*
G01Y1021140D02*
X1658840Y1021142D01*
G01X1658839Y1021134D02*
Y1021140D01*
G01Y1021126D02*
Y1021134D01*
G01Y1016140D02*
X1658840Y1016142D01*
G01X1658839Y1016134D02*
Y1016140D01*
G01Y1016126D02*
Y1016134D01*
G01Y1011140D02*
X1658840Y1011142D01*
G01X1658839Y1011134D02*
Y1011140D01*
G01Y1011126D02*
Y1011134D01*
G01Y986140D02*
X1658840Y986142D01*
G01X1658839Y986134D02*
Y986140D01*
G01Y986126D02*
Y986134D01*
G01Y981140D02*
X1658840Y981142D01*
G01X1658839Y981134D02*
Y981140D01*
G01Y981126D02*
Y981134D01*
G01Y976140D02*
X1658840Y976142D01*
G01X1658839Y976134D02*
Y976140D01*
G01Y976126D02*
Y976134D01*
G01Y971140D02*
X1658840Y971142D01*
G01X1658839Y971134D02*
Y971140D01*
G01Y971126D02*
Y971134D01*
G01Y966140D02*
X1658840Y966142D01*
G01X1658839Y966134D02*
Y966140D01*
G01Y966126D02*
Y966134D01*
G01Y961140D02*
X1658840Y961142D01*
G01X1658839Y961134D02*
Y961140D01*
G01Y961126D02*
Y961134D01*
G01Y956140D02*
X1658840Y956142D01*
G01X1658839Y956134D02*
Y956140D01*
G01Y956126D02*
Y956134D01*
G01X1645413Y1008222D02*
Y1008215D01*
G01X1645412Y1008227D02*
X1645413Y1008222D01*
G01X1645412Y1008219D02*
Y1008227D01*
G01X1659823Y962487D02*
Y962494D01*
G01X1659824Y962482D02*
X1659823Y962487D01*
G01X1659825Y962480D02*
X1659824Y962482D01*
G01X1659823Y967487D02*
Y967494D01*
G01X1659824Y967482D02*
X1659823Y967487D01*
G01X1659825Y967480D02*
X1659824Y967482D01*
G01X1659823Y972487D02*
Y972494D01*
G01X1659824Y972482D02*
X1659823Y972487D01*
G01X1659825Y972480D02*
X1659824Y972482D01*
G01X1659823Y977487D02*
Y977494D01*
G01X1659824Y977482D02*
X1659823Y977487D01*
G01X1659825Y977480D02*
X1659824Y977482D01*
G01X1659823Y982487D02*
Y982494D01*
G01X1659824Y982482D02*
X1659823Y982487D01*
G01X1659825Y982480D02*
X1659824Y982482D01*
G01X1659823Y987487D02*
Y987494D01*
G01X1659824Y987482D02*
X1659823Y987487D01*
G01X1659825Y987480D02*
X1659824Y987482D01*
G01X1659823Y1012487D02*
Y1012494D01*
G01X1659824Y1012482D02*
X1659823Y1012487D01*
G01X1659825Y1012480D02*
X1659824Y1012482D01*
G01X1659823Y1017487D02*
Y1017494D01*
G01X1659824Y1017482D02*
X1659823Y1017487D01*
G01X1659825Y1017480D02*
X1659824Y1017482D01*
G01X1659823Y1022487D02*
Y1022494D01*
G01X1659824Y1022482D02*
X1659823Y1022487D01*
G01X1659825Y1022480D02*
X1659824Y1022482D01*
G01X1659823Y1027487D02*
Y1027494D01*
G01X1659824Y1027482D02*
X1659823Y1027487D01*
G01X1659825Y1027480D02*
X1659824Y1027482D01*
G01X1659823Y1032487D02*
Y1032494D01*
G01X1659824Y1032482D02*
X1659823Y1032487D01*
G01X1659825Y1032480D02*
X1659824Y1032482D01*
G01X1659823Y1037487D02*
Y1037494D01*
G01X1659824Y1037482D02*
X1659823Y1037487D01*
G01X1659825Y1037480D02*
X1659824Y1037482D01*
G01X1659823Y1042487D02*
Y1042494D01*
G01X1659824Y1042482D02*
X1659823Y1042487D01*
G01X1659825Y1042480D02*
X1659824Y1042482D01*
G01Y1047482D02*
X1659823Y1047487D01*
G01X1659825Y1047480D02*
X1659824Y1047482D01*
G01X1645436Y992443D02*
X1645450Y992441D01*
G01X1645425Y992450D02*
X1645436Y992443D01*
G01X1645413Y992469D02*
X1645425Y992450D01*
G01X1645436Y1001892D02*
X1645450Y1001890D01*
G01X1645424Y1001900D02*
X1645436Y1001892D01*
G01X1645413Y1001918D02*
X1645424Y1001900D01*
G01X1645436Y995593D02*
X1645450Y995591D01*
G01X1645424Y995601D02*
X1645436Y995593D01*
G01X1645412Y995621D02*
X1645424Y995601D01*
G01X1645436Y1005042D02*
X1645450Y1005039D01*
G01X1645424Y1005050D02*
X1645436Y1005042D01*
G01X1645412Y1005070D02*
X1645424Y1005050D01*
G01X1646398Y989325D02*
Y989317D01*
G01X1646397Y989329D02*
X1646398Y989325D01*
G01X1646396Y989331D02*
X1646397Y989329D01*
G01X1646398Y992474D02*
Y992467D01*
G01X1646397Y992479D02*
X1646398Y992474D01*
G01X1646396Y992480D02*
X1646397Y992479D01*
G01X1646398Y995624D02*
Y995616D01*
G01X1646397Y995628D02*
X1646398Y995624D01*
G01X1646396Y995630D02*
X1646397Y995628D01*
G01X1646398Y998774D02*
Y998766D01*
G01X1646397Y998778D02*
X1646398Y998774D01*
G01X1646396Y998780D02*
X1646397Y998778D01*
G01X1646398Y1001923D02*
Y1001915D01*
G01X1646397Y1001928D02*
X1646398Y1001923D01*
G01X1646396Y1001929D02*
X1646397Y1001928D01*
G01X1646398Y1005073D02*
Y1005065D01*
G01X1646397Y1005077D02*
X1646398Y1005073D01*
G01X1646396Y1005079D02*
X1646397Y1005077D01*
G01X1646398Y1008222D02*
Y1008215D01*
G01X1646397Y1008227D02*
X1646398Y1008222D01*
G01X1646396Y1008228D02*
X1646397Y1008227D01*
G01X1645436Y1008192D02*
X1645450Y1008189D01*
G01X1645423Y1008200D02*
X1645436Y1008192D01*
G01X1645412Y1008220D02*
X1645423Y1008200D01*
G01X1645435Y989294D02*
X1645450Y989291D01*
G01X1645422Y989303D02*
X1645435Y989294D01*
G01X1645412Y989323D02*
X1645422Y989303D01*
G01X1646397Y990453D02*
X1646398Y990446D01*
G01X1646395Y990459D02*
X1646397Y990453D01*
G01X1646392Y990465D02*
X1646395Y990459D01*
G01X1646397Y993603D02*
X1646398Y993596D01*
G01X1646395Y993609D02*
X1646397Y993603D01*
G01X1646392Y993615D02*
X1646395Y993609D01*
G01X1646397Y996752D02*
X1646398Y996746D01*
G01X1646395Y996759D02*
X1646397Y996752D01*
G01X1646392Y996765D02*
X1646395Y996759D01*
G01X1646397Y999902D02*
X1646398Y999895D01*
G01X1646395Y999908D02*
X1646397Y999902D01*
G01X1646392Y999914D02*
X1646395Y999908D01*
G01X1646397Y1003052D02*
X1646398Y1003045D01*
G01X1646395Y1003058D02*
X1646397Y1003052D01*
G01X1646392Y1003064D02*
X1646395Y1003058D01*
G01X1646397Y1006201D02*
X1646398Y1006194D01*
G01X1646395Y1006207D02*
X1646397Y1006201D01*
G01X1646392Y1006213D02*
X1646395Y1006207D01*
G01X1646397Y1009351D02*
X1646398Y1009344D01*
G01X1646395Y1009357D02*
X1646397Y1009351D01*
G01X1646392Y1009363D02*
X1646395Y1009357D01*
G01X1646359Y989286D02*
Y989280D01*
G01X1646357Y989290D02*
X1646359Y989286D01*
G01X1646357Y989291D02*
Y989290D01*
G01X1646359Y992436D02*
Y992430D01*
G01X1646357Y992439D02*
X1646359Y992436D01*
G01X1646357Y992441D02*
Y992439D01*
G01X1646359Y995585D02*
Y995579D01*
G01X1646357Y995589D02*
X1646359Y995585D01*
G01X1646357Y995591D02*
Y995589D01*
G01X1646359Y998735D02*
Y998729D01*
G01X1646357Y998739D02*
X1646359Y998735D01*
G01X1646357Y998740D02*
Y998739D01*
G01X1646359Y1001885D02*
Y1001878D01*
G01X1646357Y1001888D02*
X1646359Y1001885D01*
G01X1646357Y1001890D02*
Y1001888D01*
G01X1646359Y1008184D02*
Y1008178D01*
G01X1646357Y1008187D02*
X1646359Y1008184D01*
G01X1646357Y1008189D02*
Y1008187D01*
G01X1658839Y957527D02*
Y957536D01*
G01Y957521D02*
Y957527D01*
G01X1658840Y957520D02*
X1658839Y957521D01*
G01Y962527D02*
Y962536D01*
G01Y962521D02*
Y962527D01*
G01X1658840Y962520D02*
X1658839Y962521D01*
G01Y967527D02*
Y967536D01*
G01Y967521D02*
Y967527D01*
G01X1658840Y967520D02*
X1658839Y967521D01*
G01Y972527D02*
Y972536D01*
G01Y972521D02*
Y972527D01*
G01X1658840Y972520D02*
X1658839Y972521D01*
G01Y977527D02*
Y977536D01*
G01Y977521D02*
Y977527D01*
G01X1658840Y977520D02*
X1658839Y977521D01*
G01Y982527D02*
Y982536D01*
G01Y982521D02*
Y982527D01*
G01X1658840Y982520D02*
X1658839Y982521D01*
G01Y987527D02*
Y987536D01*
G01Y987521D02*
Y987527D01*
G01X1658840Y987520D02*
X1658839Y987521D01*
G01Y1012527D02*
Y1012536D01*
G01Y1012521D02*
Y1012527D01*
G01X1658840Y1012520D02*
X1658839Y1012521D01*
G01Y1017527D02*
Y1017536D01*
G01Y1017521D02*
Y1017527D01*
G01X1658840Y1017520D02*
X1658839Y1017521D01*
G01Y1022527D02*
Y1022536D01*
G01Y1022521D02*
Y1022527D01*
G01X1658840Y1022520D02*
X1658839Y1022521D01*
G01Y1027527D02*
Y1027536D01*
G01Y1027521D02*
Y1027527D01*
G01X1658840Y1027520D02*
X1658839Y1027521D01*
G01Y1032527D02*
Y1032536D01*
G01Y1032521D02*
Y1032527D01*
G01X1658840Y1032520D02*
X1658839Y1032521D01*
G01Y1037527D02*
Y1037536D01*
G01Y1037521D02*
Y1037527D01*
G01X1658840Y1037520D02*
X1658839Y1037521D01*
G01Y1042527D02*
Y1042536D01*
G01Y1042521D02*
Y1042527D01*
G01X1658840Y1042520D02*
X1658839Y1042521D01*
G01X1658840Y1047520D02*
X1658839Y1047521D01*
G01X1659815Y957663D02*
X1659823Y957637D01*
G01X1659805Y957690D02*
X1659815Y957663D01*
G01X1659794Y957717D02*
X1659805Y957690D01*
G01X1659815Y962663D02*
X1659823Y962637D01*
G01X1659805Y962690D02*
X1659815Y962663D01*
G01X1659794Y962717D02*
X1659805Y962690D01*
G01X1659815Y967663D02*
X1659823Y967637D01*
G01X1659805Y967690D02*
X1659815Y967663D01*
G01X1659794Y967717D02*
X1659805Y967690D01*
G01X1659815Y972663D02*
X1659823Y972637D01*
G01X1659805Y972690D02*
X1659815Y972663D01*
G01X1659794Y972717D02*
X1659805Y972690D01*
G01X1659815Y977663D02*
X1659823Y977637D01*
G01X1659805Y977690D02*
X1659815Y977663D01*
G01X1659794Y977717D02*
X1659805Y977690D01*
G01X1659815Y982663D02*
X1659823Y982637D01*
G01X1659805Y982690D02*
X1659815Y982663D01*
G01X1659794Y982717D02*
X1659805Y982690D01*
G01X1659815Y987663D02*
X1659823Y987637D01*
G01X1659805Y987690D02*
X1659815Y987663D01*
G01X1659794Y987717D02*
X1659805Y987690D01*
G01X1659815Y1012663D02*
X1659823Y1012637D01*
G01X1659805Y1012690D02*
X1659815Y1012663D01*
G01X1659794Y1012717D02*
X1659805Y1012690D01*
G01X1659815Y1017663D02*
X1659823Y1017637D01*
G01X1659805Y1017690D02*
X1659815Y1017663D01*
G01X1659794Y1017717D02*
X1659805Y1017690D01*
G01X1659815Y1022663D02*
X1659823Y1022637D01*
G01X1659805Y1022690D02*
X1659815Y1022663D01*
G01X1659794Y1022717D02*
X1659805Y1022690D01*
G01X1659815Y1027663D02*
X1659823Y1027637D01*
G01X1659805Y1027690D02*
X1659815Y1027663D01*
G01X1659794Y1027717D02*
X1659805Y1027690D01*
G01X1659815Y1032663D02*
X1659823Y1032637D01*
G01X1659805Y1032690D02*
X1659815Y1032663D01*
G01X1659794Y1032717D02*
X1659805Y1032690D01*
G01X1659815Y1037663D02*
X1659823Y1037637D01*
G01X1659805Y1037690D02*
X1659815Y1037663D01*
G01X1659794Y1037717D02*
X1659805Y1037690D01*
G01X1659815Y1042663D02*
X1659823Y1042637D01*
G01X1659805Y1042690D02*
X1659815Y1042663D01*
G01X1659794Y1042717D02*
X1659805Y1042690D01*
G01X1645431Y998745D02*
X1645450Y998740D01*
G01X1645418Y998757D02*
X1645431Y998745D01*
G01X1645411Y998775D02*
X1645418Y998757D01*
G01X1659806Y957515D02*
X1659786Y957520D01*
G01X1659820Y957500D02*
X1659806Y957515D01*
G01X1659825Y957480D02*
X1659820Y957500D01*
G01X1659806Y962515D02*
X1659786Y962520D01*
G01X1659820Y962500D02*
X1659806Y962515D01*
G01X1659825Y962480D02*
X1659820Y962500D01*
G01X1659806Y967515D02*
X1659786Y967520D01*
G01X1659820Y967500D02*
X1659806Y967515D01*
G01X1659825Y967480D02*
X1659820Y967500D01*
G01X1659806Y972515D02*
X1659786Y972520D01*
G01X1659820Y972500D02*
X1659806Y972515D01*
G01X1659825Y972480D02*
X1659820Y972500D01*
G01X1659806Y977515D02*
X1659786Y977520D01*
G01X1659820Y977500D02*
X1659806Y977515D01*
G01X1659825Y977480D02*
X1659820Y977500D01*
G01X1659806Y982515D02*
X1659786Y982520D01*
G01X1659820Y982500D02*
X1659806Y982515D01*
G01X1659825Y982480D02*
X1659820Y982500D01*
G01X1659806Y987515D02*
X1659786Y987520D01*
G01X1659820Y987500D02*
X1659806Y987515D01*
G01X1659825Y987480D02*
X1659820Y987500D01*
G01X1659806Y1012515D02*
X1659786Y1012520D01*
G01X1659820Y1012500D02*
X1659806Y1012515D01*
G01X1659825Y1012480D02*
X1659820Y1012500D01*
G01X1659806Y1017515D02*
X1659786Y1017520D01*
G01X1659820Y1017500D02*
X1659806Y1017515D01*
G01X1659825Y1017480D02*
X1659820Y1017500D01*
G01X1659806Y1022515D02*
X1659786Y1022520D01*
G01X1659820Y1022500D02*
X1659806Y1022515D01*
G01X1659825Y1022480D02*
X1659820Y1022500D01*
G01X1659806Y1027515D02*
X1659786Y1027520D01*
G01X1659820Y1027500D02*
X1659806Y1027515D01*
G01X1659825Y1027480D02*
X1659820Y1027500D01*
G01X1659806Y1032515D02*
X1659786Y1032520D01*
G01X1659820Y1032500D02*
X1659806Y1032515D01*
G01X1659825Y1032480D02*
X1659820Y1032500D01*
G01X1659806Y1037515D02*
X1659786Y1037520D01*
G01X1659820Y1037500D02*
X1659806Y1037515D01*
G01X1659825Y1037480D02*
X1659820Y1037500D01*
G01X1659806Y1042515D02*
X1659786Y1042520D01*
G01X1659820Y1042500D02*
X1659806Y1042515D01*
G01X1659825Y1042480D02*
X1659820Y1042500D01*
G01X1659806Y1047515D02*
X1659786Y1047520D01*
G01X1659820Y1047500D02*
X1659806Y1047515D01*
G01X1659825Y1047480D02*
X1659820Y1047500D01*
G01X1646390Y996754D02*
X1646383Y996762D01*
G01X1646395Y996743D02*
X1646390Y996754D01*
G01X1646396Y996732D02*
X1646395Y996743D01*
G01X1646390Y990454D02*
X1646383Y990463D01*
G01X1646395Y990444D02*
X1646390Y990454D01*
G01X1646396Y990433D02*
X1646395Y990444D01*
G01X1646390Y993604D02*
X1646383Y993612D01*
G01X1646395Y993594D02*
X1646390Y993604D01*
G01X1646396Y993583D02*
X1646395Y993594D01*
G01X1646390Y999903D02*
X1646383Y999911D01*
G01X1646395Y999893D02*
X1646390Y999903D01*
G01X1646396Y999882D02*
X1646395Y999893D01*
G01X1646390Y1003053D02*
X1646383Y1003061D01*
G01X1646395Y1003043D02*
X1646390Y1003053D01*
G01X1646396Y1003031D02*
X1646395Y1003043D01*
G01X1646390Y1006202D02*
X1646383Y1006211D01*
G01X1646395Y1006192D02*
X1646390Y1006202D01*
G01X1646396Y1006181D02*
X1646395Y1006192D01*
G01X1646390Y1009352D02*
X1646383Y1009360D01*
G01X1646395Y1009342D02*
X1646390Y1009352D01*
G01X1646396Y1009331D02*
X1646395Y1009342D01*
G01X1646357Y1005039D02*
X1646360Y1005028D01*
G01X1646397Y990435D02*
X1646398Y990446D01*
G01X1646397Y993585D02*
X1646398Y993596D01*
G01X1646397Y996734D02*
X1646398Y996746D01*
G01X1646397Y999884D02*
X1646398Y999895D01*
G01X1646397Y1003033D02*
X1646398Y1003045D01*
G01X1646397Y1006183D02*
X1646398Y1006194D01*
G01X1646397Y1009333D02*
X1646398Y1009344D01*
G01X1659823Y957494D02*
Y957502D01*
G01Y962494D02*
Y962502D01*
G01Y967494D02*
Y967502D01*
G01Y972494D02*
Y972502D01*
G01Y977494D02*
Y977502D01*
G01Y982494D02*
Y982502D01*
G01Y987494D02*
Y987502D01*
G01Y1012494D02*
Y1012502D01*
G01Y1017494D02*
Y1017502D01*
G01Y1022494D02*
Y1022502D01*
G01Y1027494D02*
Y1027502D01*
G01Y1032494D02*
Y1032502D01*
G01Y1037494D02*
Y1037502D01*
G01Y1042494D02*
Y1042502D01*
G01X1664173Y1046142D02*
Y1047520D01*
G01Y1041142D02*
Y1042520D01*
G01Y1036142D02*
Y1037520D01*
G01Y1031142D02*
Y1032520D01*
G01Y1026142D02*
Y1027520D01*
G01Y1021142D02*
Y1022520D01*
G01Y1016142D02*
Y1017520D01*
G01Y1011142D02*
Y1012520D01*
G01Y986142D02*
Y987520D01*
G01Y981142D02*
Y982520D01*
G01Y976142D02*
Y977520D01*
G01Y971142D02*
Y972520D01*
G01Y966142D02*
Y967520D01*
G01Y961142D02*
Y962520D01*
G01Y956142D02*
Y957520D01*
G01X1661004D02*
Y956142D01*
G01Y962520D02*
Y961142D01*
G01Y967520D02*
Y966142D01*
G01Y972520D02*
Y971142D01*
G01Y977520D02*
Y976142D01*
G01Y982520D02*
Y981142D01*
G01Y987520D02*
Y986142D01*
G01Y1012520D02*
Y1011142D01*
G01Y1017520D02*
Y1016142D01*
G01Y1022520D02*
Y1021142D01*
G01Y1027520D02*
Y1026142D01*
G01Y1032520D02*
Y1031142D01*
G01Y1037520D02*
Y1036142D01*
G01Y1042520D02*
Y1041142D01*
G01Y1047520D02*
Y1046142D01*
G01X1660433Y1010374D02*
Y988287D01*
G01X1659823Y1045650D02*
Y1048012D01*
G01Y1040650D02*
Y1043012D01*
G01Y1035650D02*
Y1038012D01*
G01Y1030650D02*
Y1033012D01*
G01Y1025650D02*
Y1028012D01*
G01Y1020650D02*
Y1023012D01*
G01Y1015650D02*
Y1018012D01*
G01Y1010650D02*
Y1013012D01*
G01Y985650D02*
Y988012D01*
G01Y980650D02*
Y983012D01*
G01Y975650D02*
Y978012D01*
G01Y970650D02*
Y973012D01*
G01Y965650D02*
Y968012D01*
G01Y960650D02*
Y963012D01*
G01Y955650D02*
Y958012D01*
G01Y962494D02*
Y962637D01*
G01Y957494D02*
Y957637D01*
G01Y972494D02*
Y972637D01*
G01Y967494D02*
Y967637D01*
G01Y982494D02*
Y982637D01*
G01Y977494D02*
Y977637D01*
G01Y987494D02*
Y987637D01*
G01Y1012494D02*
Y1012637D01*
G01Y1022494D02*
Y1022637D01*
G01Y1017494D02*
Y1017637D01*
G01Y1032494D02*
Y1032637D01*
G01Y1027494D02*
Y1027637D01*
G01Y1042494D02*
Y1042637D01*
G01Y1037494D02*
Y1037637D01*
G01X1659252Y1009193D02*
Y989469D01*
G01X1658839Y958012D02*
Y955650D01*
G01Y963012D02*
Y960650D01*
G01Y968012D02*
Y965650D01*
G01Y973012D02*
Y970650D01*
G01Y978012D02*
Y975650D01*
G01Y983012D02*
Y980650D01*
G01Y988012D02*
Y985650D01*
G01Y1013012D02*
Y1010650D01*
G01Y1018012D02*
Y1015650D01*
G01Y1023012D02*
Y1020650D01*
G01Y1028012D02*
Y1025650D01*
G01Y1033012D02*
Y1030650D01*
G01Y1038012D02*
Y1035650D01*
G01Y1043012D02*
Y1040650D01*
G01Y1048012D02*
Y1045650D01*
G01X1656496Y1086831D02*
Y1010374D01*
G01X1655315Y989469D02*
Y953012D01*
G01Y1085650D02*
Y1009193D01*
G01X1649803Y953012D02*
Y1085650D01*
G01X1646850Y1090571D02*
Y1011535D01*
G01X1646398Y1008031D02*
Y1009528D01*
G01Y1004881D02*
Y1006378D01*
G01Y1001732D02*
Y1003228D01*
G01Y998582D02*
Y1000079D01*
G01Y995433D02*
Y996929D01*
G01Y992283D02*
Y993780D01*
G01Y989133D02*
Y990630D01*
G01X1646358Y989280D02*
Y989133D01*
G01Y990630D02*
Y990483D01*
G01Y995579D02*
Y995432D01*
G01Y992430D02*
Y992283D01*
G01Y993780D02*
Y993633D01*
G01Y998729D02*
Y998582D01*
G01Y1000079D02*
Y999932D01*
G01Y996930D02*
Y996783D01*
G01Y1001878D02*
Y1001731D01*
G01Y1003229D02*
Y1003082D01*
G01Y1008178D02*
Y1008031D01*
G01Y1009528D02*
Y1009381D01*
G01Y1005028D02*
Y1004881D01*
G01Y1006378D02*
Y1006231D01*
G01X1645453Y1008031D02*
Y1008178D01*
G01Y1009381D02*
Y1009528D01*
G01Y1004881D02*
Y1005028D01*
G01Y1006231D02*
Y1006378D01*
G01Y1001731D02*
Y1001878D01*
G01Y1003082D02*
Y1003229D01*
G01Y998582D02*
Y998729D01*
G01Y999932D02*
Y1000079D01*
G01Y996783D02*
Y996930D01*
G01Y995432D02*
Y995579D01*
G01Y992283D02*
Y992430D01*
G01Y993633D02*
Y993780D01*
G01Y989133D02*
Y989280D01*
G01Y990483D02*
Y990630D01*
G01X1645413D02*
Y989134D01*
G01Y993780D02*
Y992283D01*
G01Y1000079D02*
Y998583D01*
G01Y996929D02*
Y995433D01*
G01Y1003228D02*
Y1001732D01*
G01Y1009528D02*
Y1008031D01*
G01Y1006378D02*
Y1004882D01*
G01X1644232Y990472D02*
Y989291D01*
G01Y996772D02*
Y995591D01*
G01Y993622D02*
Y992441D01*
G01Y999921D02*
Y998740D01*
G01Y1003071D02*
Y1001890D01*
G01Y1009370D02*
Y1008189D01*
G01Y1006220D02*
Y1005039D01*
G01X1643898Y1011535D02*
Y987126D01*
G01X1643504D02*
Y1011535D01*
G01X1640472Y1008189D02*
Y1009370D01*
G01Y1005039D02*
Y1006220D01*
G01Y1001890D02*
Y1003071D01*
G01Y998740D02*
Y999921D01*
G01Y995591D02*
Y996772D01*
G01Y992441D02*
Y993622D01*
G01Y989291D02*
Y990472D01*
G01X1646398Y1008215D02*
X1646397Y1008226D01*
G01X1646398Y1005065D02*
X1646397Y1005076D01*
G01X1646398Y1001916D02*
X1646397Y1001926D01*
G01X1646398Y998766D02*
X1646397Y998777D01*
G01X1646398Y995617D02*
X1646397Y995627D01*
G01X1646398Y992467D02*
X1646397Y992478D01*
G01X1646398Y989317D02*
X1646397Y989328D01*
G01X1659252Y989469D02*
X1660433Y988287D01*
G01X1655315Y989469D02*
X1656496Y988287D01*
G01X1645300Y1008228D02*
X1645412Y1008220D01*
G01X1645411Y998775D02*
X1645300Y998780D01*
G01X1645411Y1001926D02*
X1645300Y1001929D01*
G01X1664173Y1046142D02*
X1658840D01*
G01X1658839Y1045650D02*
X1659823D01*
G01Y1043012D02*
X1658839D01*
G01X1658840Y1042520D02*
X1664173D01*
G01Y1042480D02*
X1659825D01*
G01X1664173Y1041142D02*
X1658840D01*
G01X1658839Y1040650D02*
X1659823D01*
G01Y1038012D02*
X1658839D01*
G01X1658840Y1037520D02*
X1664173D01*
G01Y1037480D02*
X1659825D01*
G01X1664173Y1036142D02*
X1658840D01*
G01X1658839Y1035650D02*
X1659823D01*
G01Y1033012D02*
X1658839D01*
G01X1658840Y1032520D02*
X1664173D01*
G01Y1032480D02*
X1659825D01*
G01X1664173Y1031142D02*
X1658840D01*
G01X1658839Y1030650D02*
X1659823D01*
G01Y1028012D02*
X1658839D01*
G01X1658840Y1027520D02*
X1664173D01*
G01Y1027480D02*
X1659825D01*
G01X1664173Y1026142D02*
X1658840D01*
G01X1658839Y1025650D02*
X1659823D01*
G01Y1023012D02*
X1658839D01*
G01X1658840Y1022520D02*
X1664173D01*
G01Y1022480D02*
X1659825D01*
G01X1664173Y1021142D02*
X1658840D01*
G01X1659823Y1045946D02*
X1658839Y1045945D01*
G01Y1042715D02*
X1659794Y1042717D01*
G01X1659823Y1040946D02*
X1658839Y1040945D01*
G01Y1037715D02*
X1659794Y1037717D01*
G01X1659823Y1035946D02*
X1658839Y1035945D01*
G01Y1032715D02*
X1659794Y1032717D01*
G01X1659823Y1030946D02*
X1658839Y1030945D01*
G01Y1027715D02*
X1659794Y1027717D01*
G01X1659823Y1025946D02*
X1658839Y1025945D01*
G01Y1022715D02*
X1659794Y1022717D01*
G01X1659252Y1009193D02*
X1660433Y1010374D01*
G01X1655315Y1009193D02*
X1656496Y1010374D01*
G01X1645411Y992477D02*
X1645300Y992480D01*
G01X1658839Y1020650D02*
X1659823D01*
G01Y1018012D02*
X1658839D01*
G01X1658840Y1017520D02*
X1664173D01*
G01Y1017480D02*
X1659825D01*
G01X1664173Y1016142D02*
X1658840D01*
G01X1658839Y1015650D02*
X1659823D01*
G01Y1013012D02*
X1658839D01*
G01X1658840Y1012520D02*
X1664173D01*
G01Y1012480D02*
X1659825D01*
G01X1646850Y1011535D02*
X1643504D01*
G01X1664173Y1011142D02*
X1658840D01*
G01X1658839Y1010650D02*
X1659823D01*
G01X1656496Y1010374D02*
X1660433D01*
G01X1646358Y1009567D02*
X1645453D01*
G01X1646398Y1009528D02*
X1645413D01*
G01X1646357Y1009370D02*
X1640472D01*
G01Y1009331D02*
X1646396D01*
G01X1655315Y1009193D02*
X1659252D01*
G01X1646396Y1008228D02*
X1640472D01*
G01X1646357Y1008189D02*
X1640472D01*
G01X1645413Y1008031D02*
X1646398D01*
G01X1645453Y1007992D02*
X1646358D01*
G01Y1006417D02*
X1645453D01*
G01X1646398Y1006378D02*
X1645413D01*
G01X1646357Y1006220D02*
X1640472D01*
G01Y1006181D02*
X1646396D01*
G01Y1005079D02*
X1640472D01*
G01X1646357Y1005039D02*
X1640472D01*
G01X1645413Y1004882D02*
X1646398D01*
G01X1645453Y1004843D02*
X1646358D01*
G01Y1003268D02*
X1645453D01*
G01X1646398Y1003228D02*
X1645413D01*
G01X1646357Y1003071D02*
X1640472D01*
G01Y1003031D02*
X1646396D01*
G01X1644666Y1001929D02*
X1644232D01*
G01X1646396D02*
X1640472D01*
G01X1646357Y1001890D02*
X1640472D01*
G01X1645413Y1001732D02*
X1646398D01*
G01X1645453Y1001693D02*
X1646358D01*
G01Y1000118D02*
X1645453D01*
G01X1646398Y1000079D02*
X1645413D01*
G01X1646357Y999921D02*
X1640472D01*
G01Y999882D02*
X1646396D01*
G01X1644666Y998780D02*
X1644232D01*
G01X1646396D02*
X1640472D01*
G01X1646357Y998740D02*
X1640472D01*
G01X1645413Y998583D02*
X1646398D01*
G01X1645453Y998543D02*
X1646358D01*
G01Y996969D02*
X1645453D01*
G01X1646398Y996929D02*
X1645413D01*
G01X1646357Y996772D02*
X1640472D01*
G01Y996732D02*
X1646396D01*
G01Y995630D02*
X1640472D01*
G01X1646357Y995591D02*
X1640472D01*
G01X1645413Y995433D02*
X1646398D01*
G01X1645453Y995394D02*
X1646358D01*
G01Y993819D02*
X1645453D01*
G01X1646398Y993780D02*
X1645413D01*
G01X1646357Y993622D02*
X1640472D01*
G01Y993583D02*
X1646396D01*
G01X1644666Y992480D02*
X1644232D01*
G01X1646396D02*
X1640472D01*
G01X1646357Y992441D02*
X1640472D01*
G01X1645413Y992283D02*
X1646398D01*
G01X1645453Y992244D02*
X1646358D01*
G01Y990669D02*
X1645453D01*
G01X1646398Y990630D02*
X1645413D01*
G01X1646357Y990472D02*
X1640472D01*
G01Y990433D02*
X1646396D01*
G01X1659252Y989469D02*
X1655315D01*
G01X1646396Y989331D02*
X1640472D01*
G01X1646357Y989291D02*
X1640472D01*
G01X1645413Y989134D02*
X1646398D01*
G01X1645453Y989094D02*
X1646358D01*
G01X1660433Y988287D02*
X1656496D01*
G01X1659823Y988012D02*
X1658839D01*
G01X1658840Y987520D02*
X1664173D01*
G01Y987480D02*
X1659825D01*
G01X1646850Y987126D02*
X1643504D01*
G01X1664173Y986142D02*
X1658840D01*
G01X1658839Y985650D02*
X1659823D01*
G01Y983012D02*
X1658839D01*
G01X1658840Y982520D02*
X1664173D01*
G01Y982480D02*
X1659825D01*
G01X1664173Y981142D02*
X1658840D01*
G01X1658839Y980650D02*
X1659823D01*
G01Y978012D02*
X1658839D01*
G01X1658840Y977520D02*
X1664173D01*
G01Y977480D02*
X1659825D01*
G01X1664173Y976142D02*
X1658840D01*
G01X1658839Y975650D02*
X1659823D01*
G01Y973012D02*
X1658839D01*
G01X1658840Y972520D02*
X1664173D01*
G01Y972480D02*
X1659825D01*
G01X1664173Y971142D02*
X1658840D01*
G01X1658839Y970650D02*
X1659823D01*
G01Y968012D02*
X1658839D01*
G01X1658840Y967520D02*
X1664173D01*
G01Y967480D02*
X1659825D01*
G01X1664173Y966142D02*
X1658840D01*
G01X1658839Y965650D02*
X1659823D01*
G01Y963012D02*
X1658839D01*
G01X1658840Y962520D02*
X1664173D01*
G01Y962480D02*
X1659825D01*
G01X1664173Y961142D02*
X1658840D01*
G01X1658839Y960650D02*
X1659823D01*
G01Y958012D02*
X1658839D01*
G01X1658840Y957520D02*
X1664173D01*
G01Y957480D02*
X1659825D01*
G01X1664173Y956142D02*
X1658840D01*
G01X1658839Y955650D02*
X1659823D01*
G01X1655315Y953012D02*
X1649803D01*
G01X1659823Y1020946D02*
X1658839Y1020945D01*
G01Y1017715D02*
X1659794Y1017717D01*
G01X1659823Y1015946D02*
X1658839Y1015945D01*
G01Y1012715D02*
X1659794Y1012717D01*
G01X1659823Y1010946D02*
X1658839Y1010945D01*
G01Y987715D02*
X1659794Y987717D01*
G01X1659823Y985946D02*
X1658839Y985945D01*
G01Y982715D02*
X1659794Y982717D01*
G01X1659823Y980946D02*
X1658839Y980945D01*
G01Y977715D02*
X1659794Y977717D01*
G01X1659823Y975946D02*
X1658839Y975945D01*
G01Y972715D02*
X1659794Y972717D01*
G01X1659823Y970946D02*
X1658839Y970945D01*
G01Y967715D02*
X1659794Y967717D01*
G01X1659823Y965946D02*
X1658839Y965945D01*
G01Y962715D02*
X1659794Y962717D01*
G01X1659823Y960946D02*
X1658839Y960945D01*
G01Y957715D02*
X1659794Y957717D01*
G01X1659823Y955946D02*
X1658839Y955945D01*
G01X1659823Y1081134D02*
Y1081125D01*
G01X1659824Y1081140D02*
X1659823Y1081134D01*
G01X1659826Y1081142D02*
X1659824Y1081140D01*
G01X1659823Y1076134D02*
Y1076125D01*
G01X1659824Y1076140D02*
X1659823Y1076134D01*
G01X1659826Y1076142D02*
X1659824Y1076140D01*
G01X1659823Y1071134D02*
Y1071125D01*
G01X1659824Y1071140D02*
X1659823Y1071134D01*
G01X1659826Y1071142D02*
X1659824Y1071140D01*
G01X1659823Y1066134D02*
Y1066125D01*
G01X1659824Y1066140D02*
X1659823Y1066134D01*
G01X1659826Y1066142D02*
X1659824Y1066140D01*
G01X1659823Y1061134D02*
Y1061125D01*
G01X1659824Y1061140D02*
X1659823Y1061134D01*
G01X1659826Y1061142D02*
X1659824Y1061140D01*
G01X1659823Y1056134D02*
Y1056125D01*
G01X1659824Y1056140D02*
X1659823Y1056134D01*
G01X1659826Y1056142D02*
X1659824Y1056140D01*
G01X1659823Y1051134D02*
Y1051125D01*
G01X1659824Y1051140D02*
X1659823Y1051134D01*
G01X1659826Y1051142D02*
X1659824Y1051140D01*
G01X1659810Y1052511D02*
X1659821Y1052496D01*
G01X1659786Y1052520D02*
X1659810Y1052511D01*
G01Y1057511D02*
X1659821Y1057496D01*
G01X1659786Y1057520D02*
X1659810Y1057511D01*
G01Y1062511D02*
X1659821Y1062496D01*
G01X1659786Y1062520D02*
X1659810Y1062511D01*
G01Y1067511D02*
X1659821Y1067496D01*
G01X1659786Y1067520D02*
X1659810Y1067511D01*
G01Y1072511D02*
X1659821Y1072496D01*
G01X1659786Y1072520D02*
X1659810Y1072511D01*
G01Y1077511D02*
X1659821Y1077496D01*
G01X1659786Y1077520D02*
X1659810Y1077511D01*
G01Y1082511D02*
X1659821Y1082496D01*
G01X1659786Y1082520D02*
X1659810Y1082511D01*
G01X1659790Y1047618D02*
X1659794Y1047717D01*
G01X1659784Y1047546D02*
X1659790Y1047618D01*
G01X1659786Y1047520D02*
X1659784Y1047546D01*
G01X1659790Y1052618D02*
X1659794Y1052717D01*
G01X1659784Y1052546D02*
X1659790Y1052618D01*
G01X1659786Y1052520D02*
X1659784Y1052546D01*
G01X1659790Y1057618D02*
X1659794Y1057717D01*
G01X1659784Y1057546D02*
X1659790Y1057618D01*
G01X1659786Y1057520D02*
X1659784Y1057546D01*
G01X1659790Y1062618D02*
X1659794Y1062717D01*
G01X1659784Y1062546D02*
X1659790Y1062618D01*
G01X1659786Y1062520D02*
X1659784Y1062546D01*
G01X1659790Y1067618D02*
X1659794Y1067717D01*
G01X1659784Y1067546D02*
X1659790Y1067618D01*
G01X1659786Y1067520D02*
X1659784Y1067546D01*
G01X1659790Y1072618D02*
X1659794Y1072717D01*
G01X1659784Y1072546D02*
X1659790Y1072618D01*
G01X1659786Y1072520D02*
X1659784Y1072546D01*
G01X1659790Y1077618D02*
X1659794Y1077717D01*
G01X1659784Y1077546D02*
X1659790Y1077618D01*
G01X1659786Y1077520D02*
X1659784Y1077546D01*
G01X1659790Y1082618D02*
X1659794Y1082717D01*
G01X1659784Y1082546D02*
X1659790Y1082618D01*
G01X1659786Y1082520D02*
X1659784Y1082546D01*
G01X1658839Y1081140D02*
X1658840Y1081142D01*
G01X1658839Y1081134D02*
Y1081140D01*
G01Y1081126D02*
Y1081134D01*
G01Y1076140D02*
X1658840Y1076142D01*
G01X1658839Y1076134D02*
Y1076140D01*
G01Y1076126D02*
Y1076134D01*
G01Y1071140D02*
X1658840Y1071142D01*
G01X1658839Y1071134D02*
Y1071140D01*
G01Y1071126D02*
Y1071134D01*
G01Y1066140D02*
X1658840Y1066142D01*
G01X1658839Y1066134D02*
Y1066140D01*
G01Y1066126D02*
Y1066134D01*
G01Y1061140D02*
X1658840Y1061142D01*
G01X1658839Y1061134D02*
Y1061140D01*
G01Y1061126D02*
Y1061134D01*
G01Y1056140D02*
X1658840Y1056142D01*
G01X1658839Y1056134D02*
Y1056140D01*
G01Y1056126D02*
Y1056134D01*
G01Y1051140D02*
X1658840Y1051142D01*
G01X1658839Y1051134D02*
Y1051140D01*
G01Y1051126D02*
Y1051134D01*
G01X1659823Y1047487D02*
Y1047494D01*
G01Y1052487D02*
Y1052494D01*
G01X1659824Y1052482D02*
X1659823Y1052487D01*
G01X1659825Y1052480D02*
X1659824Y1052482D01*
G01X1659823Y1057487D02*
Y1057494D01*
G01X1659824Y1057482D02*
X1659823Y1057487D01*
G01X1659825Y1057480D02*
X1659824Y1057482D01*
G01X1659823Y1062487D02*
Y1062494D01*
G01X1659824Y1062482D02*
X1659823Y1062487D01*
G01X1659825Y1062480D02*
X1659824Y1062482D01*
G01X1659823Y1067487D02*
Y1067494D01*
G01X1659824Y1067482D02*
X1659823Y1067487D01*
G01X1659825Y1067480D02*
X1659824Y1067482D01*
G01X1659823Y1072487D02*
Y1072494D01*
G01X1659824Y1072482D02*
X1659823Y1072487D01*
G01X1659825Y1072480D02*
X1659824Y1072482D01*
G01X1659823Y1077487D02*
Y1077494D01*
G01X1659824Y1077482D02*
X1659823Y1077487D01*
G01X1659825Y1077480D02*
X1659824Y1077482D01*
G01X1659823Y1082487D02*
Y1082494D01*
G01X1659824Y1082482D02*
X1659823Y1082487D01*
G01X1659825Y1082480D02*
X1659824Y1082482D01*
G01X1658839Y1047527D02*
Y1047536D01*
G01Y1047521D02*
Y1047527D01*
G01Y1052527D02*
Y1052536D01*
G01Y1052521D02*
Y1052527D01*
G01X1658840Y1052520D02*
X1658839Y1052521D01*
G01X1659815Y1047663D02*
X1659823Y1047637D01*
G01X1659805Y1047690D02*
X1659815Y1047663D01*
G01X1659794Y1047717D02*
X1659805Y1047690D01*
G01X1659815Y1052663D02*
X1659823Y1052637D01*
G01X1659805Y1052690D02*
X1659815Y1052663D01*
G01X1659794Y1052717D02*
X1659805Y1052690D01*
G01X1659806Y1052515D02*
X1659786Y1052520D01*
G01X1659820Y1052500D02*
X1659806Y1052515D01*
G01X1659825Y1052480D02*
X1659820Y1052500D01*
G01X1659806Y1057515D02*
X1659786Y1057520D01*
G01X1659820Y1057500D02*
X1659806Y1057515D01*
G01X1659825Y1057480D02*
X1659820Y1057500D01*
G01X1659806Y1062515D02*
X1659786Y1062520D01*
G01X1659820Y1062500D02*
X1659806Y1062515D01*
G01X1659825Y1062480D02*
X1659820Y1062500D01*
G01X1659806Y1067515D02*
X1659786Y1067520D01*
G01X1659820Y1067500D02*
X1659806Y1067515D01*
G01X1659825Y1067480D02*
X1659820Y1067500D01*
G01X1659806Y1072515D02*
X1659786Y1072520D01*
G01X1659820Y1072500D02*
X1659806Y1072515D01*
G01X1659825Y1072480D02*
X1659820Y1072500D01*
G01X1659806Y1077515D02*
X1659786Y1077520D01*
G01X1659820Y1077500D02*
X1659806Y1077515D01*
G01X1659825Y1077480D02*
X1659820Y1077500D01*
G01X1658839Y1057527D02*
Y1057536D01*
G01Y1057521D02*
Y1057527D01*
G01X1658840Y1057520D02*
X1658839Y1057521D01*
G01Y1062527D02*
Y1062536D01*
G01Y1062521D02*
Y1062527D01*
G01X1658840Y1062520D02*
X1658839Y1062521D01*
G01Y1067527D02*
Y1067536D01*
G01Y1067521D02*
Y1067527D01*
G01X1658840Y1067520D02*
X1658839Y1067521D01*
G01Y1072527D02*
Y1072536D01*
G01Y1072521D02*
Y1072527D01*
G01X1658840Y1072520D02*
X1658839Y1072521D01*
G01Y1077527D02*
Y1077536D01*
G01Y1077521D02*
Y1077527D01*
G01X1658840Y1077520D02*
X1658839Y1077521D01*
G01Y1082527D02*
Y1082536D01*
G01Y1082521D02*
Y1082527D01*
G01X1658840Y1082520D02*
X1658839Y1082521D01*
G01X1659815Y1057663D02*
X1659823Y1057637D01*
G01X1659805Y1057690D02*
X1659815Y1057663D01*
G01X1659794Y1057717D02*
X1659805Y1057690D01*
G01X1659815Y1062663D02*
X1659823Y1062637D01*
G01X1659805Y1062690D02*
X1659815Y1062663D01*
G01X1659794Y1062717D02*
X1659805Y1062690D01*
G01X1659815Y1067663D02*
X1659823Y1067637D01*
G01X1659805Y1067690D02*
X1659815Y1067663D01*
G01X1659794Y1067717D02*
X1659805Y1067690D01*
G01X1659815Y1072663D02*
X1659823Y1072637D01*
G01X1659805Y1072690D02*
X1659815Y1072663D01*
G01X1659794Y1072717D02*
X1659805Y1072690D01*
G01X1659815Y1077663D02*
X1659823Y1077637D01*
G01X1659805Y1077690D02*
X1659815Y1077663D01*
G01X1659794Y1077717D02*
X1659805Y1077690D01*
G01X1659815Y1082663D02*
X1659823Y1082637D01*
G01X1659805Y1082690D02*
X1659815Y1082663D01*
G01X1659794Y1082717D02*
X1659805Y1082690D01*
G01X1659806Y1082515D02*
X1659786Y1082520D01*
G01X1659820Y1082500D02*
X1659806Y1082515D01*
G01X1659825Y1082480D02*
X1659820Y1082500D01*
G01X1658268Y1108012D02*
G03X1657677Y1108602I-591J-1D01*
G01X1650984D02*
G03X1650394Y1108012I0J-590D01*
G01X1653150Y1106831D02*
G03Y1104862I0J-985D01*
G01X1655512D02*
G03Y1106831I0J984D01*
G01X1665157Y1107421D02*
G03X1663189Y1109390I-1968J1D01*
G01X1645472D02*
G03X1643504Y1107421I1J-1969D01*
G01X1651772Y1098917D02*
G03X1650591Y1097736I0J-1181D01*
G01X1658071D02*
G03X1656890Y1098917I-1181J0D01*
G01X1656220Y1093642D02*
G03I-1889J0D01*
G01X1656693D02*
G03I-2362J0D01*
G01X1653150Y1094232D02*
X1650839Y1098461D01*
G01X1655512Y1092539D02*
X1656815Y1090571D01*
G01X1648622Y1086831D02*
X1649803Y1085650D01*
G01X1643504Y1091673D02*
X1646850Y1088327D01*
G01X1659823Y1047494D02*
Y1047502D01*
G01Y1052494D02*
Y1052502D01*
G01Y1057494D02*
Y1057502D01*
G01Y1062494D02*
Y1062502D01*
G01Y1067494D02*
Y1067502D01*
G01Y1072494D02*
Y1072502D01*
G01Y1077494D02*
Y1077502D01*
G01Y1082494D02*
Y1082502D01*
G01X1665157Y1091673D02*
Y1107421D01*
G01X1664173Y1081142D02*
Y1082520D01*
G01Y1076142D02*
Y1077520D01*
G01Y1071142D02*
Y1072520D01*
G01Y1066142D02*
Y1067520D01*
G01Y1061142D02*
Y1062520D01*
G01Y1056142D02*
Y1057520D01*
G01Y1051142D02*
Y1052520D01*
G01X1661004D02*
Y1051142D01*
G01Y1057520D02*
Y1056142D01*
G01Y1062520D02*
Y1061142D01*
G01Y1067520D02*
Y1066142D01*
G01Y1072520D02*
Y1071142D01*
G01Y1077520D02*
Y1076142D01*
G01Y1082520D02*
Y1081142D01*
G01X1659823Y1080650D02*
Y1083012D01*
G01Y1075650D02*
Y1078012D01*
G01Y1070650D02*
Y1073012D01*
G01Y1065650D02*
Y1068012D01*
G01Y1060650D02*
Y1063012D01*
G01Y1055650D02*
Y1058012D01*
G01Y1050650D02*
Y1053012D01*
G01Y1052494D02*
Y1052637D01*
G01Y1047494D02*
Y1047637D01*
G01Y1062494D02*
Y1062637D01*
G01Y1057494D02*
Y1057637D01*
G01Y1072494D02*
Y1072637D01*
G01Y1067494D02*
Y1067637D01*
G01Y1082494D02*
Y1082637D01*
G01Y1077494D02*
Y1077637D01*
G01X1658839Y1053012D02*
Y1050650D01*
G01Y1058012D02*
Y1055650D01*
G01Y1063012D02*
Y1060650D01*
G01Y1068012D02*
Y1065650D01*
G01Y1073012D02*
Y1070650D01*
G01Y1078012D02*
Y1075650D01*
G01Y1083012D02*
Y1080650D01*
G01X1658268Y1101909D02*
Y1108012D01*
G01X1658071Y1097736D02*
Y1089193D01*
G01X1655512Y1094232D02*
Y1092539D01*
G01X1653150D02*
Y1094232D01*
G01X1650591Y1089193D02*
Y1097736D01*
G01X1650394Y1101909D02*
Y1108012D01*
G01X1643504Y1107421D02*
Y1091673D01*
G01X1657822Y1098461D02*
X1655512Y1094232D01*
G01X1663189Y1109390D02*
X1645472D01*
G01X1657677Y1108602D02*
X1650984D01*
G01X1655512Y1106831D02*
X1653150D01*
G01Y1104862D02*
X1655512D01*
G01X1658268Y1103484D02*
X1650394D01*
G01X1651846Y1090571D02*
X1653150Y1092539D01*
G01X1650394Y1101909D02*
X1658268D01*
G01X1665157Y1098957D02*
X1643504D01*
G01X1651772Y1098917D02*
X1656890D01*
G01X1653150Y1094232D02*
X1655512D01*
G01X1653150Y1092539D02*
X1655512D01*
G01X1646850Y1090571D02*
X1661220D01*
G01X1646850Y1089193D02*
X1650591D01*
G01X1661220D02*
X1658071D01*
G01X1646850Y1088327D02*
X1661811D01*
G01X1648622Y1086831D02*
X1656496D01*
G01X1649803Y1085650D02*
X1655315D01*
G01X1659823Y1083012D02*
X1658839D01*
G01X1658840Y1082520D02*
X1664173D01*
G01Y1082480D02*
X1659825D01*
G01X1664173Y1081142D02*
X1658840D01*
G01X1658839Y1080650D02*
X1659823D01*
G01Y1078012D02*
X1658839D01*
G01X1658840Y1077520D02*
X1664173D01*
G01Y1077480D02*
X1659825D01*
G01X1664173Y1076142D02*
X1658840D01*
G01X1658839Y1075650D02*
X1659823D01*
G01Y1073012D02*
X1658839D01*
G01X1658840Y1072520D02*
X1664173D01*
G01Y1072480D02*
X1659825D01*
G01X1664173Y1071142D02*
X1658840D01*
G01X1658839Y1070650D02*
X1659823D01*
G01Y1068012D02*
X1658839D01*
G01X1658840Y1067520D02*
X1664173D01*
G01Y1067480D02*
X1659825D01*
G01X1664173Y1066142D02*
X1658840D01*
G01X1658839Y1065650D02*
X1659823D01*
G01Y1063012D02*
X1658839D01*
G01X1658840Y1062520D02*
X1664173D01*
G01Y1062480D02*
X1659825D01*
G01X1664173Y1061142D02*
X1658840D01*
G01X1658839Y1060650D02*
X1659823D01*
G01Y1058012D02*
X1658839D01*
G01X1658840Y1057520D02*
X1664173D01*
G01Y1057480D02*
X1659825D01*
G01X1664173Y1056142D02*
X1658840D01*
G01X1658839Y1055650D02*
X1659823D01*
G01Y1053012D02*
X1658839D01*
G01X1658840Y1052520D02*
X1664173D01*
G01Y1052480D02*
X1659825D01*
G01X1664173Y1051142D02*
X1658840D01*
G01X1658839Y1050650D02*
X1659823D01*
G01Y1048012D02*
X1658839D01*
G01X1658840Y1047520D02*
X1664173D01*
G01Y1047480D02*
X1659825D01*
G01X1658839Y1082715D02*
X1659794Y1082717D01*
G01X1659823Y1080946D02*
X1658839Y1080945D01*
G01Y1077715D02*
X1659794Y1077717D01*
G01X1659823Y1075946D02*
X1658839Y1075945D01*
G01Y1072715D02*
X1659794Y1072717D01*
G01X1659823Y1070946D02*
X1658839Y1070945D01*
G01Y1067715D02*
X1659794Y1067717D01*
G01X1659823Y1065946D02*
X1658839Y1065945D01*
G01Y1062715D02*
X1659794Y1062717D01*
G01X1659823Y1060946D02*
X1658839Y1060945D01*
G01Y1057715D02*
X1659794Y1057717D01*
G01X1659823Y1055946D02*
X1658839Y1055945D01*
G01Y1052715D02*
X1659794Y1052717D01*
G01X1659823Y1050946D02*
X1658839Y1050945D01*
G01Y1047715D02*
X1659794Y1047717D01*
G01X1665157Y1091673D02*
X1661811Y1088327D01*
G01X1655315Y1085650D02*
X1656496Y1086831D01*
G01X1636614Y1515748D02*
G03X1632677Y1519685I-3937J0D01*
G01X1636614Y1515748D02*
Y1503937D01*
G01Y1515748D02*
G03X1632677Y1519685I-3937J0D01*
G01X1640551Y1496063D02*
G03X1644488Y1500000I0J3937D01*
G01Y1515748D02*
Y1500000D01*
G01X1648425Y1519685D02*
G03X1644488Y1515748I0J-3937D01*
G01X1827756Y1519685D02*
X1648425D01*
G01X1636614Y1515748D02*
Y1503937D01*
G01X1695276Y1494280D02*
G03Y1497059I0J1389D01*
G01Y1492575D02*
G03Y1498764I0J3094D01*
G01X1640551Y1496063D02*
G03X1644488Y1500000I0J3937D01*
G01X1648425Y1519685D02*
G03X1644488Y1515748I0J-3937D01*
G01X1696536Y1491732D02*
G03Y1499606I-1260J3937D01*
G01X1699409Y1491732D02*
G03Y1499606I-4134J3937D01*
G01X1674016Y1523622D02*
X1684646Y1510954D01*
G01X1677559Y1526772D02*
X1688189Y1516929D01*
G01D02*
X1677559Y1521654D01*
G01X1711811Y1523622D02*
X1744882D01*
G01X1674016D02*
X1707874D01*
G01X1677559Y1521654D02*
X1674016D01*
G01X1711811Y1520210D02*
X1695276D01*
G01X1827756Y1519685D02*
X1648425D01*
G01X1711811Y1518110D02*
X1744882D01*
G01X1768504Y1516929D02*
X1688189D01*
G01X1721260Y1485827D02*
Y1512992D01*
G01X1718898Y1485827D02*
Y1512992D01*
G01X1768504D02*
X1688189D01*
G01X1711811Y1512598D02*
X1744882D01*
G01X1683266D02*
X1683031D01*
G01X1715748Y1510954D02*
X1726378D01*
G01X1684646D02*
X1707874D01*
G01Y1509843D02*
X1748819D01*
G01X1709744Y1505512D02*
X1713878D01*
G01X1693209D02*
X1697343D01*
G01X1711811Y1505210D02*
X1715748D01*
G01X1699409Y1499606D02*
X1695276D01*
G01X1674016Y1492913D02*
X1684646D01*
G01X1699409Y1491732D02*
X1695276D01*
G01X1702362Y1485827D02*
X1688189D01*
G01X1718898D02*
X1704724D01*
G01X1735433D02*
X1721260D01*
G01X1683031Y1471260D02*
X1772047D01*
G01X1697343Y1469783D02*
X1693209D01*
G01X1713878D02*
X1709744D01*
G01X1697343Y1468996D02*
X1693209D01*
G01X1713878D02*
X1709744D01*
G01X1697343Y1464862D02*
X1693209D01*
G01X1713878D02*
X1709744D01*
G01X1697343Y1448130D02*
X1693209D01*
G01X1713878D02*
X1709744D01*
G01X1697343Y1447343D02*
X1693209D01*
G01X1713878D02*
X1709744D01*
G01X1697343Y1443209D02*
X1693209D01*
G01X1713878D02*
X1709744D01*
G01X1715748Y1523622D02*
Y1505210D01*
G01X1714961Y1485827D02*
Y1512992D01*
G01X1713878Y1443209D02*
Y1471260D01*
G01Y1505512D02*
Y1485827D01*
G01X1711811Y1505210D02*
Y1526772D01*
G01X1709744Y1471260D02*
Y1443209D01*
G01Y1505512D02*
Y1485827D01*
G01X1708661D02*
Y1512992D01*
G01X1707874Y1509843D02*
Y1523622D01*
G01X1704724Y1485827D02*
Y1512992D01*
G01X1702362Y1485827D02*
Y1512992D01*
G01X1698425Y1485827D02*
Y1512992D01*
G01X1697343Y1443209D02*
Y1471260D01*
G01Y1505512D02*
Y1485827D01*
G01X1695276Y1492574D02*
Y1494279D01*
G01Y1510954D02*
Y1526772D01*
G01Y1499606D02*
Y1491732D01*
G01Y1497059D02*
Y1498764D01*
G01X1693209Y1471260D02*
Y1443209D01*
G01Y1505512D02*
Y1485827D01*
G01X1692913Y1523622D02*
Y1471260D01*
G01X1692126Y1485827D02*
Y1512992D01*
G01X1689409Y1523622D02*
Y1471260D01*
G01X1688189Y1516929D02*
Y1485827D01*
G01X1684646Y1510954D02*
Y1471260D01*
G01X1684606Y1511001D02*
Y1471260D01*
G01X1683031Y1512598D02*
Y1471260D01*
G01X1677559Y1526772D02*
Y1521654D01*
G01X1675709Y1519685D02*
Y1521604D01*
G01X1674016Y1526772D02*
Y1492913D01*
G01X1644488Y1515748D02*
Y1500000D01*
G01X1674016Y1526772D02*
X1782677D01*
G01X1796282Y-369410D02*
Y-388347D01*
G01X1724836Y-356015D02*
Y-100109D01*
G01X2669718Y-295751D02*
X1724836D01*
G01Y-356015D02*
X2669718D01*
G01X1724836Y-205499D02*
X2669718D01*
G01X1724836Y-250625D02*
X2256063D01*
G01X1724836Y-100109D02*
X2669718D01*
G01X1724836Y-160373D02*
X2669718D01*
G01X1769629Y84941D02*
X1769624Y84921D01*
G01X1769643Y84955D02*
X1769629Y84941D01*
G01X1769663Y84961D02*
X1769643Y84955D01*
G01X1769629Y88091D02*
X1769624Y88071D01*
G01X1769643Y88105D02*
X1769629Y88091D01*
G01X1769663Y88110D02*
X1769643Y88105D01*
G01X1769629Y91240D02*
X1769624Y91220D01*
G01X1769643Y91254D02*
X1769629Y91240D01*
G01X1769663Y91260D02*
X1769643Y91254D01*
G01X1770604Y83799D02*
X1770609Y83819D01*
G01X1770589Y83785D02*
X1770604Y83799D01*
G01X1770569Y83780D02*
X1770589Y83785D01*
G01X1770604Y86949D02*
X1770609Y86969D01*
G01X1770589Y86934D02*
X1770604Y86949D01*
G01X1770569Y86929D02*
X1770589Y86934D01*
G01X1770604Y90098D02*
X1770609Y90118D01*
G01X1770589Y90084D02*
X1770604Y90098D01*
G01X1770569Y90079D02*
X1770589Y90084D01*
G01X1770604Y93248D02*
X1770609Y93268D01*
G01X1770589Y93233D02*
X1770604Y93248D01*
G01X1770569Y93228D02*
X1770589Y93233D01*
G01X1770588Y83772D02*
X1770591Y83774D01*
G01X1770585Y83770D02*
X1770588Y83772D01*
G01X1770581Y83770D02*
X1770585D01*
G01X1770578Y83769D02*
X1770581Y83770D01*
G01X1770574Y83769D02*
X1770578D01*
G01X1770571Y83768D02*
X1770574Y83769D01*
G01X1769648Y84968D02*
X1769645Y84967D01*
G01X1769652Y84969D02*
X1769648Y84968D01*
G01X1769655Y84970D02*
X1769652Y84969D01*
G01X1769658Y84971D02*
X1769655Y84970D01*
G01X1769662Y84972D02*
X1769658Y84971D01*
G01X1769665Y84972D02*
X1769662D01*
G01X1770588Y86921D02*
X1770591Y86923D01*
G01X1770585Y86920D02*
X1770588Y86921D01*
G01X1770581Y86919D02*
X1770585Y86920D01*
G01X1770578Y86919D02*
X1770581D01*
G01X1770574Y86918D02*
X1770578Y86919D01*
G01X1770571Y86918D02*
X1770574D01*
G01X1769648Y88118D02*
X1769645Y88116D01*
G01X1769652Y88119D02*
X1769648Y88118D01*
G01X1769655Y88120D02*
X1769652Y88119D01*
G01X1769658Y88121D02*
X1769655Y88120D01*
G01X1769662Y88121D02*
X1769658D01*
G01X1769665D02*
X1769662D01*
G01X1770588Y90071D02*
X1770591Y90073D01*
G01X1770585Y90070D02*
X1770588Y90071D01*
G01X1770581Y90069D02*
X1770585Y90070D01*
G01X1770578Y90068D02*
X1770581Y90069D01*
G01X1770574Y90068D02*
X1770578D01*
G01X1770571Y90067D02*
X1770574Y90068D01*
G01X1769648Y91267D02*
X1769645Y91266D01*
G01X1769652Y91269D02*
X1769648Y91267D01*
G01X1769655Y91270D02*
X1769652Y91269D01*
G01X1769658Y91270D02*
X1769655D01*
G01X1769662Y91271D02*
X1769658Y91270D01*
G01X1769665Y91271D02*
X1769662D01*
G01X1770588Y93220D02*
X1770591Y93222D01*
G01X1770585Y93219D02*
X1770588Y93220D01*
G01X1770581Y93219D02*
X1770585D01*
G01X1770578Y93218D02*
X1770581Y93219D01*
G01X1770574Y93217D02*
X1770578Y93218D01*
G01X1770571Y93217D02*
X1770574D01*
G01X1770601Y84959D02*
X1770605Y84954D01*
G01X1770596Y84963D02*
X1770601Y84959D01*
G01X1770590Y84967D02*
X1770596Y84963D01*
G01X1770584Y84970D02*
X1770590Y84967D01*
G01X1770578Y84971D02*
X1770584Y84970D01*
G01X1770571Y84972D02*
X1770578Y84971D01*
G01X1770601Y88109D02*
X1770605Y88103D01*
G01X1770596Y88113D02*
X1770601Y88109D01*
G01X1770590Y88117D02*
X1770596Y88113D01*
G01X1770584Y88119D02*
X1770590Y88117D01*
G01X1770578Y88121D02*
X1770584Y88119D01*
G01X1770571Y88121D02*
X1770578D01*
G01X1770601Y91258D02*
X1770605Y91253D01*
G01X1770596Y91263D02*
X1770601Y91258D01*
G01X1770590Y91266D02*
X1770596Y91263D01*
G01X1770584Y91269D02*
X1770590Y91266D01*
G01X1770578Y91270D02*
X1770584Y91269D01*
G01X1770571Y91271D02*
X1770578Y91270D01*
G01X1769627Y83798D02*
X1769626Y83805D01*
G01X1769629Y83791D02*
X1769627Y83798D01*
G01X1769633Y83785D02*
X1769629Y83791D01*
G01X1769637Y83779D02*
X1769633Y83785D01*
G01X1769644Y83774D02*
X1769637Y83779D01*
G01X1769650Y83771D02*
X1769644Y83774D01*
G01X1769658Y83769D02*
X1769650Y83771D01*
G01X1769665Y83768D02*
X1769658Y83769D01*
G01X1769627Y86948D02*
X1769626Y86955D01*
G01X1769629Y86941D02*
X1769627Y86948D01*
G01X1769633Y86934D02*
X1769629Y86941D01*
G01X1769637Y86929D02*
X1769633Y86934D01*
G01X1769644Y86924D02*
X1769637Y86929D01*
G01X1769650Y86920D02*
X1769644Y86924D01*
G01X1769658Y86919D02*
X1769650Y86920D01*
G01X1769665Y86918D02*
X1769658Y86919D01*
G01X1769627Y90097D02*
X1769626Y90104D01*
G01X1769629Y90090D02*
X1769627Y90097D01*
G01X1769633Y90084D02*
X1769629Y90090D01*
G01X1769637Y90078D02*
X1769633Y90084D01*
G01X1769644Y90074D02*
X1769637Y90078D01*
G01X1769650Y90070D02*
X1769644Y90074D01*
G01X1769658Y90068D02*
X1769650Y90070D01*
G01X1769665Y90067D02*
X1769658Y90068D01*
G01X1769627Y93247D02*
X1769626Y93254D01*
G01X1769629Y93240D02*
X1769627Y93247D01*
G01X1769633Y93233D02*
X1769629Y93240D01*
G01X1769637Y93228D02*
X1769633Y93233D01*
G01X1769644Y93223D02*
X1769637Y93228D01*
G01X1769650Y93220D02*
X1769644Y93223D01*
G01X1769658Y93218D02*
X1769650Y93220D01*
G01X1769665Y93217D02*
X1769658Y93218D01*
G01X1770580Y84959D02*
X1770589Y84955D01*
G01X1770569Y84961D02*
X1770580Y84959D01*
G01Y88109D02*
X1770589Y88105D01*
G01X1770569Y88110D02*
X1770580Y88109D01*
G01Y91258D02*
X1770589Y91254D01*
G01X1770569Y91260D02*
X1770580Y91258D01*
G01X1784023Y51999D02*
X1784034Y51984D01*
G01X1783998Y52008D02*
X1784023Y51999D01*
G01X1769626Y86959D02*
Y86955D01*
G01X1769628Y86952D02*
X1769626Y86959D01*
G01X1769639Y86937D02*
X1769628Y86952D01*
G01X1769664Y86929D02*
X1769639Y86937D01*
G01X1769626Y90108D02*
Y90104D01*
G01X1769628Y90102D02*
X1769626Y90108D01*
G01X1769639Y90087D02*
X1769628Y90102D01*
G01X1769663Y90079D02*
X1769639Y90087D01*
G01X1769626Y83809D02*
Y83806D01*
G01X1769628Y83803D02*
X1769626Y83809D01*
G01X1769639Y83788D02*
X1769628Y83803D01*
G01X1769663Y83780D02*
X1769639Y83788D01*
G01X1784023Y56999D02*
X1784034Y56984D01*
G01X1783998Y57008D02*
X1784023Y56999D01*
G01Y61999D02*
X1784034Y61984D01*
G01X1783998Y62008D02*
X1784023Y61999D01*
G01Y66999D02*
X1784034Y66984D01*
G01X1783998Y67008D02*
X1784023Y66999D01*
G01Y71999D02*
X1784034Y71984D01*
G01X1783998Y72008D02*
X1784023Y71999D01*
G01Y76999D02*
X1784034Y76984D01*
G01X1783998Y77008D02*
X1784023Y76999D01*
G01Y81999D02*
X1784034Y81984D01*
G01X1783998Y82008D02*
X1784023Y81999D01*
G01X1769626Y93258D02*
Y93254D01*
G01X1769628Y93252D02*
X1769626Y93258D01*
G01X1769638Y93238D02*
X1769628Y93252D01*
G01X1769661Y93228D02*
X1769638Y93238D01*
G01X1770579Y91259D02*
X1770569Y91260D01*
G01X1770587Y91256D02*
X1770579Y91259D01*
G01X1770595Y91250D02*
X1770587Y91256D01*
G01X1770579Y84959D02*
X1770569Y84961D01*
G01X1770588Y84956D02*
X1770579Y84959D01*
G01X1770595Y84951D02*
X1770588Y84956D01*
G01X1770579Y88109D02*
X1770569Y88110D01*
G01X1770588Y88106D02*
X1770579Y88109D01*
G01X1770595Y88100D02*
X1770588Y88106D01*
G01X1769665Y83774D02*
Y83768D01*
G01X1769664Y83778D02*
X1769665Y83774D01*
G01X1769663Y83780D02*
X1769664Y83778D01*
G01X1769665Y86924D02*
Y86918D01*
G01X1769664Y86928D02*
X1769665Y86924D01*
G01X1769663Y86929D02*
X1769664Y86928D01*
G01X1769665Y90074D02*
Y90067D01*
G01X1769664Y90078D02*
X1769665Y90074D01*
G01X1769663Y90079D02*
X1769664Y90078D01*
G01X1769665Y93223D02*
Y93217D01*
G01X1769664Y93227D02*
X1769665Y93223D01*
G01X1769663Y93228D02*
X1769664Y93227D01*
G01X1784036Y51975D02*
X1784035Y51982D01*
G01X1784037Y51970D02*
X1784036Y51975D01*
G01X1784038Y51969D02*
X1784037Y51970D01*
G01X1784036Y56975D02*
X1784035Y56982D01*
G01X1784037Y56970D02*
X1784036Y56975D01*
G01X1784038Y56969D02*
X1784037Y56970D01*
G01X1784036Y61975D02*
X1784035Y61982D01*
G01X1784037Y61970D02*
X1784036Y61975D01*
G01X1784038Y61969D02*
X1784037Y61970D01*
G01X1784036Y66975D02*
X1784035Y66982D01*
G01X1784037Y66970D02*
X1784036Y66975D01*
G01X1784038Y66969D02*
X1784037Y66970D01*
G01X1784036Y71975D02*
X1784035Y71982D01*
G01X1784037Y71970D02*
X1784036Y71975D01*
G01X1784038Y71969D02*
X1784037Y71970D01*
G01X1784036Y76975D02*
X1784035Y76982D01*
G01X1784037Y76970D02*
X1784036Y76975D01*
G01X1784038Y76969D02*
X1784037Y76970D01*
G01X1784036Y81975D02*
X1784035Y81982D01*
G01X1784037Y81970D02*
X1784036Y81975D01*
G01X1784038Y81969D02*
X1784037Y81970D01*
G01X1769649Y86931D02*
X1769663Y86929D01*
G01X1769637Y86939D02*
X1769649Y86931D01*
G01X1769625Y86957D02*
X1769637Y86939D01*
G01X1769648Y90081D02*
X1769663Y90079D01*
G01X1769636Y90089D02*
X1769648Y90081D01*
G01X1769624Y90109D02*
X1769636Y90089D01*
G01X1770610Y83813D02*
Y83805D01*
G01X1770609Y83817D02*
X1770610Y83813D01*
G01X1770609Y83819D02*
Y83817D01*
G01X1770610Y86963D02*
Y86955D01*
G01X1770609Y86967D02*
X1770610Y86963D01*
G01X1770609Y86969D02*
Y86967D01*
G01X1770610Y90112D02*
Y90104D01*
G01X1770609Y90117D02*
X1770610Y90112D01*
G01X1770609Y90118D02*
Y90117D01*
G01X1770610Y93262D02*
Y93254D01*
G01X1770609Y93266D02*
X1770610Y93262D01*
G01X1770609Y93268D02*
Y93266D01*
G01X1769648Y83782D02*
X1769663Y83780D01*
G01X1769635Y83791D02*
X1769648Y83782D01*
G01X1769624Y83811D02*
X1769635Y83791D01*
G01X1770609Y84941D02*
X1770610Y84935D01*
G01X1770608Y84948D02*
X1770609Y84941D01*
G01X1770605Y84954D02*
X1770608Y84948D01*
G01X1770609Y88091D02*
X1770610Y88084D01*
G01X1770608Y88097D02*
X1770609Y88091D01*
G01X1770605Y88103D02*
X1770608Y88097D01*
G01X1770609Y91241D02*
X1770610Y91234D01*
G01X1770608Y91247D02*
X1770609Y91241D01*
G01X1770605Y91253D02*
X1770608Y91247D01*
G01X1770571Y83774D02*
X1770572Y83768D01*
G01X1770570Y83778D02*
X1770571Y83774D01*
G01X1770569Y83780D02*
X1770570Y83778D01*
G01X1770571Y86924D02*
X1770572Y86918D01*
G01X1770570Y86928D02*
X1770571Y86924D01*
G01X1770569Y86929D02*
X1770570Y86928D01*
G01X1770571Y90074D02*
X1770572Y90067D01*
G01X1770570Y90077D02*
X1770571Y90074D01*
G01X1770569Y90079D02*
X1770570Y90077D01*
G01X1770571Y93223D02*
X1770572Y93217D01*
G01X1770570Y93227D02*
X1770571Y93223D01*
G01X1770569Y93228D02*
X1770570Y93227D01*
G01X1783051Y52015D02*
Y52024D01*
G01X1783052Y52009D02*
X1783051Y52015D01*
G01X1783053Y52008D02*
X1783052Y52009D01*
G01X1783051Y57015D02*
Y57024D01*
G01X1783052Y57009D02*
X1783051Y57015D01*
G01X1783053Y57008D02*
X1783052Y57009D01*
G01X1783051Y62015D02*
Y62024D01*
G01X1783052Y62009D02*
X1783051Y62015D01*
G01X1783053Y62008D02*
X1783052Y62009D01*
G01X1783051Y67015D02*
Y67024D01*
G01X1783052Y67009D02*
X1783051Y67015D01*
G01X1783053Y67008D02*
X1783052Y67009D01*
G01X1783051Y72015D02*
Y72024D01*
G01X1783052Y72009D02*
X1783051Y72015D01*
G01X1783053Y72008D02*
X1783052Y72009D01*
G01X1783051Y77015D02*
Y77024D01*
G01X1783052Y77009D02*
X1783051Y77015D01*
G01X1783053Y77008D02*
X1783052Y77009D01*
G01X1783051Y82015D02*
Y82024D01*
G01X1783052Y82009D02*
X1783051Y82015D01*
G01X1783053Y82008D02*
X1783052Y82009D01*
G01X1784028Y52152D02*
X1784035Y52125D01*
G01X1784018Y52178D02*
X1784028Y52152D01*
G01X1784006Y52205D02*
X1784018Y52178D01*
G01X1784028Y57152D02*
X1784035Y57125D01*
G01X1784018Y57178D02*
X1784028Y57152D01*
G01X1784006Y57205D02*
X1784018Y57178D01*
G01X1784028Y62152D02*
X1784035Y62125D01*
G01X1784018Y62178D02*
X1784028Y62152D01*
G01X1784006Y62205D02*
X1784018Y62178D01*
G01X1784028Y67152D02*
X1784035Y67125D01*
G01X1784018Y67178D02*
X1784028Y67152D01*
G01X1784006Y67205D02*
X1784018Y67178D01*
G01X1784028Y72152D02*
X1784035Y72125D01*
G01X1784018Y72178D02*
X1784028Y72152D01*
G01X1784006Y72205D02*
X1784018Y72178D01*
G01X1784028Y77152D02*
X1784035Y77125D01*
G01X1784018Y77178D02*
X1784028Y77152D01*
G01X1784006Y77205D02*
X1784018Y77178D01*
G01X1784028Y82152D02*
X1784035Y82125D01*
G01X1784018Y82178D02*
X1784028Y82152D01*
G01X1784006Y82205D02*
X1784018Y82178D01*
G01X1769644Y93233D02*
X1769663Y93228D01*
G01X1769630Y93246D02*
X1769644Y93233D01*
G01X1769624Y93263D02*
X1769630Y93246D01*
G01X1784018Y52003D02*
X1783999Y52008D01*
G01X1784033Y51988D02*
X1784018Y52003D01*
G01X1784038Y51969D02*
X1784033Y51988D01*
G01X1784018Y57003D02*
X1783999Y57008D01*
G01X1784033Y56988D02*
X1784018Y57003D01*
G01X1784038Y56969D02*
X1784033Y56988D01*
G01X1784018Y62003D02*
X1783999Y62008D01*
G01X1784033Y61988D02*
X1784018Y62003D01*
G01X1784038Y61969D02*
X1784033Y61988D01*
G01X1784018Y67003D02*
X1783999Y67008D01*
G01X1784033Y66988D02*
X1784018Y67003D01*
G01X1784038Y66969D02*
X1784033Y66988D01*
G01X1784018Y72003D02*
X1783999Y72008D01*
G01X1784033Y71988D02*
X1784018Y72003D01*
G01X1784038Y71969D02*
X1784033Y71988D01*
G01X1784018Y77003D02*
X1783999Y77008D01*
G01X1784033Y76988D02*
X1784018Y77003D01*
G01X1784038Y76969D02*
X1784033Y76988D01*
G01X1784018Y82003D02*
X1783999Y82008D01*
G01X1784033Y81988D02*
X1784018Y82003D01*
G01X1784038Y81969D02*
X1784033Y81988D01*
G01X1770603Y91242D02*
X1770595Y91250D01*
G01X1770607Y91231D02*
X1770603Y91242D01*
G01X1770609Y91220D02*
X1770607Y91231D01*
G01X1770603Y84943D02*
X1770595Y84951D01*
G01X1770607Y84932D02*
X1770603Y84943D01*
G01X1770609Y84921D02*
X1770607Y84932D01*
G01X1770603Y88092D02*
X1770595Y88100D01*
G01X1770607Y88082D02*
X1770603Y88092D01*
G01X1770609Y88071D02*
X1770607Y88082D01*
G01X1784002Y52106D02*
X1784006Y52205D01*
G01X1783997Y52034D02*
X1784002Y52106D01*
G01X1783999Y52008D02*
X1783997Y52034D01*
G01X1784002Y57106D02*
X1784006Y57205D01*
G01X1783997Y57034D02*
X1784002Y57106D01*
G01X1783999Y57008D02*
X1783997Y57034D01*
G01X1784002Y62106D02*
X1784006Y62205D01*
G01X1783997Y62034D02*
X1784002Y62106D01*
G01X1783999Y62008D02*
X1783997Y62034D01*
G01X1784002Y67106D02*
X1784006Y67205D01*
G01X1783997Y67034D02*
X1784002Y67106D01*
G01X1783999Y67008D02*
X1783997Y67034D01*
G01X1784002Y72106D02*
X1784006Y72205D01*
G01X1783997Y72034D02*
X1784002Y72106D01*
G01X1783999Y72008D02*
X1783997Y72034D01*
G01X1784002Y77106D02*
X1784006Y77205D01*
G01X1783997Y77034D02*
X1784002Y77106D01*
G01X1783999Y77008D02*
X1783997Y77034D01*
G01X1784002Y82106D02*
X1784006Y82205D01*
G01X1783997Y82034D02*
X1784002Y82106D01*
G01X1783999Y82008D02*
X1783997Y82034D01*
G01X1769666Y91444D02*
X1769665Y91457D01*
G01X1769663Y91431D02*
X1769666Y91444D01*
G01X1769663Y91417D02*
Y91431D01*
G01X1769666Y88294D02*
X1769665Y88307D01*
G01X1769663Y88281D02*
X1769666Y88294D01*
G01X1769663Y88268D02*
Y88281D01*
G01X1769666Y85145D02*
X1769665Y85157D01*
G01X1769663Y85132D02*
X1769666Y85145D01*
G01X1769663Y85118D02*
Y85132D01*
G01X1783052Y80628D02*
X1783053Y80630D01*
G01X1783051Y80622D02*
X1783052Y80628D01*
G01X1783051Y80614D02*
Y80622D01*
G01X1783052Y75628D02*
X1783053Y75630D01*
G01X1783051Y75622D02*
X1783052Y75628D01*
G01X1783051Y75614D02*
Y75622D01*
G01X1783052Y70628D02*
X1783053Y70630D01*
G01X1783051Y70622D02*
X1783052Y70628D01*
G01X1783051Y70614D02*
Y70622D01*
G01X1783052Y65628D02*
X1783053Y65630D01*
G01X1783051Y65622D02*
X1783052Y65628D01*
G01X1783051Y65614D02*
Y65622D01*
G01X1783052Y60628D02*
X1783053Y60630D01*
G01X1783051Y60622D02*
X1783052Y60628D01*
G01X1783051Y60614D02*
Y60622D01*
G01X1783052Y55628D02*
X1783053Y55630D01*
G01X1783051Y55622D02*
X1783052Y55628D01*
G01X1783051Y55614D02*
Y55622D01*
G01X1783052Y50628D02*
X1783053Y50630D01*
G01X1783051Y50622D02*
X1783052Y50628D01*
G01X1783051Y50614D02*
Y50622D01*
G01X1769663Y93057D02*
X1769662Y93070D01*
G01X1769666Y93044D02*
X1769663Y93057D01*
G01X1769665Y93031D02*
X1769666Y93044D01*
G01X1769663Y89907D02*
X1769662Y89921D01*
G01X1769666Y89894D02*
X1769663Y89907D01*
G01X1769665Y89882D02*
X1769666Y89894D01*
G01X1769663Y86757D02*
X1769662Y86771D01*
G01X1769666Y86745D02*
X1769663Y86757D01*
G01X1769665Y86732D02*
X1769666Y86745D01*
G01X1769663Y83608D02*
X1769662Y83622D01*
G01X1769666Y83595D02*
X1769663Y83608D01*
G01X1769665Y83583D02*
X1769666Y83595D01*
G01X1770573Y91431D02*
X1770574Y91417D01*
G01X1770570Y91444D02*
X1770573Y91431D01*
G01X1770571Y91457D02*
X1770570Y91444D01*
G01X1770573Y88281D02*
X1770574Y88268D01*
G01X1770570Y88294D02*
X1770573Y88281D01*
G01X1770571Y88307D02*
X1770570Y88294D01*
G01X1770573Y85132D02*
X1770574Y85118D01*
G01X1770570Y85145D02*
X1770573Y85132D01*
G01X1770571Y85157D02*
X1770570Y85145D01*
G01X1769626Y90112D02*
Y90105D01*
G01X1769625Y90117D02*
X1769626Y90112D01*
G01X1769624Y90109D02*
X1769625Y90117D01*
G01X1770570Y93044D02*
X1770571Y93031D01*
G01X1770573Y93057D02*
X1770570Y93044D01*
G01X1770574Y93070D02*
X1770573Y93057D01*
G01X1770570Y89894D02*
X1770571Y89882D01*
G01X1770573Y89907D02*
X1770570Y89894D01*
G01X1770574Y89921D02*
X1770573Y89907D01*
G01X1770570Y86745D02*
X1770571Y86732D01*
G01X1770573Y86757D02*
X1770570Y86745D01*
G01X1770574Y86771D02*
X1770573Y86757D01*
G01X1770570Y83595D02*
X1770571Y83583D01*
G01X1770573Y83608D02*
X1770570Y83595D01*
G01X1770574Y83622D02*
X1770573Y83608D01*
G01X1769626Y83813D02*
Y83806D01*
G01X1769625Y83817D02*
X1769626Y83813D01*
G01X1769624Y83811D02*
X1769625Y83817D01*
G01X1769639Y91251D02*
X1769663Y91260D01*
G01X1769628Y91237D02*
X1769639Y91251D01*
G01X1769626Y91230D02*
X1769628Y91237D01*
G01X1769639Y88102D02*
X1769663Y88110D01*
G01X1769628Y88087D02*
X1769639Y88102D01*
G01X1769626Y88080D02*
X1769628Y88087D01*
G01X1769639Y84952D02*
X1769663Y84961D01*
G01X1769628Y84937D02*
X1769639Y84952D01*
G01X1769626Y84931D02*
X1769628Y84937D01*
G01X1770581Y93230D02*
X1770569Y93228D01*
G01X1770592Y93235D02*
X1770581Y93230D01*
G01Y90081D02*
X1770569Y90079D01*
G01X1770592Y90085D02*
X1770581Y90081D01*
G01Y86931D02*
X1770569Y86929D01*
G01X1770592Y86936D02*
X1770581Y86931D01*
G01Y83781D02*
X1770569Y83780D01*
G01X1770592Y83786D02*
X1770581Y83781D01*
G01X1770610Y91227D02*
Y91234D01*
G01Y91222D02*
Y91227D01*
G01X1770609Y91220D02*
X1770610Y91222D01*
G01Y88077D02*
Y88084D01*
G01Y88072D02*
Y88077D01*
G01X1770609Y88071D02*
X1770610Y88072D01*
G01Y84928D02*
Y84935D01*
G01Y84923D02*
Y84928D01*
G01X1770609Y84921D02*
X1770610Y84923D01*
G01X1769626Y93262D02*
Y93254D01*
G01X1769625Y93266D02*
X1769626Y93262D01*
G01X1769624Y93263D02*
X1769625Y93266D01*
G01X1769626Y86963D02*
Y86955D01*
G01X1769625Y86967D02*
X1769626Y86963D01*
G01X1769624Y86965D02*
X1769625Y86967D01*
G01X1770571Y91265D02*
Y91271D01*
G01X1770570Y91261D02*
X1770571Y91265D01*
G01X1770569Y91260D02*
X1770570Y91261D01*
G01X1770571Y88115D02*
Y88121D01*
G01X1770570Y88111D02*
X1770571Y88115D01*
G01X1770569Y88110D02*
X1770570Y88111D01*
G01X1770571Y84966D02*
Y84972D01*
G01X1770570Y84962D02*
X1770571Y84966D01*
G01X1770569Y84961D02*
X1770570Y84962D01*
G01X1784036Y80622D02*
X1784035Y80613D01*
G01X1784037Y80628D02*
X1784036Y80622D01*
G01X1784038Y80630D02*
X1784037Y80628D01*
G01X1784036Y75622D02*
X1784035Y75613D01*
G01X1784037Y75628D02*
X1784036Y75622D01*
G01X1784038Y75630D02*
X1784037Y75628D01*
G01X1784036Y70622D02*
X1784035Y70613D01*
G01X1784037Y70628D02*
X1784036Y70622D01*
G01X1784038Y70630D02*
X1784037Y70628D01*
G01X1784036Y65622D02*
X1784035Y65613D01*
G01X1784037Y65628D02*
X1784036Y65622D01*
G01X1784038Y65630D02*
X1784037Y65628D01*
G01X1784036Y60622D02*
X1784035Y60613D01*
G01X1784037Y60628D02*
X1784036Y60622D01*
G01X1784038Y60630D02*
X1784037Y60628D01*
G01X1769626Y91226D02*
Y91234D01*
G01X1769625Y91222D02*
X1769626Y91226D01*
G01X1769624Y91220D02*
X1769625Y91222D01*
G01X1769626Y88077D02*
Y88084D01*
G01X1769625Y88072D02*
X1769626Y88077D01*
G01X1769624Y88071D02*
X1769625Y88072D01*
G01X1769626Y84927D02*
Y84935D01*
G01X1769625Y84923D02*
X1769626Y84927D01*
G01X1769624Y84921D02*
X1769625Y84923D01*
G01X1770608Y93242D02*
X1770610Y93254D01*
G01X1770601Y93230D02*
X1770608Y93242D01*
G01X1770591Y93222D02*
X1770601Y93230D01*
G01X1770608Y90092D02*
X1770610Y90104D01*
G01X1770601Y90081D02*
X1770608Y90092D01*
G01X1770591Y90073D02*
X1770601Y90081D01*
G01X1770608Y86943D02*
X1770610Y86955D01*
G01X1770601Y86931D02*
X1770608Y86943D01*
G01X1770591Y86923D02*
X1770601Y86931D01*
G01X1770608Y83793D02*
X1770610Y83805D01*
G01X1770601Y83781D02*
X1770608Y83793D01*
G01X1770591Y83774D02*
X1770601Y83781D01*
G01X1769665Y91265D02*
Y91271D01*
G01Y91261D02*
Y91265D01*
G01X1769663Y91260D02*
X1769665Y91261D01*
G01Y88115D02*
Y88121D01*
G01Y88111D02*
Y88115D01*
G01X1769663Y88110D02*
X1769665Y88111D01*
G01Y84965D02*
Y84972D01*
G01Y84962D02*
Y84965D01*
G01X1769663Y84961D02*
X1769665Y84962D01*
G01X1769627Y91240D02*
X1769626Y91234D01*
G01X1769628Y91246D02*
X1769627Y91240D01*
G01X1769631Y91252D02*
X1769628Y91246D01*
G01X1769635Y91257D02*
X1769631Y91252D01*
G01X1769640Y91262D02*
X1769635Y91257D01*
G01X1769645Y91266D02*
X1769640Y91262D01*
G01X1769627Y88091D02*
X1769626Y88084D01*
G01X1769628Y88097D02*
X1769627Y88091D01*
G01X1769631Y88103D02*
X1769628Y88097D01*
G01X1769635Y88108D02*
X1769631Y88103D01*
G01X1769640Y88113D02*
X1769635Y88108D01*
G01X1769645Y88116D02*
X1769640Y88113D01*
G01X1769627Y84941D02*
X1769626Y84935D01*
G01X1769628Y84947D02*
X1769627Y84941D01*
G01X1769631Y84953D02*
X1769628Y84947D01*
G01X1769635Y84958D02*
X1769631Y84953D01*
G01X1769640Y84963D02*
X1769635Y84958D01*
G01X1769645Y84967D02*
X1769640Y84963D01*
G01X1784036Y55622D02*
X1784035Y55613D01*
G01X1784037Y55628D02*
X1784036Y55622D01*
G01X1784038Y55630D02*
X1784037Y55628D01*
G01X1784036Y50622D02*
X1784035Y50613D01*
G01X1784037Y50628D02*
X1784036Y50622D01*
G01X1784038Y50630D02*
X1784037Y50628D01*
G01X1774606Y25138D02*
G03X1775197Y24547I591J0D01*
G01X1781890D02*
G03X1782480Y25138I0J590D01*
G01X1779724Y26319D02*
G03Y28287I0J984D01*
G01X1777362D02*
G03Y26319I0J-984D01*
G01X1779646Y39508D02*
G03I-1103J0D01*
G01X1781102Y34232D02*
G03X1782283Y35413I0J1181D01*
G01X1774803D02*
G03X1775984Y34232I1181J0D01*
G01X1780118Y39508D02*
G03I-1575J0D01*
G01X1767717Y25728D02*
G03X1769685Y23760I1968J0D01*
G01X1787402D02*
G03X1789370Y25728I0J1968D01*
G01X1774016Y47500D02*
X1772835Y46319D01*
G01X1771063Y44823D02*
X1767717Y41476D01*
G01X1781028Y42579D02*
X1779724Y40610D01*
G01X1775052Y34688D02*
X1777362Y38917D01*
G01X1784035Y51982D02*
X1784036Y51991D01*
G01X1784035Y56982D02*
X1784036Y56991D01*
G01X1784035Y61982D02*
X1784036Y61991D01*
G01X1784035Y66982D02*
X1784036Y66991D01*
G01X1784035Y71982D02*
X1784036Y71991D01*
G01X1784035Y76982D02*
X1784036Y76991D01*
G01X1784035Y81982D02*
X1784036Y81991D01*
G01X1770610Y84923D02*
Y84935D01*
G01Y88073D02*
Y88084D01*
G01Y91222D02*
Y91234D01*
G01X1789370Y25728D02*
Y41476D01*
G01X1788386Y80630D02*
Y82008D01*
G01Y75630D02*
Y77008D01*
G01Y70630D02*
Y72008D01*
G01Y65630D02*
Y67008D01*
G01Y60630D02*
Y62008D01*
G01Y55630D02*
Y57008D01*
G01Y50630D02*
Y52008D01*
G01X1786024Y182815D02*
Y44823D01*
G01X1785433Y185059D02*
Y42579D01*
G01X1785217Y52008D02*
Y50630D01*
G01Y57008D02*
Y55630D01*
G01Y62008D02*
Y60630D01*
G01Y67008D02*
Y65630D01*
G01Y72008D02*
Y70630D01*
G01Y77008D02*
Y75630D01*
G01Y82008D02*
Y80630D01*
G01X1784646Y104862D02*
Y82776D01*
G01X1784035Y51982D02*
Y52125D01*
G01Y61982D02*
Y62125D01*
G01Y56982D02*
Y57125D01*
G01Y71982D02*
Y72125D01*
G01Y66982D02*
Y67125D01*
G01Y81982D02*
Y82125D01*
G01Y76982D02*
Y77125D01*
G01Y80138D02*
Y82500D01*
G01Y75138D02*
Y77500D01*
G01Y70138D02*
Y72500D01*
G01Y65138D02*
Y67500D01*
G01Y60138D02*
Y62500D01*
G01Y55138D02*
Y57500D01*
G01Y50138D02*
Y52500D01*
G01X1783465Y103681D02*
Y83957D01*
G01X1783051Y52500D02*
Y50138D01*
G01Y57500D02*
Y55138D01*
G01Y62500D02*
Y60138D01*
G01Y67500D02*
Y65138D01*
G01Y72500D02*
Y70138D01*
G01Y77500D02*
Y75138D01*
G01Y82500D02*
Y80138D01*
G01X1782480Y31240D02*
Y25138D01*
G01X1782283Y43957D02*
Y35413D01*
G01X1780709Y82776D02*
Y46319D01*
G01X1779724Y40610D02*
Y38917D01*
G01X1779528Y83957D02*
Y47500D01*
G01X1777362Y38917D02*
Y40610D01*
G01X1774803Y35413D02*
Y43957D01*
G01X1774606Y31240D02*
Y25138D01*
G01X1774016Y47500D02*
Y180138D01*
G01X1772835Y46319D02*
Y181319D01*
G01X1771063Y81614D02*
Y42579D01*
G01X1770610Y93070D02*
Y94567D01*
G01Y89921D02*
Y91417D01*
G01Y86771D02*
Y88268D01*
G01Y83622D02*
Y85118D01*
G01X1770571Y86918D02*
Y86771D01*
G01Y83768D02*
Y83621D01*
G01Y85119D02*
Y84972D01*
G01Y90067D02*
Y89920D01*
G01Y91418D02*
Y91271D01*
G01Y88268D02*
Y88121D01*
G01Y93217D02*
Y93070D01*
G01X1769665D02*
Y93217D01*
G01Y89920D02*
Y90067D01*
G01Y91271D02*
Y91418D01*
G01Y88121D02*
Y88268D01*
G01Y86771D02*
Y86918D01*
G01Y83621D02*
Y83768D01*
G01Y84972D02*
Y85119D01*
G01X1769626Y85118D02*
Y83622D01*
G01Y91417D02*
Y89921D01*
G01Y88268D02*
Y86772D01*
G01Y94567D02*
Y93071D01*
G01X1768445Y88110D02*
Y86929D01*
G01Y84961D02*
Y83780D01*
G01Y91260D02*
Y90079D01*
G01Y94409D02*
Y93228D01*
G01X1768110Y106024D02*
Y81614D01*
G01X1767717D02*
Y106024D01*
G01Y41476D02*
Y25728D01*
G01X1764685Y93228D02*
Y94409D01*
G01Y90079D02*
Y91260D01*
G01Y86929D02*
Y88110D01*
G01Y83780D02*
Y84961D01*
G01X1770610Y93254D02*
Y93265D01*
G01Y90105D02*
Y90115D01*
G01Y86955D02*
Y86966D01*
G01Y83806D02*
Y83816D01*
G01X1779724Y38917D02*
X1782035Y34688D01*
G01X1777362Y40610D02*
X1776059Y42579D01*
G01X1783465Y83957D02*
X1784646Y82776D01*
G01X1779528Y83957D02*
X1780709Y82776D01*
G01X1789370Y41476D02*
X1786024Y44823D01*
G01X1779528Y47500D02*
X1780709Y46319D01*
G01X1769624Y93263D02*
X1769513Y93268D01*
G01X1769624Y86965D02*
X1769513Y86969D01*
G01X1768879Y93268D02*
X1768445D01*
G01X1770609D02*
X1764685D01*
G01X1770569Y93228D02*
X1764685D01*
G01X1769626Y93071D02*
X1770610D01*
G01X1769665Y93031D02*
X1770571D01*
G01Y91457D02*
X1769665D01*
G01X1770610Y91417D02*
X1769626D01*
G01X1770569Y91260D02*
X1764685D01*
G01Y91220D02*
X1770609D01*
G01Y90118D02*
X1764685D01*
G01X1770569Y90079D02*
X1764685D01*
G01X1769626Y89921D02*
X1770610D01*
G01X1769665Y89882D02*
X1770571D01*
G01Y88307D02*
X1769665D01*
G01X1770610Y88268D02*
X1769626D01*
G01X1770569Y88110D02*
X1764685D01*
G01Y88071D02*
X1770609D01*
G01X1768879Y86969D02*
X1768445D01*
G01X1770609D02*
X1764685D01*
G01X1770569Y86929D02*
X1764685D01*
G01X1769626Y86772D02*
X1770610D01*
G01X1769665Y86732D02*
X1770571D01*
G01Y85157D02*
X1769665D01*
G01X1770610Y85118D02*
X1769626D01*
G01X1770569Y84961D02*
X1764685D01*
G01Y84921D02*
X1770609D01*
G01X1783465Y83957D02*
X1779528D01*
G01X1770609Y83819D02*
X1764685D01*
G01X1770569Y83780D02*
X1764685D01*
G01X1769626Y83622D02*
X1770610D01*
G01X1769665Y83583D02*
X1770571D01*
G01X1784646Y82776D02*
X1780709D01*
G01X1784035Y82500D02*
X1783051D01*
G01X1783053Y82008D02*
X1788386D01*
G01Y81969D02*
X1784038D01*
G01X1771063Y81614D02*
X1767717D01*
G01X1788386Y80630D02*
X1783053D01*
G01X1783051Y80138D02*
X1784035D01*
G01Y77500D02*
X1783051D01*
G01X1783053Y77008D02*
X1788386D01*
G01Y76969D02*
X1784038D01*
G01X1788386Y75630D02*
X1783053D01*
G01X1783051Y75138D02*
X1784035D01*
G01Y72500D02*
X1783051D01*
G01X1783053Y72008D02*
X1788386D01*
G01Y71969D02*
X1784038D01*
G01X1788386Y70630D02*
X1783053D01*
G01X1783051Y70138D02*
X1784035D01*
G01Y67500D02*
X1783051D01*
G01X1783053Y67008D02*
X1788386D01*
G01Y66969D02*
X1784038D01*
G01X1788386Y65630D02*
X1783053D01*
G01X1783051Y65138D02*
X1784035D01*
G01Y62500D02*
X1783051D01*
G01X1783053Y62008D02*
X1788386D01*
G01Y61969D02*
X1784038D01*
G01X1788386Y60630D02*
X1783053D01*
G01X1783051Y60138D02*
X1784035D01*
G01Y57500D02*
X1783051D01*
G01X1783053Y57008D02*
X1788386D01*
G01Y56969D02*
X1784038D01*
G01X1788386Y55630D02*
X1783053D01*
G01X1783051Y55138D02*
X1784035D01*
G01Y52500D02*
X1783051D01*
G01X1783053Y52008D02*
X1788386D01*
G01Y51969D02*
X1784038D01*
G01X1788386Y50630D02*
X1783053D01*
G01X1783051Y50138D02*
X1784035D01*
G01X1779528Y47500D02*
X1774016D01*
G01X1780709Y46319D02*
X1772835D01*
G01X1786024Y44823D02*
X1771063D01*
G01X1782283Y43957D02*
X1785433D01*
G01X1774803D02*
X1771063D01*
G01Y42579D02*
X1785433D01*
G01X1779724Y40610D02*
X1777362D01*
G01X1779724Y38917D02*
X1777362D01*
G01X1783051Y82204D02*
X1784006Y82205D01*
G01X1784035Y80434D02*
X1783051Y80433D01*
G01Y77204D02*
X1784006Y77205D01*
G01X1784035Y75434D02*
X1783051Y75433D01*
G01Y72204D02*
X1784006Y72205D01*
G01X1784035Y70434D02*
X1783051Y70433D01*
G01Y67204D02*
X1784006Y67205D01*
G01X1784035Y65434D02*
X1783051Y65433D01*
G01Y62204D02*
X1784006Y62205D01*
G01X1784035Y60434D02*
X1783051Y60433D01*
G01Y57204D02*
X1784006Y57205D01*
G01X1784035Y55434D02*
X1783051Y55433D01*
G01Y52204D02*
X1784006Y52205D01*
G01X1784035Y50434D02*
X1783051Y50433D01*
G01X1781102Y34232D02*
X1775984D01*
G01X1789370Y34193D02*
X1767717D01*
G01X1782480Y31240D02*
X1774606D01*
G01Y29665D02*
X1782480D01*
G01X1779724Y28287D02*
X1777362D01*
G01Y26319D02*
X1779724D01*
G01X1781890Y24547D02*
X1775197D01*
G01X1787402Y23760D02*
X1769685D01*
G01X1769629Y94390D02*
X1769624Y94370D01*
G01X1769643Y94404D02*
X1769629Y94390D01*
G01X1769663Y94409D02*
X1769643Y94404D01*
G01X1769629Y97539D02*
X1769624Y97520D01*
G01X1769643Y97554D02*
X1769629Y97539D01*
G01X1769663Y97559D02*
X1769643Y97554D01*
G01X1769629Y100689D02*
X1769624Y100669D01*
G01X1769643Y100703D02*
X1769629Y100689D01*
G01X1769663Y100709D02*
X1769643Y100703D01*
G01X1769629Y103839D02*
X1769624Y103819D01*
G01X1769643Y103853D02*
X1769629Y103839D01*
G01X1769663Y103858D02*
X1769643Y103853D01*
G01X1770604Y96398D02*
X1770609Y96417D01*
G01X1770589Y96383D02*
X1770604Y96398D01*
G01X1770569Y96378D02*
X1770589Y96383D01*
G01X1770604Y99547D02*
X1770609Y99567D01*
G01X1770589Y99533D02*
X1770604Y99547D01*
G01X1770569Y99528D02*
X1770589Y99533D01*
G01X1770604Y102697D02*
X1770609Y102717D01*
G01X1770589Y102682D02*
X1770604Y102697D01*
G01X1770569Y102677D02*
X1770589Y102682D01*
G01X1770609Y99546D02*
X1770610Y99553D01*
G01X1770607Y99539D02*
X1770609Y99546D01*
G01X1770604Y99533D02*
X1770607Y99539D01*
G01X1770599Y99527D02*
X1770604Y99533D01*
G01X1770593Y99522D02*
X1770599Y99527D01*
G01X1770586Y99519D02*
X1770593Y99522D01*
G01X1770579Y99517D02*
X1770586Y99519D01*
G01X1770571Y99516D02*
X1770579Y99517D01*
G01X1769648Y94417D02*
X1769645Y94415D01*
G01X1769652Y94418D02*
X1769648Y94417D01*
G01X1769655Y94419D02*
X1769652Y94418D01*
G01X1769658Y94420D02*
X1769655Y94419D01*
G01X1769662Y94420D02*
X1769658D01*
G01X1769665D02*
X1769662D01*
G01X1770588Y96370D02*
X1770591Y96372D01*
G01X1770585Y96369D02*
X1770588Y96370D01*
G01X1770581Y96368D02*
X1770585Y96369D01*
G01X1770578Y96367D02*
X1770581Y96368D01*
G01X1770574Y96367D02*
X1770578D01*
G01X1770571D02*
X1770574D01*
G01X1769648Y97567D02*
X1769645Y97565D01*
G01X1769652Y97568D02*
X1769648Y97567D01*
G01X1769655Y97569D02*
X1769652Y97568D01*
G01X1769658Y97570D02*
X1769655Y97569D01*
G01X1769662Y97570D02*
X1769658D01*
G01X1769665D02*
X1769662D01*
G01X1769648Y100716D02*
X1769645Y100715D01*
G01X1769652Y100717D02*
X1769648Y100716D01*
G01X1769655Y100719D02*
X1769652Y100717D01*
G01X1769658Y100719D02*
X1769655D01*
G01X1769662Y100720D02*
X1769658Y100719D01*
G01X1769665Y100720D02*
X1769662D01*
G01X1770588Y102669D02*
X1770591Y102671D01*
G01X1770585Y102668D02*
X1770588Y102669D01*
G01X1770581Y102667D02*
X1770585Y102668D01*
G01X1770578Y102667D02*
X1770581D01*
G01X1770574Y102666D02*
X1770578Y102667D01*
G01X1770571Y102666D02*
X1770574D01*
G01X1769648Y103866D02*
X1769645Y103864D01*
G01X1769652Y103867D02*
X1769648Y103866D01*
G01X1769655Y103868D02*
X1769652Y103867D01*
G01X1769658Y103869D02*
X1769655Y103868D01*
G01X1769662Y103869D02*
X1769658D01*
G01X1769665D02*
X1769662D01*
G01X1770601Y94408D02*
X1770605Y94402D01*
G01X1770596Y94412D02*
X1770601Y94408D01*
G01X1770590Y94416D02*
X1770596Y94412D01*
G01X1770584Y94419D02*
X1770590Y94416D01*
G01X1770578Y94420D02*
X1770584Y94419D01*
G01X1770571Y94420D02*
X1770578D01*
G01X1770601Y97557D02*
X1770605Y97552D01*
G01X1770596Y97562D02*
X1770601Y97557D01*
G01X1770590Y97565D02*
X1770596Y97562D01*
G01X1770584Y97568D02*
X1770590Y97565D01*
G01X1770578Y97570D02*
X1770584Y97568D01*
G01X1770571Y97570D02*
X1770578D01*
G01X1770601Y100707D02*
X1770605Y100702D01*
G01X1770596Y100711D02*
X1770601Y100707D01*
G01X1770590Y100715D02*
X1770596Y100711D01*
G01X1770584Y100718D02*
X1770590Y100715D01*
G01X1770578Y100719D02*
X1770584Y100718D01*
G01X1770571Y100720D02*
X1770578Y100719D01*
G01X1770601Y103857D02*
X1770605Y103851D01*
G01X1770596Y103861D02*
X1770601Y103857D01*
G01X1770590Y103865D02*
X1770596Y103861D01*
G01X1770584Y103867D02*
X1770590Y103865D01*
G01X1770578Y103869D02*
X1770584Y103867D01*
G01X1770571Y103869D02*
X1770578D01*
G01X1769627Y96396D02*
X1769626Y96404D01*
G01X1769629Y96389D02*
X1769627Y96396D01*
G01X1769633Y96383D02*
X1769629Y96389D01*
G01X1769637Y96378D02*
X1769633Y96383D01*
G01X1769644Y96373D02*
X1769637Y96378D01*
G01X1769650Y96369D02*
X1769644Y96373D01*
G01X1769658Y96367D02*
X1769650Y96369D01*
G01X1769665Y96367D02*
X1769658D01*
G01X1769627Y99546D02*
X1769626Y99553D01*
G01X1769629Y99539D02*
X1769627Y99546D01*
G01X1769633Y99533D02*
X1769629Y99539D01*
G01X1769637Y99527D02*
X1769633Y99533D01*
G01X1769644Y99522D02*
X1769637Y99527D01*
G01X1769650Y99519D02*
X1769644Y99522D01*
G01X1769658Y99517D02*
X1769650Y99519D01*
G01X1769665Y99516D02*
X1769658Y99517D01*
G01X1769627Y102696D02*
X1769626Y102703D01*
G01X1769629Y102689D02*
X1769627Y102696D01*
G01X1769633Y102682D02*
X1769629Y102689D01*
G01X1769637Y102677D02*
X1769633Y102682D01*
G01X1769644Y102672D02*
X1769637Y102677D01*
G01X1769650Y102669D02*
X1769644Y102672D01*
G01X1769658Y102667D02*
X1769650Y102669D01*
G01X1769665Y102666D02*
X1769658Y102667D01*
G01X1770580Y94408D02*
X1770589Y94404D01*
G01X1770569Y94409D02*
X1770580Y94408D01*
G01Y97557D02*
X1770589Y97554D01*
G01X1770569Y97559D02*
X1770580Y97557D01*
G01Y100707D02*
X1770589Y100703D01*
G01X1770569Y100709D02*
X1770580Y100707D01*
G01Y103857D02*
X1770589Y103853D01*
G01X1770569Y103858D02*
X1770580Y103857D01*
G01X1769626Y96407D02*
Y96404D01*
G01X1769628Y96401D02*
X1769626Y96407D01*
G01X1769639Y96386D02*
X1769628Y96401D01*
G01X1769663Y96378D02*
X1769639Y96386D01*
G01X1769626Y99557D02*
Y99553D01*
G01X1769628Y99551D02*
X1769626Y99557D01*
G01X1769639Y99536D02*
X1769628Y99551D01*
G01X1769663Y99528D02*
X1769639Y99536D01*
G01X1769626Y102707D02*
Y102703D01*
G01X1769628Y102701D02*
X1769626Y102707D01*
G01X1769639Y102685D02*
X1769628Y102701D01*
G01X1769663Y102677D02*
X1769639Y102685D01*
G01X1784023Y106999D02*
X1784034Y106984D01*
G01X1783998Y107008D02*
X1784023Y106999D01*
G01Y111999D02*
X1784034Y111984D01*
G01X1783998Y112008D02*
X1784023Y111999D01*
G01Y116999D02*
X1784034Y116984D01*
G01X1783998Y117008D02*
X1784023Y116999D01*
G01Y121999D02*
X1784034Y121984D01*
G01X1783998Y122008D02*
X1784023Y121999D01*
G01Y126999D02*
X1784034Y126984D01*
G01X1783998Y127008D02*
X1784023Y126999D01*
G01Y131999D02*
X1784034Y131984D01*
G01X1783998Y132008D02*
X1784023Y131999D01*
G01Y136999D02*
X1784034Y136984D01*
G01X1783998Y137008D02*
X1784023Y136999D01*
G01Y141999D02*
X1784034Y141984D01*
G01X1783998Y142008D02*
X1784023Y141999D01*
G01Y146999D02*
X1784034Y146984D01*
G01X1783998Y147008D02*
X1784023Y146999D01*
G01Y151999D02*
X1784034Y151984D01*
G01X1783998Y152008D02*
X1784023Y151999D01*
G01Y156999D02*
X1784034Y156984D01*
G01X1783998Y157008D02*
X1784023Y156999D01*
G01Y161999D02*
X1784034Y161984D01*
G01X1783998Y162008D02*
X1784023Y161999D01*
G01Y166999D02*
X1784034Y166984D01*
G01X1783998Y167008D02*
X1784023Y166999D01*
G01Y171999D02*
X1784034Y171984D01*
G01X1783998Y172008D02*
X1784023Y171999D01*
G01Y176999D02*
X1784034Y176984D01*
G01X1783998Y177008D02*
X1784023Y176999D01*
G01X1770579Y94408D02*
X1770569Y94409D01*
G01X1770588Y94405D02*
X1770579Y94408D01*
G01X1770595Y94400D02*
X1770588Y94405D01*
G01X1770579Y97558D02*
X1770569Y97559D01*
G01X1770588Y97555D02*
X1770579Y97558D01*
G01X1770595Y97549D02*
X1770588Y97555D01*
G01X1770579Y100707D02*
X1770569Y100709D01*
G01X1770588Y100704D02*
X1770579Y100707D01*
G01X1770595Y100699D02*
X1770588Y100704D01*
G01X1770579Y103857D02*
X1770569Y103858D01*
G01X1770588Y103854D02*
X1770579Y103857D01*
G01X1770595Y103848D02*
X1770588Y103854D01*
G01X1769665Y96373D02*
Y96367D01*
G01X1769664Y96377D02*
X1769665Y96373D01*
G01X1769663Y96378D02*
X1769664Y96377D01*
G01X1769665Y99522D02*
Y99516D01*
G01X1769664Y99526D02*
X1769665Y99522D01*
G01X1769663Y99528D02*
X1769664Y99526D01*
G01X1769665Y102672D02*
Y102666D01*
G01X1769664Y102676D02*
X1769665Y102672D01*
G01X1769663Y102677D02*
X1769664Y102676D01*
G01X1784036Y106975D02*
X1784035Y106982D01*
G01X1784037Y106970D02*
X1784036Y106975D01*
G01X1784038Y106969D02*
X1784037Y106970D01*
G01X1784036Y111975D02*
X1784035Y111982D01*
G01X1784037Y111970D02*
X1784036Y111975D01*
G01X1784038Y111969D02*
X1784037Y111970D01*
G01X1784036Y116975D02*
X1784035Y116982D01*
G01X1784037Y116970D02*
X1784036Y116975D01*
G01X1784038Y116969D02*
X1784037Y116970D01*
G01X1784036Y121975D02*
X1784035Y121982D01*
G01X1784037Y121970D02*
X1784036Y121975D01*
G01X1784038Y121969D02*
X1784037Y121970D01*
G01X1784036Y126975D02*
X1784035Y126982D01*
G01X1784037Y126970D02*
X1784036Y126975D01*
G01X1784038Y126969D02*
X1784037Y126970D01*
G01X1784036Y131975D02*
X1784035Y131982D01*
G01X1784037Y131970D02*
X1784036Y131975D01*
G01X1784038Y131969D02*
X1784037Y131970D01*
G01X1784036Y136975D02*
X1784035Y136982D01*
G01X1784037Y136970D02*
X1784036Y136975D01*
G01X1784038Y136969D02*
X1784037Y136970D01*
G01X1784036Y141975D02*
X1784035Y141982D01*
G01X1784037Y141970D02*
X1784036Y141975D01*
G01X1784038Y141969D02*
X1784037Y141970D01*
G01X1784036Y146975D02*
X1784035Y146982D01*
G01X1784037Y146970D02*
X1784036Y146975D01*
G01X1784038Y146969D02*
X1784037Y146970D01*
G01X1784036Y151975D02*
X1784035Y151982D01*
G01X1784037Y151970D02*
X1784036Y151975D01*
G01X1784038Y151969D02*
X1784037Y151970D01*
G01X1784036Y156975D02*
X1784035Y156982D01*
G01X1784037Y156970D02*
X1784036Y156975D01*
G01X1784038Y156969D02*
X1784037Y156970D01*
G01X1784036Y161975D02*
X1784035Y161982D01*
G01X1784037Y161970D02*
X1784036Y161975D01*
G01X1784038Y161969D02*
X1784037Y161970D01*
G01X1784036Y166975D02*
X1784035Y166982D01*
G01X1784037Y166970D02*
X1784036Y166975D01*
G01X1784038Y166969D02*
X1784037Y166970D01*
G01X1784036Y171975D02*
X1784035Y171982D01*
G01X1784037Y171970D02*
X1784036Y171975D01*
G01X1784038Y171969D02*
X1784037Y171970D01*
G01X1784036Y176975D02*
X1784035Y176982D01*
G01X1784037Y176970D02*
X1784036Y176975D01*
G01X1784038Y176969D02*
X1784037Y176970D01*
G01X1769649Y96380D02*
X1769663Y96378D01*
G01X1769637Y96388D02*
X1769649Y96380D01*
G01X1769625Y96406D02*
X1769637Y96388D01*
G01X1769648Y99530D02*
X1769663Y99528D01*
G01X1769636Y99538D02*
X1769648Y99530D01*
G01X1769624Y99558D02*
X1769636Y99538D01*
G01X1770610Y96411D02*
Y96404D01*
G01X1770609Y96416D02*
X1770610Y96411D01*
G01X1770609Y96417D02*
Y96416D01*
G01X1770610Y99561D02*
Y99553D01*
G01X1770609Y99565D02*
X1770610Y99561D01*
G01X1770609Y99567D02*
Y99565D01*
G01X1770610Y102711D02*
Y102703D01*
G01X1770609Y102715D02*
X1770610Y102711D01*
G01X1770609Y102717D02*
Y102715D01*
G01X1769648Y102680D02*
X1769663Y102677D01*
G01X1769636Y102688D02*
X1769648Y102680D01*
G01X1769624Y102708D02*
X1769636Y102688D01*
G01X1770609Y94390D02*
X1770610Y94383D01*
G01X1770608Y94396D02*
X1770609Y94390D01*
G01X1770605Y94402D02*
X1770608Y94396D01*
G01X1770609Y97540D02*
X1770610Y97533D01*
G01X1770608Y97546D02*
X1770609Y97540D01*
G01X1770605Y97552D02*
X1770608Y97546D01*
G01X1770609Y100689D02*
X1770610Y100683D01*
G01X1770608Y100696D02*
X1770609Y100689D01*
G01X1770605Y100702D02*
X1770608Y100696D01*
G01X1770609Y103839D02*
X1770610Y103832D01*
G01X1770608Y103845D02*
X1770609Y103839D01*
G01X1770605Y103851D02*
X1770608Y103845D01*
G01X1770571Y96373D02*
X1770572Y96367D01*
G01X1770570Y96376D02*
X1770571Y96373D01*
G01X1770569Y96378D02*
X1770570Y96376D01*
G01X1770571Y102672D02*
X1770572Y102666D01*
G01X1770570Y102676D02*
X1770571Y102672D01*
G01X1770569Y102677D02*
X1770570Y102676D01*
G01X1783051Y107015D02*
Y107024D01*
G01X1783052Y107009D02*
X1783051Y107015D01*
G01X1783053Y107008D02*
X1783052Y107009D01*
G01X1783051Y112015D02*
Y112024D01*
G01X1783052Y112009D02*
X1783051Y112015D01*
G01X1783053Y112008D02*
X1783052Y112009D01*
G01X1783051Y117015D02*
Y117024D01*
G01X1783052Y117009D02*
X1783051Y117015D01*
G01X1783053Y117008D02*
X1783052Y117009D01*
G01X1783051Y122015D02*
Y122024D01*
G01X1783052Y122009D02*
X1783051Y122015D01*
G01X1783053Y122008D02*
X1783052Y122009D01*
G01X1783051Y127015D02*
Y127024D01*
G01X1783052Y127009D02*
X1783051Y127015D01*
G01X1783053Y127008D02*
X1783052Y127009D01*
G01X1783051Y132015D02*
Y132024D01*
G01X1783052Y132009D02*
X1783051Y132015D01*
G01X1783053Y132008D02*
X1783052Y132009D01*
G01X1783051Y137015D02*
Y137024D01*
G01X1783052Y137009D02*
X1783051Y137015D01*
G01X1783053Y137008D02*
X1783052Y137009D01*
G01X1783051Y142015D02*
Y142024D01*
G01X1783052Y142009D02*
X1783051Y142015D01*
G01X1783053Y142008D02*
X1783052Y142009D01*
G01X1783051Y147015D02*
Y147024D01*
G01X1783052Y147009D02*
X1783051Y147015D01*
G01X1783053Y147008D02*
X1783052Y147009D01*
G01X1783051Y152015D02*
Y152024D01*
G01X1783052Y152009D02*
X1783051Y152015D01*
G01X1783053Y152008D02*
X1783052Y152009D01*
G01X1783051Y157015D02*
Y157024D01*
G01X1783052Y157009D02*
X1783051Y157015D01*
G01X1783053Y157008D02*
X1783052Y157009D01*
G01X1784028Y107152D02*
X1784035Y107125D01*
G01X1784018Y107178D02*
X1784028Y107152D01*
G01X1784006Y107205D02*
X1784018Y107178D01*
G01X1784028Y112152D02*
X1784035Y112125D01*
G01X1784018Y112178D02*
X1784028Y112152D01*
G01X1784006Y112205D02*
X1784018Y112178D01*
G01X1784028Y117152D02*
X1784035Y117125D01*
G01X1784018Y117178D02*
X1784028Y117152D01*
G01X1784006Y117205D02*
X1784018Y117178D01*
G01X1784028Y122152D02*
X1784035Y122125D01*
G01X1784018Y122178D02*
X1784028Y122152D01*
G01X1784006Y122205D02*
X1784018Y122178D01*
G01X1784028Y127152D02*
X1784035Y127125D01*
G01X1784018Y127178D02*
X1784028Y127152D01*
G01X1784006Y127205D02*
X1784018Y127178D01*
G01X1784028Y132152D02*
X1784035Y132125D01*
G01X1784018Y132178D02*
X1784028Y132152D01*
G01X1784006Y132205D02*
X1784018Y132178D01*
G01X1784028Y137152D02*
X1784035Y137125D01*
G01X1784018Y137178D02*
X1784028Y137152D01*
G01X1784006Y137205D02*
X1784018Y137178D01*
G01X1784028Y142152D02*
X1784035Y142125D01*
G01X1784018Y142178D02*
X1784028Y142152D01*
G01X1784006Y142205D02*
X1784018Y142178D01*
G01X1783051Y162015D02*
Y162024D01*
G01X1783052Y162009D02*
X1783051Y162015D01*
G01X1783053Y162008D02*
X1783052Y162009D01*
G01X1783051Y167015D02*
Y167024D01*
G01X1783052Y167009D02*
X1783051Y167015D01*
G01X1783053Y167008D02*
X1783052Y167009D01*
G01X1783051Y172015D02*
Y172024D01*
G01X1783052Y172009D02*
X1783051Y172015D01*
G01X1783053Y172008D02*
X1783052Y172009D01*
G01X1783051Y177015D02*
Y177024D01*
G01X1783052Y177009D02*
X1783051Y177015D01*
G01X1783053Y177008D02*
X1783052Y177009D01*
G01X1784028Y147152D02*
X1784035Y147125D01*
G01X1784018Y147178D02*
X1784028Y147152D01*
G01X1784006Y147205D02*
X1784018Y147178D01*
G01X1784028Y152152D02*
X1784035Y152125D01*
G01X1784018Y152178D02*
X1784028Y152152D01*
G01X1784006Y152205D02*
X1784018Y152178D01*
G01X1784028Y157152D02*
X1784035Y157125D01*
G01X1784018Y157178D02*
X1784028Y157152D01*
G01X1784006Y157205D02*
X1784018Y157178D01*
G01X1784028Y162152D02*
X1784035Y162125D01*
G01X1784018Y162178D02*
X1784028Y162152D01*
G01X1784006Y162205D02*
X1784018Y162178D01*
G01X1784028Y167152D02*
X1784035Y167125D01*
G01X1784018Y167178D02*
X1784028Y167152D01*
G01X1784006Y167205D02*
X1784018Y167178D01*
G01X1784028Y172152D02*
X1784035Y172125D01*
G01X1784018Y172178D02*
X1784028Y172152D01*
G01X1784006Y172205D02*
X1784018Y172178D01*
G01X1784028Y177152D02*
X1784035Y177125D01*
G01X1784018Y177178D02*
X1784028Y177152D01*
G01X1784006Y177205D02*
X1784018Y177178D01*
G01Y107003D02*
X1783999Y107008D01*
G01X1784033Y106988D02*
X1784018Y107003D01*
G01X1784038Y106969D02*
X1784033Y106988D01*
G01X1784018Y112003D02*
X1783999Y112008D01*
G01X1784033Y111988D02*
X1784018Y112003D01*
G01X1784038Y111969D02*
X1784033Y111988D01*
G01X1784018Y117003D02*
X1783999Y117008D01*
G01X1784033Y116988D02*
X1784018Y117003D01*
G01X1784038Y116969D02*
X1784033Y116988D01*
G01X1784018Y122003D02*
X1783999Y122008D01*
G01X1784033Y121988D02*
X1784018Y122003D01*
G01X1784038Y121969D02*
X1784033Y121988D01*
G01X1784018Y127003D02*
X1783999Y127008D01*
G01X1784033Y126988D02*
X1784018Y127003D01*
G01X1784038Y126969D02*
X1784033Y126988D01*
G01X1784018Y132003D02*
X1783999Y132008D01*
G01X1784033Y131988D02*
X1784018Y132003D01*
G01X1784038Y131969D02*
X1784033Y131988D01*
G01X1784018Y137003D02*
X1783999Y137008D01*
G01X1784033Y136988D02*
X1784018Y137003D01*
G01X1784038Y136969D02*
X1784033Y136988D01*
G01X1784018Y142003D02*
X1783999Y142008D01*
G01X1784033Y141988D02*
X1784018Y142003D01*
G01X1784038Y141969D02*
X1784033Y141988D01*
G01X1784018Y147003D02*
X1783999Y147008D01*
G01X1784033Y146988D02*
X1784018Y147003D01*
G01X1784038Y146969D02*
X1784033Y146988D01*
G01X1784018Y152003D02*
X1783999Y152008D01*
G01X1784033Y151988D02*
X1784018Y152003D01*
G01X1784038Y151969D02*
X1784033Y151988D01*
G01X1784018Y157003D02*
X1783999Y157008D01*
G01X1784033Y156988D02*
X1784018Y157003D01*
G01X1784038Y156969D02*
X1784033Y156988D01*
G01X1784018Y162003D02*
X1783999Y162008D01*
G01X1784033Y161988D02*
X1784018Y162003D01*
G01X1784038Y161969D02*
X1784033Y161988D01*
G01X1784018Y167003D02*
X1783999Y167008D01*
G01X1784033Y166988D02*
X1784018Y167003D01*
G01X1784038Y166969D02*
X1784033Y166988D01*
G01X1784018Y172003D02*
X1783999Y172008D01*
G01X1784033Y171988D02*
X1784018Y172003D01*
G01X1784038Y171969D02*
X1784033Y171988D01*
G01X1784018Y177003D02*
X1783999Y177008D01*
G01X1784033Y176988D02*
X1784018Y177003D01*
G01X1784038Y176969D02*
X1784033Y176988D01*
G01X1770603Y94391D02*
X1770595Y94400D01*
G01X1770607Y94381D02*
X1770603Y94391D01*
G01X1770609Y94370D02*
X1770607Y94381D01*
G01X1770603Y97541D02*
X1770595Y97549D01*
G01X1770607Y97531D02*
X1770603Y97541D01*
G01X1770609Y97520D02*
X1770607Y97531D01*
G01X1770603Y100691D02*
X1770595Y100699D01*
G01X1770607Y100680D02*
X1770603Y100691D01*
G01X1770609Y100669D02*
X1770607Y100680D01*
G01X1770603Y103840D02*
X1770595Y103848D01*
G01X1770607Y103830D02*
X1770603Y103840D01*
G01X1770609Y103819D02*
X1770607Y103830D01*
G01X1784002Y107106D02*
X1784006Y107205D01*
G01X1783997Y107034D02*
X1784002Y107106D01*
G01X1783999Y107008D02*
X1783997Y107034D01*
G01X1784002Y112106D02*
X1784006Y112205D01*
G01X1783997Y112034D02*
X1784002Y112106D01*
G01X1783999Y112008D02*
X1783997Y112034D01*
G01X1784002Y117106D02*
X1784006Y117205D01*
G01X1783997Y117034D02*
X1784002Y117106D01*
G01X1783999Y117008D02*
X1783997Y117034D01*
G01X1784002Y122106D02*
X1784006Y122205D01*
G01X1783997Y122034D02*
X1784002Y122106D01*
G01X1783999Y122008D02*
X1783997Y122034D01*
G01X1784002Y127106D02*
X1784006Y127205D01*
G01X1783997Y127034D02*
X1784002Y127106D01*
G01X1783999Y127008D02*
X1783997Y127034D01*
G01X1784002Y132106D02*
X1784006Y132205D01*
G01X1783997Y132034D02*
X1784002Y132106D01*
G01X1783999Y132008D02*
X1783997Y132034D01*
G01X1784002Y137106D02*
X1784006Y137205D01*
G01X1783997Y137034D02*
X1784002Y137106D01*
G01X1783999Y137008D02*
X1783997Y137034D01*
G01X1784002Y142106D02*
X1784006Y142205D01*
G01X1783997Y142034D02*
X1784002Y142106D01*
G01X1783999Y142008D02*
X1783997Y142034D01*
G01X1784002Y147106D02*
X1784006Y147205D01*
G01X1783997Y147034D02*
X1784002Y147106D01*
G01X1783999Y147008D02*
X1783997Y147034D01*
G01X1784002Y152106D02*
X1784006Y152205D01*
G01X1783997Y152034D02*
X1784002Y152106D01*
G01X1783999Y152008D02*
X1783997Y152034D01*
G01X1784002Y157106D02*
X1784006Y157205D01*
G01X1783997Y157034D02*
X1784002Y157106D01*
G01X1783999Y157008D02*
X1783997Y157034D01*
G01X1784002Y162106D02*
X1784006Y162205D01*
G01X1783997Y162034D02*
X1784002Y162106D01*
G01X1783999Y162008D02*
X1783997Y162034D01*
G01X1784002Y167106D02*
X1784006Y167205D01*
G01X1783997Y167034D02*
X1784002Y167106D01*
G01X1783999Y167008D02*
X1783997Y167034D01*
G01X1784002Y172106D02*
X1784006Y172205D01*
G01X1783997Y172034D02*
X1784002Y172106D01*
G01X1783999Y172008D02*
X1783997Y172034D01*
G01X1784002Y177106D02*
X1784006Y177205D01*
G01X1783997Y177034D02*
X1784002Y177106D01*
G01X1783999Y177008D02*
X1783997Y177034D01*
G01X1769626Y96411D02*
Y96404D01*
G01X1769625Y96416D02*
X1769626Y96411D01*
G01X1769625Y96406D02*
Y96416D01*
G01X1769666Y104043D02*
X1769665Y104055D01*
G01X1769663Y104030D02*
X1769666Y104043D01*
G01X1769663Y104016D02*
Y104030D01*
G01X1769666Y100893D02*
X1769665Y100906D01*
G01X1769663Y100880D02*
X1769666Y100893D01*
G01X1769663Y100866D02*
Y100880D01*
G01X1769666Y97743D02*
X1769665Y97756D01*
G01X1769663Y97730D02*
X1769666Y97743D01*
G01X1769663Y97717D02*
Y97730D01*
G01X1769666Y94594D02*
X1769665Y94606D01*
G01X1769663Y94581D02*
X1769666Y94594D01*
G01X1769663Y94567D02*
Y94581D01*
G01X1783052Y175628D02*
X1783053Y175630D01*
G01X1783051Y175622D02*
X1783052Y175628D01*
G01X1783051Y175614D02*
Y175622D01*
G01X1783052Y170628D02*
X1783053Y170630D01*
G01X1783051Y170622D02*
X1783052Y170628D01*
G01X1783051Y170614D02*
Y170622D01*
G01X1783052Y165628D02*
X1783053Y165630D01*
G01X1783051Y165622D02*
X1783052Y165628D01*
G01X1783051Y165614D02*
Y165622D01*
G01X1783052Y160628D02*
X1783053Y160630D01*
G01X1783051Y160622D02*
X1783052Y160628D01*
G01X1783051Y160614D02*
Y160622D01*
G01X1783052Y155628D02*
X1783053Y155630D01*
G01X1783051Y155622D02*
X1783052Y155628D01*
G01X1783051Y155614D02*
Y155622D01*
G01X1783052Y150628D02*
X1783053Y150630D01*
G01X1783051Y150622D02*
X1783052Y150628D01*
G01X1783051Y150614D02*
Y150622D01*
G01X1783052Y145628D02*
X1783053Y145630D01*
G01X1783051Y145622D02*
X1783052Y145628D01*
G01X1783051Y145614D02*
Y145622D01*
G01X1783052Y140628D02*
X1783053Y140630D01*
G01X1783051Y140622D02*
X1783052Y140628D01*
G01X1783051Y140614D02*
Y140622D01*
G01X1783052Y135628D02*
X1783053Y135630D01*
G01X1783051Y135622D02*
X1783052Y135628D01*
G01X1783051Y135614D02*
Y135622D01*
G01X1783052Y130628D02*
X1783053Y130630D01*
G01X1783051Y130622D02*
X1783052Y130628D01*
G01X1783051Y130614D02*
Y130622D01*
G01X1783052Y125628D02*
X1783053Y125630D01*
G01X1783051Y125622D02*
X1783052Y125628D01*
G01X1783051Y125614D02*
Y125622D01*
G01X1783052Y120628D02*
X1783053Y120630D01*
G01X1783051Y120622D02*
X1783052Y120628D01*
G01X1783051Y120614D02*
Y120622D01*
G01X1783052Y115628D02*
X1783053Y115630D01*
G01X1783051Y115622D02*
X1783052Y115628D01*
G01X1783051Y115614D02*
Y115622D01*
G01X1783052Y110628D02*
X1783053Y110630D01*
G01X1783051Y110622D02*
X1783052Y110628D01*
G01X1783051Y110614D02*
Y110622D01*
G01X1783052Y105628D02*
X1783053Y105630D01*
G01X1783051Y105622D02*
X1783052Y105628D01*
G01X1783051Y105614D02*
Y105622D01*
G01X1769626Y102711D02*
Y102703D01*
G01X1769625Y102715D02*
X1769626Y102711D01*
G01X1769625Y102707D02*
Y102715D01*
G01X1769663Y102506D02*
X1769662Y102519D01*
G01X1769666Y102493D02*
X1769663Y102506D01*
G01X1769665Y102480D02*
X1769666Y102493D01*
G01X1769663Y99356D02*
X1769662Y99370D01*
G01X1769666Y99343D02*
X1769663Y99356D01*
G01X1769665Y99331D02*
X1769666Y99343D01*
G01X1769663Y96206D02*
X1769662Y96220D01*
G01X1769666Y96194D02*
X1769663Y96206D01*
G01X1769665Y96181D02*
X1769666Y96194D01*
G01X1770573Y104030D02*
X1770574Y104016D01*
G01X1770570Y104043D02*
X1770573Y104030D01*
G01X1770571Y104055D02*
X1770570Y104043D01*
G01X1770573Y100880D02*
X1770574Y100866D01*
G01X1770570Y100893D02*
X1770573Y100880D01*
G01X1770571Y100906D02*
X1770570Y100893D01*
G01X1770573Y97730D02*
X1770574Y97717D01*
G01X1770570Y97743D02*
X1770573Y97730D01*
G01X1770571Y97756D02*
X1770570Y97743D01*
G01X1770573Y94581D02*
X1770574Y94567D01*
G01X1770570Y94594D02*
X1770573Y94581D01*
G01X1770571Y94606D02*
X1770570Y94594D01*
G01X1769626Y99561D02*
Y99554D01*
G01X1769625Y99565D02*
X1769626Y99561D01*
G01X1769624Y99558D02*
X1769625Y99565D01*
G01X1770570Y102493D02*
X1770571Y102480D01*
G01X1770573Y102506D02*
X1770570Y102493D01*
G01X1770574Y102519D02*
X1770573Y102506D01*
G01X1770570Y99343D02*
X1770571Y99331D01*
G01X1770573Y99356D02*
X1770570Y99343D01*
G01X1770574Y99370D02*
X1770573Y99356D01*
G01X1770570Y96194D02*
X1770571Y96181D01*
G01X1770573Y96206D02*
X1770570Y96194D01*
G01X1770574Y96220D02*
X1770573Y96206D01*
G01X1769639Y103850D02*
X1769663Y103858D01*
G01X1769628Y103835D02*
X1769639Y103850D01*
G01X1769626Y103828D02*
X1769628Y103835D01*
G01X1769639Y100700D02*
X1769663Y100709D01*
G01X1769628Y100685D02*
X1769639Y100700D01*
G01X1769626Y100679D02*
X1769628Y100685D01*
G01X1769639Y97550D02*
X1769663Y97559D01*
G01X1769628Y97536D02*
X1769639Y97550D01*
G01X1769626Y97529D02*
X1769628Y97536D01*
G01X1769639Y94401D02*
X1769663Y94409D01*
G01X1769628Y94386D02*
X1769639Y94401D01*
G01X1769626Y94380D02*
X1769628Y94386D01*
G01X1769627Y103839D02*
X1769626Y103832D01*
G01X1769628Y103845D02*
X1769627Y103839D01*
G01X1769631Y103851D02*
X1769628Y103845D01*
G01X1769635Y103856D02*
X1769631Y103851D01*
G01X1769640Y103861D02*
X1769635Y103856D01*
G01X1769645Y103864D02*
X1769640Y103861D01*
G01X1770581Y102679D02*
X1770569Y102677D01*
G01X1770592Y102684D02*
X1770581Y102679D01*
G01Y99530D02*
X1770569Y99528D01*
G01X1770592Y99534D02*
X1770581Y99530D01*
G01Y96380D02*
X1770569Y96378D01*
G01X1770592Y96385D02*
X1770581Y96380D01*
G01X1770610Y103825D02*
Y103832D01*
G01Y103820D02*
Y103825D01*
G01X1770609Y103819D02*
X1770610Y103820D01*
G01Y100676D02*
Y100683D01*
G01Y100671D02*
Y100676D01*
G01X1770609Y100669D02*
X1770610Y100671D01*
G01Y97526D02*
Y97533D01*
G01Y97521D02*
Y97526D01*
G01X1770609Y97520D02*
X1770610Y97521D01*
G01Y94376D02*
Y94383D01*
G01Y94372D02*
Y94376D01*
G01X1770609Y94370D02*
X1770610Y94372D01*
G01X1770571Y103863D02*
Y103869D01*
G01X1770570Y103859D02*
X1770571Y103863D01*
G01X1770569Y103858D02*
X1770570Y103859D01*
G01X1770571Y100714D02*
Y100720D01*
G01X1770570Y100710D02*
X1770571Y100714D01*
G01X1770569Y100709D02*
X1770570Y100710D01*
G01X1770571Y97564D02*
Y97570D01*
G01X1770570Y97560D02*
X1770571Y97564D01*
G01X1770569Y97559D02*
X1770570Y97560D01*
G01X1770571Y94415D02*
Y94420D01*
G01X1770570Y94411D02*
X1770571Y94415D01*
G01X1770569Y94409D02*
X1770570Y94411D01*
G01X1784036Y175622D02*
X1784035Y175613D01*
G01X1784037Y175628D02*
X1784036Y175622D01*
G01X1784038Y175630D02*
X1784037Y175628D01*
G01X1784036Y170622D02*
X1784035Y170613D01*
G01X1784037Y170628D02*
X1784036Y170622D01*
G01X1784038Y170630D02*
X1784037Y170628D01*
G01X1784036Y165622D02*
X1784035Y165613D01*
G01X1784037Y165628D02*
X1784036Y165622D01*
G01X1784038Y165630D02*
X1784037Y165628D01*
G01X1784036Y160622D02*
X1784035Y160613D01*
G01X1784037Y160628D02*
X1784036Y160622D01*
G01X1784038Y160630D02*
X1784037Y160628D01*
G01X1784036Y155622D02*
X1784035Y155613D01*
G01X1784037Y155628D02*
X1784036Y155622D01*
G01X1784038Y155630D02*
X1784037Y155628D01*
G01X1784036Y150622D02*
X1784035Y150613D01*
G01X1784037Y150628D02*
X1784036Y150622D01*
G01X1784038Y150630D02*
X1784037Y150628D01*
G01X1784036Y145622D02*
X1784035Y145613D01*
G01X1784037Y145628D02*
X1784036Y145622D01*
G01X1784038Y145630D02*
X1784037Y145628D01*
G01X1784036Y140622D02*
X1784035Y140613D01*
G01X1784037Y140628D02*
X1784036Y140622D01*
G01X1784038Y140630D02*
X1784037Y140628D01*
G01X1784036Y135622D02*
X1784035Y135613D01*
G01X1784037Y135628D02*
X1784036Y135622D01*
G01X1784038Y135630D02*
X1784037Y135628D01*
G01X1784036Y130622D02*
X1784035Y130613D01*
G01X1784037Y130628D02*
X1784036Y130622D01*
G01X1784038Y130630D02*
X1784037Y130628D01*
G01X1784036Y125622D02*
X1784035Y125613D01*
G01X1784037Y125628D02*
X1784036Y125622D01*
G01X1784038Y125630D02*
X1784037Y125628D01*
G01X1784036Y120622D02*
X1784035Y120613D01*
G01X1784037Y120628D02*
X1784036Y120622D01*
G01X1784038Y120630D02*
X1784037Y120628D01*
G01X1784036Y115622D02*
X1784035Y115613D01*
G01X1784037Y115628D02*
X1784036Y115622D01*
G01X1784038Y115630D02*
X1784037Y115628D01*
G01X1784036Y110622D02*
X1784035Y110613D01*
G01X1784037Y110628D02*
X1784036Y110622D01*
G01X1784038Y110630D02*
X1784037Y110628D01*
G01X1784036Y105622D02*
X1784035Y105613D01*
G01X1784037Y105628D02*
X1784036Y105622D01*
G01X1784038Y105630D02*
X1784037Y105628D01*
G01X1769626Y103825D02*
Y103832D01*
G01X1769625Y103820D02*
X1769626Y103825D01*
G01X1769624Y103819D02*
X1769625Y103820D01*
G01X1769626Y100675D02*
Y100683D01*
G01X1769625Y100671D02*
X1769626Y100675D01*
G01X1769624Y100669D02*
X1769625Y100671D01*
G01X1769626Y97526D02*
Y97533D01*
G01X1769625Y97521D02*
X1769626Y97526D01*
G01X1769624Y97520D02*
X1769625Y97521D01*
G01X1769626Y94376D02*
Y94383D01*
G01X1769625Y94372D02*
X1769626Y94376D01*
G01X1769624Y94370D02*
X1769625Y94372D01*
G01X1770608Y102691D02*
X1770610Y102703D01*
G01X1770601Y102679D02*
X1770608Y102691D01*
G01X1770591Y102671D02*
X1770601Y102679D01*
G01X1770608Y96391D02*
X1770610Y96404D01*
G01X1770601Y96380D02*
X1770608Y96391D01*
G01X1770591Y96372D02*
X1770601Y96380D01*
G01X1769665Y103863D02*
Y103869D01*
G01Y103859D02*
Y103863D01*
G01X1769663Y103858D02*
X1769665Y103859D01*
G01Y100713D02*
Y100720D01*
G01Y100710D02*
Y100713D01*
G01X1769663Y100709D02*
X1769665Y100710D01*
G01Y97564D02*
Y97570D01*
G01Y97560D02*
Y97564D01*
G01X1769663Y97559D02*
X1769665Y97560D01*
G01Y94414D02*
Y94420D01*
G01Y94411D02*
Y94414D01*
G01X1769663Y94409D02*
X1769665Y94411D01*
G01X1769627Y100689D02*
X1769626Y100683D01*
G01X1769628Y100695D02*
X1769627Y100689D01*
G01X1769631Y100701D02*
X1769628Y100695D01*
G01X1769635Y100706D02*
X1769631Y100701D01*
G01X1769640Y100711D02*
X1769635Y100706D01*
G01X1769645Y100715D02*
X1769640Y100711D01*
G01X1769627Y97539D02*
X1769626Y97533D01*
G01X1769628Y97546D02*
X1769627Y97539D01*
G01X1769631Y97552D02*
X1769628Y97546D01*
G01X1769635Y97557D02*
X1769631Y97552D01*
G01X1769640Y97561D02*
X1769635Y97557D01*
G01X1769645Y97565D02*
X1769640Y97561D01*
G01X1769627Y94390D02*
X1769626Y94383D01*
G01X1769628Y94396D02*
X1769627Y94390D01*
G01X1769631Y94402D02*
X1769628Y94396D01*
G01X1769635Y94407D02*
X1769631Y94402D01*
G01X1769640Y94412D02*
X1769635Y94407D01*
G01X1769645Y94415D02*
X1769640Y94412D01*
G01X1780433Y188130D02*
G03I-1890J0D01*
G01X1780906D02*
G03I-2363J0D01*
G01X1783465Y103681D02*
X1784646Y104862D01*
G01X1779528Y103681D02*
X1780709Y104862D01*
G01X1789370Y186161D02*
X1786024Y182815D01*
G01X1779528Y180138D02*
X1780709Y181319D01*
G01X1776059Y185059D02*
X1777362Y187028D01*
G01X1782035Y192950D02*
X1779724Y188720D01*
G01X1784035Y106982D02*
X1784036Y106991D01*
G01X1770610Y94372D02*
Y94383D01*
G01Y97522D02*
Y97533D01*
G01Y100671D02*
Y100683D01*
G01Y103821D02*
Y103832D01*
G01X1784035Y111982D02*
X1784036Y111991D01*
G01X1784035Y116982D02*
X1784036Y116991D01*
G01X1784035Y121982D02*
X1784036Y121991D01*
G01X1784035Y126982D02*
X1784036Y126991D01*
G01X1784035Y131982D02*
X1784036Y131991D01*
G01X1784035Y136982D02*
X1784036Y136991D01*
G01X1784035Y141982D02*
X1784036Y141991D01*
G01X1784035Y146982D02*
X1784036Y146991D01*
G01X1784035Y151982D02*
X1784036Y151991D01*
G01X1784035Y156982D02*
X1784036Y156991D01*
G01X1784035Y161982D02*
X1784036Y161991D01*
G01X1784035Y166982D02*
X1784036Y166991D01*
G01X1784035Y171982D02*
X1784036Y171991D01*
G01X1784035Y176982D02*
X1784036Y176991D01*
G01X1789370Y186161D02*
Y201909D01*
G01X1788386Y175630D02*
Y177008D01*
G01Y170630D02*
Y172008D01*
G01Y165630D02*
Y167008D01*
G01Y160630D02*
Y162008D01*
G01Y155630D02*
Y157008D01*
G01Y150630D02*
Y152008D01*
G01Y145630D02*
Y147008D01*
G01Y140630D02*
Y142008D01*
G01Y135630D02*
Y137008D01*
G01Y130630D02*
Y132008D01*
G01Y125630D02*
Y127008D01*
G01Y120630D02*
Y122008D01*
G01Y115630D02*
Y117008D01*
G01Y110630D02*
Y112008D01*
G01Y105630D02*
Y107008D01*
G01X1785217D02*
Y105630D01*
G01Y112008D02*
Y110630D01*
G01Y117008D02*
Y115630D01*
G01Y122008D02*
Y120630D01*
G01Y127008D02*
Y125630D01*
G01Y132008D02*
Y130630D01*
G01Y137008D02*
Y135630D01*
G01Y142008D02*
Y140630D01*
G01Y147008D02*
Y145630D01*
G01Y152008D02*
Y150630D01*
G01Y157008D02*
Y155630D01*
G01Y162008D02*
Y160630D01*
G01Y167008D02*
Y165630D01*
G01Y172008D02*
Y170630D01*
G01Y177008D02*
Y175630D01*
G01X1784035Y111982D02*
Y112125D01*
G01Y106982D02*
Y107125D01*
G01Y121982D02*
Y122125D01*
G01Y116982D02*
Y117125D01*
G01Y131982D02*
Y132125D01*
G01Y126982D02*
Y127125D01*
G01Y141982D02*
Y142125D01*
G01Y136982D02*
Y137125D01*
G01Y151982D02*
Y152125D01*
G01Y146982D02*
Y147125D01*
G01Y161982D02*
Y162125D01*
G01Y156982D02*
Y157125D01*
G01Y171982D02*
Y172125D01*
G01Y166982D02*
Y167125D01*
G01Y176982D02*
Y177125D01*
G01Y175138D02*
Y177500D01*
G01Y170138D02*
Y172500D01*
G01Y165138D02*
Y167500D01*
G01Y160138D02*
Y162500D01*
G01Y155138D02*
Y157500D01*
G01Y150138D02*
Y152500D01*
G01Y145138D02*
Y147500D01*
G01Y140138D02*
Y142500D01*
G01Y135138D02*
Y137500D01*
G01Y130138D02*
Y132500D01*
G01Y125138D02*
Y127500D01*
G01Y120138D02*
Y122500D01*
G01Y115138D02*
Y117500D01*
G01Y110138D02*
Y112500D01*
G01Y105138D02*
Y107500D01*
G01X1783051D02*
Y105138D01*
G01Y112500D02*
Y110138D01*
G01Y117500D02*
Y115138D01*
G01Y122500D02*
Y120138D01*
G01Y127500D02*
Y125138D01*
G01Y132500D02*
Y130138D01*
G01Y137500D02*
Y135138D01*
G01Y142500D02*
Y140138D01*
G01Y147500D02*
Y145138D01*
G01Y152500D02*
Y150138D01*
G01Y157500D02*
Y155138D01*
G01Y162500D02*
Y160138D01*
G01Y167500D02*
Y165138D01*
G01Y172500D02*
Y170138D01*
G01Y177500D02*
Y175138D01*
G01X1782283Y192224D02*
Y183681D01*
G01X1780709Y181319D02*
Y104862D01*
G01X1779724Y188720D02*
Y187028D01*
G01X1779528Y180138D02*
Y103681D01*
G01X1777362Y187028D02*
Y188720D01*
G01X1774803Y183681D02*
Y192224D01*
G01X1771063Y185059D02*
Y106024D01*
G01X1770610Y102519D02*
Y104016D01*
G01Y99370D02*
Y100866D01*
G01Y96220D02*
Y97717D01*
G01X1770571Y96367D02*
Y96220D01*
G01Y94567D02*
Y94420D01*
G01Y99516D02*
Y99369D01*
G01Y100867D02*
Y100720D01*
G01Y97717D02*
Y97570D01*
G01Y102666D02*
Y102519D01*
G01Y104016D02*
Y103869D01*
G01X1769665Y102519D02*
Y102666D01*
G01Y103869D02*
Y104016D01*
G01Y99369D02*
Y99516D01*
G01Y100720D02*
Y100867D01*
G01Y97570D02*
Y97717D01*
G01Y96220D02*
Y96367D01*
G01Y94420D02*
Y94567D01*
G01X1769626Y100866D02*
Y99370D01*
G01Y97717D02*
Y96220D01*
G01Y104016D02*
Y102520D01*
G01X1768445Y97559D02*
Y96378D01*
G01Y100709D02*
Y99528D01*
G01Y103858D02*
Y102677D01*
G01X1767717Y201909D02*
Y186161D01*
G01X1764685Y102677D02*
Y103858D01*
G01Y99528D02*
Y100709D01*
G01Y96378D02*
Y97559D01*
G01X1770610Y102703D02*
Y102714D01*
G01Y99554D02*
Y99564D01*
G01Y96404D02*
Y96415D01*
G01X1770569Y99528D02*
X1770573Y99516D01*
G01X1777362Y188720D02*
X1775052Y192950D01*
G01X1779724Y187028D02*
X1781028Y185059D01*
G01X1772835Y181319D02*
X1774016Y180138D01*
G01X1771063Y182815D02*
X1767717Y186161D01*
G01X1769513Y102717D02*
X1769624Y102708D01*
G01Y96414D02*
X1769513Y96417D01*
G01X1777362Y187028D02*
X1779724D01*
G01X1771063Y185059D02*
X1785433D01*
G01X1771063Y183681D02*
X1774803D01*
G01X1785433D02*
X1782283D01*
G01X1771063Y182815D02*
X1786024D01*
G01X1772835Y181319D02*
X1780709D01*
G01X1774016Y180138D02*
X1779528D01*
G01X1784035Y177500D02*
X1783051D01*
G01X1783053Y177008D02*
X1788386D01*
G01Y176969D02*
X1784038D01*
G01X1788386Y175630D02*
X1783053D01*
G01X1783051Y175138D02*
X1784035D01*
G01Y172500D02*
X1783051D01*
G01X1783053Y172008D02*
X1788386D01*
G01Y171969D02*
X1784038D01*
G01X1788386Y170630D02*
X1783053D01*
G01X1783051Y170138D02*
X1784035D01*
G01Y167500D02*
X1783051D01*
G01X1783053Y167008D02*
X1788386D01*
G01Y166969D02*
X1784038D01*
G01X1788386Y165630D02*
X1783053D01*
G01X1783051Y165138D02*
X1784035D01*
G01Y162500D02*
X1783051D01*
G01X1783053Y162008D02*
X1788386D01*
G01Y161969D02*
X1784038D01*
G01X1788386Y160630D02*
X1783053D01*
G01X1783051Y160138D02*
X1784035D01*
G01Y157500D02*
X1783051D01*
G01X1783053Y157008D02*
X1788386D01*
G01Y156969D02*
X1784038D01*
G01X1788386Y155630D02*
X1783053D01*
G01X1783051Y155138D02*
X1784035D01*
G01Y152500D02*
X1783051D01*
G01X1783053Y152008D02*
X1788386D01*
G01Y151969D02*
X1784038D01*
G01X1788386Y150630D02*
X1783053D01*
G01X1783051Y150138D02*
X1784035D01*
G01Y147500D02*
X1783051D01*
G01X1783053Y147008D02*
X1788386D01*
G01Y146969D02*
X1784038D01*
G01X1788386Y145630D02*
X1783053D01*
G01X1783051Y145138D02*
X1784035D01*
G01Y142500D02*
X1783051D01*
G01X1783053Y142008D02*
X1788386D01*
G01Y141969D02*
X1784038D01*
G01X1788386Y140630D02*
X1783053D01*
G01X1783051Y140138D02*
X1784035D01*
G01Y137500D02*
X1783051D01*
G01X1783053Y137008D02*
X1788386D01*
G01Y136969D02*
X1784038D01*
G01X1788386Y135630D02*
X1783053D01*
G01X1783051Y135138D02*
X1784035D01*
G01Y132500D02*
X1783051D01*
G01X1783053Y132008D02*
X1788386D01*
G01Y131969D02*
X1784038D01*
G01X1788386Y130630D02*
X1783053D01*
G01X1783051Y130138D02*
X1784035D01*
G01Y127500D02*
X1783051D01*
G01X1783053Y127008D02*
X1788386D01*
G01Y126969D02*
X1784038D01*
G01X1788386Y125630D02*
X1783053D01*
G01X1783051Y125138D02*
X1784035D01*
G01Y122500D02*
X1783051D01*
G01X1783053Y122008D02*
X1788386D01*
G01Y121969D02*
X1784038D01*
G01X1788386Y120630D02*
X1783053D01*
G01X1783051Y120138D02*
X1784035D01*
G01Y117500D02*
X1783051D01*
G01Y177204D02*
X1784006Y177205D01*
G01X1784035Y175434D02*
X1783051Y175433D01*
G01Y172204D02*
X1784006Y172205D01*
G01X1784035Y170434D02*
X1783051Y170433D01*
G01Y167204D02*
X1784006Y167205D01*
G01X1784035Y165434D02*
X1783051Y165433D01*
G01Y162204D02*
X1784006Y162205D01*
G01X1784035Y160434D02*
X1783051Y160433D01*
G01Y157204D02*
X1784006Y157205D01*
G01X1784035Y155434D02*
X1783051Y155433D01*
G01Y152204D02*
X1784006Y152205D01*
G01X1784035Y150434D02*
X1783051Y150433D01*
G01Y147204D02*
X1784006Y147205D01*
G01X1784035Y145434D02*
X1783051Y145433D01*
G01Y142204D02*
X1784006Y142205D01*
G01X1784035Y140434D02*
X1783051Y140433D01*
G01Y137204D02*
X1784006Y137205D01*
G01X1784035Y135434D02*
X1783051Y135433D01*
G01Y132204D02*
X1784006Y132205D01*
G01X1784035Y130434D02*
X1783051Y130433D01*
G01Y127204D02*
X1784006Y127205D01*
G01X1784035Y125434D02*
X1783051Y125433D01*
G01Y122204D02*
X1784006Y122205D01*
G01X1784035Y120434D02*
X1783051Y120433D01*
G01X1783053Y117008D02*
X1788386D01*
G01Y116969D02*
X1784038D01*
G01X1788386Y115630D02*
X1783053D01*
G01X1783051Y115138D02*
X1784035D01*
G01Y112500D02*
X1783051D01*
G01X1783053Y112008D02*
X1788386D01*
G01Y111969D02*
X1784038D01*
G01X1788386Y110630D02*
X1783053D01*
G01X1783051Y110138D02*
X1784035D01*
G01Y107500D02*
X1783051D01*
G01X1783053Y107008D02*
X1788386D01*
G01Y106969D02*
X1784038D01*
G01X1771063Y106024D02*
X1767717D01*
G01X1788386Y105630D02*
X1783053D01*
G01X1783051Y105138D02*
X1784035D01*
G01X1780709Y104862D02*
X1784646D01*
G01X1770571Y104055D02*
X1769665D01*
G01X1770610Y104016D02*
X1769626D01*
G01X1770569Y103858D02*
X1764685D01*
G01Y103819D02*
X1770609D01*
G01X1779528Y103681D02*
X1783465D01*
G01X1770609Y102717D02*
X1764685D01*
G01X1770569Y102677D02*
X1764685D01*
G01X1769626Y102520D02*
X1770610D01*
G01X1769665Y102480D02*
X1770571D01*
G01Y100906D02*
X1769665D01*
G01X1770610Y100866D02*
X1769626D01*
G01X1770569Y100709D02*
X1764685D01*
G01Y100669D02*
X1770609D01*
G01Y99567D02*
X1764685D01*
G01X1770569Y99528D02*
X1764685D01*
G01X1769626Y99370D02*
X1770610D01*
G01X1769665Y99331D02*
X1770571D01*
G01Y97756D02*
X1769665D01*
G01X1770610Y97717D02*
X1769626D01*
G01X1770569Y97559D02*
X1764685D01*
G01Y97520D02*
X1770609D01*
G01X1768879Y96417D02*
X1768445D01*
G01X1770609D02*
X1764685D01*
G01X1770569Y96378D02*
X1764685D01*
G01X1769626Y96220D02*
X1770610D01*
G01X1769665Y96181D02*
X1770571D01*
G01Y94606D02*
X1769665D01*
G01X1770610Y94567D02*
X1769626D01*
G01X1770569Y94409D02*
X1764685D01*
G01Y94370D02*
X1770609D01*
G01X1783051Y117204D02*
X1784006Y117205D01*
G01X1784035Y115434D02*
X1783051Y115433D01*
G01Y112204D02*
X1784006Y112205D01*
G01X1784035Y110434D02*
X1783051Y110433D01*
G01Y107204D02*
X1784006Y107205D01*
G01X1784035Y105434D02*
X1783051Y105433D01*
G01X1781028Y264712D02*
G03X1814839I16906J-13531D01*
G01X1807914Y277843D02*
G03X1814838Y264712I37663J11469D01*
G01X1807914Y277843D02*
G03X1787953I-9980J-3040D01*
G01X1781028Y264712D02*
G03X1787953Y277843I-30737J24602D01*
G01X1807913D02*
G03X1814839Y264712I37661J11473D01*
G01X1738583Y260630D02*
G03X1739764I590J0D01*
G01Y254331D02*
G03X1738583I-590J0D01*
G01X1736614D02*
G03X1735433I-591J0D01*
G01Y260630D02*
G03X1736614I590J0D01*
G01X1738583D02*
G03X1739764I590J0D01*
G01Y254331D02*
G03X1738583I-590J0D01*
G01X1736614D02*
G03X1735433I-591J0D01*
G01Y260630D02*
G03X1736614I590J0D01*
G01X1807913Y277843D02*
G03X1787953I-9980J-3040D01*
G01X1781028Y264712D02*
G03X1814839I16906J-13531D01*
G01X1781028D02*
G03X1787953Y277843I-30737J24602D01*
G01X1782480Y202500D02*
G03X1781890Y203091I-591J0D01*
G01X1775197D02*
G03X1774606Y202500I0J-591D01*
G01X1777362Y201319D02*
G03Y199350I0J-985D01*
G01X1779724D02*
G03Y201319I0J984D01*
G01X1775984Y193406D02*
G03X1774803Y192224I0J-1181D01*
G01X1782283D02*
G03X1781102Y193406I-1181J1D01*
G01X1789370Y201909D02*
G03X1787402Y203878I-1969J0D01*
G01X1769685D02*
G03X1767717Y201909I0J-1968D01*
G01X1782480Y196398D02*
Y202500D01*
G01X1774606Y196398D02*
Y202500D01*
G01X1740551Y254331D02*
Y260630D01*
G01Y254331D02*
Y260630D01*
G01X1734646Y254331D02*
Y260630D01*
G01D02*
Y254331D01*
G01X1738583Y260630D02*
X1736614D01*
G01X1735433D02*
X1734646D01*
G01X1738583D02*
X1736614D01*
G01X1735433D02*
X1734646D01*
G01X1740551D02*
X1739764D01*
G01X1740551D02*
X1739764D01*
G01X1740551Y259646D02*
X1734646D01*
G01Y259449D02*
X1740551D01*
G01X1734646Y255512D02*
X1740551D01*
G01Y255315D02*
X1734646D01*
G01X1739764Y254331D02*
X1740551D01*
G01X1739764D02*
X1740551D01*
G01X1736614D02*
X1738583D01*
G01X1734646D02*
X1735433D01*
G01X1736614D02*
X1738583D01*
G01X1734646D02*
X1735433D01*
G01X1787402Y203878D02*
X1769685D01*
G01X1781890Y203091D02*
X1775197D01*
G01X1779724Y201319D02*
X1777362D01*
G01Y199350D02*
X1779724D01*
G01X1782480Y197972D02*
X1774606D01*
G01Y196398D02*
X1782480D01*
G01X1789370Y193445D02*
X1767717D01*
G01X1775984Y193406D02*
X1781102D01*
G01X1777362Y188720D02*
X1779724D01*
G01X1769629Y537697D02*
X1769624Y537677D01*
G01X1769643Y537711D02*
X1769629Y537697D01*
G01X1769663Y537717D02*
X1769643Y537711D01*
G01X1769629Y540846D02*
X1769624Y540827D01*
G01X1769643Y540861D02*
X1769629Y540846D01*
G01X1769663Y540866D02*
X1769643Y540861D01*
G01X1769629Y543996D02*
X1769624Y543976D01*
G01X1769643Y544010D02*
X1769629Y543996D01*
G01X1769663Y544016D02*
X1769643Y544010D01*
G01X1769629Y547146D02*
X1769624Y547126D01*
G01X1769643Y547160D02*
X1769629Y547146D01*
G01X1769663Y547165D02*
X1769643Y547160D01*
G01X1769629Y550295D02*
X1769624Y550276D01*
G01X1769643Y550309D02*
X1769629Y550295D01*
G01X1769663Y550315D02*
X1769643Y550309D01*
G01X1769629Y553445D02*
X1769624Y553425D01*
G01X1769643Y553459D02*
X1769629Y553445D01*
G01X1769663Y553465D02*
X1769643Y553459D01*
G01X1769629Y556594D02*
X1769624Y556575D01*
G01X1769643Y556609D02*
X1769629Y556594D01*
G01X1769663Y556614D02*
X1769643Y556609D01*
G01X1770604Y536555D02*
X1770609Y536575D01*
G01X1770589Y536541D02*
X1770604Y536555D01*
G01X1770569Y536535D02*
X1770589Y536541D01*
G01X1770604Y539705D02*
X1770609Y539724D01*
G01X1770589Y539690D02*
X1770604Y539705D01*
G01X1770569Y539685D02*
X1770589Y539690D01*
G01X1770604Y542854D02*
X1770609Y542874D01*
G01X1770589Y542840D02*
X1770604Y542854D01*
G01X1770569Y542835D02*
X1770589Y542840D01*
G01X1770604Y546004D02*
X1770609Y546024D01*
G01X1770589Y545989D02*
X1770604Y546004D01*
G01X1770569Y545984D02*
X1770589Y545989D01*
G01X1770604Y549154D02*
X1770609Y549173D01*
G01X1770589Y549139D02*
X1770604Y549154D01*
G01X1770569Y549134D02*
X1770589Y549139D01*
G01X1770604Y552303D02*
X1770609Y552323D01*
G01X1770589Y552289D02*
X1770604Y552303D01*
G01X1770569Y552283D02*
X1770589Y552289D01*
G01X1770604Y555453D02*
X1770609Y555472D01*
G01X1770589Y555438D02*
X1770604Y555453D01*
G01X1770569Y555433D02*
X1770589Y555438D01*
G01X1770609Y552302D02*
X1770610Y552309D01*
G01X1770607Y552295D02*
X1770609Y552302D01*
G01X1770604Y552289D02*
X1770607Y552295D01*
G01X1770599Y552283D02*
X1770604Y552289D01*
G01X1770593Y552278D02*
X1770599Y552283D01*
G01X1770586Y552275D02*
X1770593Y552278D01*
G01X1770579Y552273D02*
X1770586Y552275D01*
G01X1770571Y552272D02*
X1770579Y552273D01*
G01X1770588Y536528D02*
X1770591Y536530D01*
G01X1770585Y536526D02*
X1770588Y536528D01*
G01X1770581Y536526D02*
X1770585D01*
G01X1770578Y536525D02*
X1770581Y536526D01*
G01X1770574Y536524D02*
X1770578Y536525D01*
G01X1770571Y536524D02*
X1770574D01*
G01X1769648Y537724D02*
X1769645Y537722D01*
G01X1769652Y537725D02*
X1769648Y537724D01*
G01X1769655Y537726D02*
X1769652Y537725D01*
G01X1769658Y537727D02*
X1769655Y537726D01*
G01X1769662Y537728D02*
X1769658Y537727D01*
G01X1769665Y537728D02*
X1769662D01*
G01X1770588Y539677D02*
X1770591Y539679D01*
G01X1770585Y539676D02*
X1770588Y539677D01*
G01X1770581Y539675D02*
X1770585Y539676D01*
G01X1770578Y539674D02*
X1770581Y539675D01*
G01X1770574Y539674D02*
X1770578D01*
G01X1770571D02*
X1770574D01*
G01X1769648Y540874D02*
X1769645Y540872D01*
G01X1769652Y540875D02*
X1769648Y540874D01*
G01X1769655Y540876D02*
X1769652Y540875D01*
G01X1769658Y540877D02*
X1769655Y540876D01*
G01X1769662Y540877D02*
X1769658D01*
G01X1769665D02*
X1769662D01*
G01X1770588Y542827D02*
X1770591Y542829D01*
G01X1770585Y542826D02*
X1770588Y542827D01*
G01X1770581Y542825D02*
X1770585Y542826D01*
G01X1770578Y542824D02*
X1770581Y542825D01*
G01X1770574Y542824D02*
X1770578D01*
G01X1770571Y542823D02*
X1770574Y542824D01*
G01X1769648Y544023D02*
X1769645Y544022D01*
G01X1769652Y544024D02*
X1769648Y544023D01*
G01X1769655Y544026D02*
X1769652Y544024D01*
G01X1769658Y544026D02*
X1769655D01*
G01X1769662Y544027D02*
X1769658Y544026D01*
G01X1769665Y544027D02*
X1769662D01*
G01X1770588Y545976D02*
X1770591Y545978D01*
G01X1770585Y545975D02*
X1770588Y545976D01*
G01X1770581Y545974D02*
X1770585Y545975D01*
G01X1770578Y545974D02*
X1770581D01*
G01X1770574Y545973D02*
X1770578Y545974D01*
G01X1770571Y545973D02*
X1770574D01*
G01X1769648Y547173D02*
X1769645Y547171D01*
G01X1769652Y547174D02*
X1769648Y547173D01*
G01X1769655Y547175D02*
X1769652Y547174D01*
G01X1769658Y547176D02*
X1769655Y547175D01*
G01X1769662Y547176D02*
X1769658D01*
G01X1769665D02*
X1769662D01*
G01X1770588Y549126D02*
X1770591Y549128D01*
G01X1770585Y549125D02*
X1770588Y549126D01*
G01X1770581Y549124D02*
X1770585Y549125D01*
G01X1770578Y549123D02*
X1770581Y549124D01*
G01X1770574Y549123D02*
X1770578D01*
G01X1770571Y549122D02*
X1770574Y549123D01*
G01X1769648Y550322D02*
X1769645Y550321D01*
G01X1769652Y550324D02*
X1769648Y550322D01*
G01X1769655Y550325D02*
X1769652Y550324D01*
G01X1769658Y550326D02*
X1769655Y550325D01*
G01X1769662Y550326D02*
X1769658D01*
G01X1769665D02*
X1769662D01*
G01X1769648Y553472D02*
X1769645Y553470D01*
G01X1769652Y553473D02*
X1769648Y553472D01*
G01X1769655Y553474D02*
X1769652Y553473D01*
G01X1769658Y553475D02*
X1769655Y553474D01*
G01X1769662Y553476D02*
X1769658Y553475D01*
G01X1769665Y553476D02*
X1769662D01*
G01X1770588Y555425D02*
X1770591Y555427D01*
G01X1770585Y555424D02*
X1770588Y555425D01*
G01X1770581Y555423D02*
X1770585Y555424D01*
G01X1770578Y555422D02*
X1770581Y555423D01*
G01X1770574Y555422D02*
X1770578D01*
G01X1770571D02*
X1770574D01*
G01X1769648Y556622D02*
X1769645Y556620D01*
G01X1769652Y556623D02*
X1769648Y556622D01*
G01X1769655Y556624D02*
X1769652Y556623D01*
G01X1769658Y556625D02*
X1769655Y556624D01*
G01X1769662Y556625D02*
X1769658D01*
G01X1769665D02*
X1769662D01*
G01X1770601Y537715D02*
X1770605Y537709D01*
G01X1770596Y537719D02*
X1770601Y537715D01*
G01X1770590Y537723D02*
X1770596Y537719D01*
G01X1770584Y537726D02*
X1770590Y537723D01*
G01X1770578Y537727D02*
X1770584Y537726D01*
G01X1770571Y537728D02*
X1770578Y537727D01*
G01X1770601Y540865D02*
X1770605Y540859D01*
G01X1770596Y540869D02*
X1770601Y540865D01*
G01X1770590Y540872D02*
X1770596Y540869D01*
G01X1770584Y540875D02*
X1770590Y540872D01*
G01X1770578Y540877D02*
X1770584Y540875D01*
G01X1770571Y540877D02*
X1770578D01*
G01X1770601Y544014D02*
X1770605Y544009D01*
G01X1770596Y544019D02*
X1770601Y544014D01*
G01X1770590Y544022D02*
X1770596Y544019D01*
G01X1770584Y544025D02*
X1770590Y544022D01*
G01X1770578Y544026D02*
X1770584Y544025D01*
G01X1770571Y544027D02*
X1770578Y544026D01*
G01X1770601Y547164D02*
X1770605Y547158D01*
G01X1770596Y547168D02*
X1770601Y547164D01*
G01X1770590Y547172D02*
X1770596Y547168D01*
G01X1770584Y547174D02*
X1770590Y547172D01*
G01X1770578Y547176D02*
X1770584Y547174D01*
G01X1770571Y547176D02*
X1770578D01*
G01X1770601Y550313D02*
X1770605Y550308D01*
G01X1770596Y550318D02*
X1770601Y550313D01*
G01X1770590Y550321D02*
X1770596Y550318D01*
G01X1770584Y550324D02*
X1770590Y550321D01*
G01X1770578Y550326D02*
X1770584Y550324D01*
G01X1770571Y550326D02*
X1770578D01*
G01X1770601Y553463D02*
X1770605Y553457D01*
G01X1770596Y553467D02*
X1770601Y553463D01*
G01X1770590Y553471D02*
X1770596Y553467D01*
G01X1770584Y553474D02*
X1770590Y553471D01*
G01X1770578Y553475D02*
X1770584Y553474D01*
G01X1770571Y553476D02*
X1770578Y553475D01*
G01X1770601Y556613D02*
X1770605Y556607D01*
G01X1770596Y556617D02*
X1770601Y556613D01*
G01X1770590Y556620D02*
X1770596Y556617D01*
G01X1770584Y556623D02*
X1770590Y556620D01*
G01X1770578Y556625D02*
X1770584Y556623D01*
G01X1770571Y556625D02*
X1770578D01*
G01X1769627Y536554D02*
X1769626Y536561D01*
G01X1769629Y536547D02*
X1769627Y536554D01*
G01X1769633Y536541D02*
X1769629Y536547D01*
G01X1769637Y536535D02*
X1769633Y536541D01*
G01X1769644Y536530D02*
X1769637Y536535D01*
G01X1769650Y536527D02*
X1769644Y536530D01*
G01X1769658Y536525D02*
X1769650Y536527D01*
G01X1769665Y536524D02*
X1769658Y536525D01*
G01X1769627Y539704D02*
X1769626Y539711D01*
G01X1769629Y539696D02*
X1769627Y539704D01*
G01X1769633Y539690D02*
X1769629Y539696D01*
G01X1769637Y539685D02*
X1769633Y539690D01*
G01X1769644Y539680D02*
X1769637Y539685D01*
G01X1769650Y539676D02*
X1769644Y539680D01*
G01X1769658Y539674D02*
X1769650Y539676D01*
G01X1769665Y539674D02*
X1769658D01*
G01X1769627Y542853D02*
X1769626Y542860D01*
G01X1769629Y542846D02*
X1769627Y542853D01*
G01X1769633Y542840D02*
X1769629Y542846D01*
G01X1769637Y542834D02*
X1769633Y542840D01*
G01X1769644Y542830D02*
X1769637Y542834D01*
G01X1769650Y542826D02*
X1769644Y542830D01*
G01X1769658Y542824D02*
X1769650Y542826D01*
G01X1769665Y542823D02*
X1769658Y542824D01*
G01X1769627Y546003D02*
X1769626Y546010D01*
G01X1769629Y545996D02*
X1769627Y546003D01*
G01X1769633Y545989D02*
X1769629Y545996D01*
G01X1769637Y545984D02*
X1769633Y545989D01*
G01X1769644Y545979D02*
X1769637Y545984D01*
G01X1769650Y545976D02*
X1769644Y545979D01*
G01X1769658Y545974D02*
X1769650Y545976D01*
G01X1769665Y545973D02*
X1769658Y545974D01*
G01X1769627Y549152D02*
X1769626Y549159D01*
G01X1769629Y549145D02*
X1769627Y549152D01*
G01X1769633Y549139D02*
X1769629Y549145D01*
G01X1769637Y549133D02*
X1769633Y549139D01*
G01X1769644Y549129D02*
X1769637Y549133D01*
G01X1769650Y549125D02*
X1769644Y549129D01*
G01X1769658Y549123D02*
X1769650Y549125D01*
G01X1769665Y549122D02*
X1769658Y549123D01*
G01X1769627Y552302D02*
X1769626Y552309D01*
G01X1769629Y552295D02*
X1769627Y552302D01*
G01X1769633Y552289D02*
X1769629Y552295D01*
G01X1769637Y552283D02*
X1769633Y552289D01*
G01X1769644Y552278D02*
X1769637Y552283D01*
G01X1769650Y552275D02*
X1769644Y552278D01*
G01X1769658Y552273D02*
X1769650Y552275D01*
G01X1769665Y552272D02*
X1769658Y552273D01*
G01X1769627Y555452D02*
X1769626Y555459D01*
G01X1769629Y555444D02*
X1769627Y555452D01*
G01X1769633Y555438D02*
X1769629Y555444D01*
G01X1769637Y555433D02*
X1769633Y555438D01*
G01X1769644Y555428D02*
X1769637Y555433D01*
G01X1769650Y555424D02*
X1769644Y555428D01*
G01X1769658Y555422D02*
X1769650Y555424D01*
G01X1769665Y555422D02*
X1769658D01*
G01X1770580Y537715D02*
X1770589Y537711D01*
G01X1770569Y537717D02*
X1770580Y537715D01*
G01Y540865D02*
X1770589Y540861D01*
G01X1770569Y540866D02*
X1770580Y540865D01*
G01Y544014D02*
X1770589Y544010D01*
G01X1770569Y544016D02*
X1770580Y544014D01*
G01Y547164D02*
X1770589Y547160D01*
G01X1770569Y547165D02*
X1770580Y547164D01*
G01Y550313D02*
X1770589Y550309D01*
G01X1770569Y550315D02*
X1770580Y550313D01*
G01Y553463D02*
X1770589Y553459D01*
G01X1770569Y553465D02*
X1770580Y553463D01*
G01Y556613D02*
X1770589Y556609D01*
G01X1770569Y556614D02*
X1770580Y556613D01*
G01X1769626Y539715D02*
Y539711D01*
G01X1769628Y539708D02*
X1769626Y539715D01*
G01X1769639Y539693D02*
X1769628Y539708D01*
G01X1769664Y539685D02*
X1769639Y539693D01*
G01X1769626Y542864D02*
Y542860D01*
G01X1769628Y542858D02*
X1769626Y542864D01*
G01X1769639Y542843D02*
X1769628Y542858D01*
G01X1769663Y542835D02*
X1769639Y542843D01*
G01X1769626Y549163D02*
Y549159D01*
G01X1769628Y549157D02*
X1769626Y549163D01*
G01X1769639Y549142D02*
X1769628Y549157D01*
G01X1769663Y549134D02*
X1769639Y549142D01*
G01X1769626Y552313D02*
Y552309D01*
G01X1769628Y552307D02*
X1769626Y552313D01*
G01X1769639Y552292D02*
X1769628Y552307D01*
G01X1769663Y552283D02*
X1769639Y552292D01*
G01X1769626Y536565D02*
Y536561D01*
G01X1769628Y536559D02*
X1769626Y536565D01*
G01X1769639Y536544D02*
X1769628Y536559D01*
G01X1769663Y536535D02*
X1769639Y536544D01*
G01X1769626Y555463D02*
Y555459D01*
G01X1769628Y555457D02*
X1769626Y555463D01*
G01X1769639Y555441D02*
X1769628Y555457D01*
G01X1769663Y555433D02*
X1769639Y555441D01*
G01X1784023Y504755D02*
X1784034Y504740D01*
G01X1783998Y504764D02*
X1784023Y504755D01*
G01Y509755D02*
X1784034Y509740D01*
G01X1783998Y509764D02*
X1784023Y509755D01*
G01Y514755D02*
X1784034Y514740D01*
G01X1783998Y514764D02*
X1784023Y514755D01*
G01Y519755D02*
X1784034Y519740D01*
G01X1783998Y519764D02*
X1784023Y519755D01*
G01Y524755D02*
X1784034Y524740D01*
G01X1783998Y524764D02*
X1784023Y524755D01*
G01Y529755D02*
X1784034Y529740D01*
G01X1783998Y529764D02*
X1784023Y529755D01*
G01Y534755D02*
X1784034Y534740D01*
G01X1783998Y534764D02*
X1784023Y534755D01*
G01Y559755D02*
X1784034Y559740D01*
G01X1783998Y559764D02*
X1784023Y559755D01*
G01Y564755D02*
X1784034Y564740D01*
G01X1783998Y564764D02*
X1784023Y564755D01*
G01Y569755D02*
X1784034Y569740D01*
G01X1783998Y569764D02*
X1784023Y569755D01*
G01X1769626Y546014D02*
Y546010D01*
G01X1769628Y546008D02*
X1769626Y546014D01*
G01X1769638Y545994D02*
X1769628Y546008D01*
G01X1769661Y545984D02*
X1769638Y545994D01*
G01X1770579Y544015D02*
X1770569Y544016D01*
G01X1770587Y544011D02*
X1770579Y544015D01*
G01X1770595Y544006D02*
X1770587Y544011D01*
G01X1770579Y537715D02*
X1770569Y537717D01*
G01X1770588Y537712D02*
X1770579Y537715D01*
G01X1770595Y537707D02*
X1770588Y537712D01*
G01X1770579Y540865D02*
X1770569Y540866D01*
G01X1770588Y540862D02*
X1770579Y540865D01*
G01X1770595Y540856D02*
X1770588Y540862D01*
G01X1770579Y547164D02*
X1770569Y547165D01*
G01X1770588Y547161D02*
X1770579Y547164D01*
G01X1770595Y547156D02*
X1770588Y547161D01*
G01X1770579Y550314D02*
X1770569Y550315D01*
G01X1770588Y550311D02*
X1770579Y550314D01*
G01X1770595Y550305D02*
X1770588Y550311D01*
G01X1770579Y553463D02*
X1770569Y553465D01*
G01X1770588Y553460D02*
X1770579Y553463D01*
G01X1770595Y553455D02*
X1770588Y553460D01*
G01X1770579Y556613D02*
X1770569Y556614D01*
G01X1770588Y556610D02*
X1770579Y556613D01*
G01X1770595Y556604D02*
X1770588Y556610D01*
G01X1769665Y536530D02*
Y536524D01*
G01X1769664Y536534D02*
X1769665Y536530D01*
G01X1769663Y536535D02*
X1769664Y536534D01*
G01X1769665Y539680D02*
Y539674D01*
G01X1769664Y539684D02*
X1769665Y539680D01*
G01X1769663Y539685D02*
X1769664Y539684D01*
G01X1769665Y542830D02*
Y542823D01*
G01X1769664Y542833D02*
X1769665Y542830D01*
G01X1769663Y542835D02*
X1769664Y542833D01*
G01X1769665Y545979D02*
Y545973D01*
G01X1769664Y545983D02*
X1769665Y545979D01*
G01X1769663Y545984D02*
X1769664Y545983D01*
G01X1769665Y549129D02*
Y549122D01*
G01X1769664Y549133D02*
X1769665Y549129D01*
G01X1769663Y549134D02*
X1769664Y549133D01*
G01X1769665Y552278D02*
Y552272D01*
G01X1769664Y552282D02*
X1769665Y552278D01*
G01X1769663Y552283D02*
X1769664Y552282D01*
G01X1769665Y555428D02*
Y555422D01*
G01X1769664Y555432D02*
X1769665Y555428D01*
G01X1769663Y555433D02*
X1769664Y555432D01*
G01X1784036Y504731D02*
X1784035Y504738D01*
G01X1784037Y504726D02*
X1784036Y504731D01*
G01X1784038Y504724D02*
X1784037Y504726D01*
G01X1784036Y509731D02*
X1784035Y509738D01*
G01X1784037Y509726D02*
X1784036Y509731D01*
G01X1784038Y509724D02*
X1784037Y509726D01*
G01X1784036Y514731D02*
X1784035Y514738D01*
G01X1784037Y514726D02*
X1784036Y514731D01*
G01X1784038Y514724D02*
X1784037Y514726D01*
G01X1784036Y519731D02*
X1784035Y519738D01*
G01X1784037Y519726D02*
X1784036Y519731D01*
G01X1784038Y519724D02*
X1784037Y519726D01*
G01X1784036Y524731D02*
X1784035Y524738D01*
G01X1784037Y524726D02*
X1784036Y524731D01*
G01X1784038Y524724D02*
X1784037Y524726D01*
G01X1770581Y555435D02*
X1770569Y555433D01*
G01X1770592Y555440D02*
X1770581Y555435D01*
G01Y552285D02*
X1770569Y552283D01*
G01X1770592Y552290D02*
X1770581Y552285D01*
G01Y549136D02*
X1770569Y549134D01*
G01X1770592Y549141D02*
X1770581Y549136D01*
G01Y545986D02*
X1770569Y545984D01*
G01X1770592Y545991D02*
X1770581Y545986D01*
G01Y542837D02*
X1770569Y542835D01*
G01X1770592Y542841D02*
X1770581Y542837D01*
G01Y539687D02*
X1770569Y539685D01*
G01X1770592Y539692D02*
X1770581Y539687D01*
G01Y536537D02*
X1770569Y536535D01*
G01X1770592Y536542D02*
X1770581Y536537D01*
G01X1784036Y529731D02*
X1784035Y529738D01*
G01X1784037Y529726D02*
X1784036Y529731D01*
G01X1784038Y529724D02*
X1784037Y529726D01*
G01X1784036Y534731D02*
X1784035Y534738D01*
G01X1784037Y534726D02*
X1784036Y534731D01*
G01X1784038Y534724D02*
X1784037Y534726D01*
G01X1784036Y559731D02*
X1784035Y559738D01*
G01X1784037Y559726D02*
X1784036Y559731D01*
G01X1784038Y559724D02*
X1784037Y559726D01*
G01X1784036Y564731D02*
X1784035Y564738D01*
G01X1784037Y564726D02*
X1784036Y564731D01*
G01X1784038Y564724D02*
X1784037Y564726D01*
G01X1784036Y569731D02*
X1784035Y569738D01*
G01X1784037Y569726D02*
X1784036Y569731D01*
G01X1784038Y569724D02*
X1784037Y569726D01*
G01X1769649Y539687D02*
X1769663Y539685D01*
G01X1769637Y539694D02*
X1769649Y539687D01*
G01X1769625Y539713D02*
X1769637Y539694D01*
G01X1769649Y549136D02*
X1769663Y549134D01*
G01X1769637Y549144D02*
X1769649Y549136D01*
G01X1769625Y549162D02*
X1769637Y549144D01*
G01X1769648Y542837D02*
X1769663Y542835D01*
G01X1769636Y542845D02*
X1769648Y542837D01*
G01X1769624Y542865D02*
X1769636Y542845D01*
G01X1770610Y536569D02*
Y536561D01*
G01X1770609Y536573D02*
X1770610Y536569D01*
G01X1770609Y536575D02*
Y536573D01*
G01X1770610Y539719D02*
Y539711D01*
G01X1770609Y539723D02*
X1770610Y539719D01*
G01X1770609Y539724D02*
Y539723D01*
G01X1770608Y555446D02*
X1770610Y555459D01*
G01X1770601Y555435D02*
X1770608Y555446D01*
G01X1770591Y555427D02*
X1770601Y555435D01*
G01X1769665Y556619D02*
Y556625D01*
G01Y556615D02*
Y556619D01*
G01X1769663Y556614D02*
X1769665Y556615D01*
G01Y553469D02*
Y553476D01*
G01Y553466D02*
Y553469D01*
G01X1769663Y553465D02*
X1769665Y553466D01*
G01Y550320D02*
Y550326D01*
G01Y550316D02*
Y550320D01*
G01X1769663Y550315D02*
X1769665Y550316D01*
G01Y547170D02*
Y547176D01*
G01Y547167D02*
Y547170D01*
G01X1769663Y547165D02*
X1769665Y547167D01*
G01Y544020D02*
Y544027D01*
G01Y544017D02*
Y544020D01*
G01X1769663Y544016D02*
X1769665Y544017D01*
G01Y540871D02*
Y540877D01*
G01Y540867D02*
Y540871D01*
G01X1769663Y540866D02*
X1769665Y540867D01*
G01Y537721D02*
Y537728D01*
G01Y537718D02*
Y537721D01*
G01X1769663Y537717D02*
X1769665Y537718D01*
G01X1769627Y556594D02*
X1769626Y556588D01*
G01X1769628Y556601D02*
X1769627Y556594D01*
G01X1769631Y556607D02*
X1769628Y556601D01*
G01X1769635Y556612D02*
X1769631Y556607D01*
G01X1769640Y556617D02*
X1769635Y556612D01*
G01X1769645Y556620D02*
X1769640Y556617D01*
G01X1769627Y553445D02*
X1769626Y553439D01*
G01X1769628Y553451D02*
X1769627Y553445D01*
G01X1769631Y553457D02*
X1769628Y553451D01*
G01X1769635Y553462D02*
X1769631Y553457D01*
G01X1769640Y553467D02*
X1769635Y553462D01*
G01X1769645Y553470D02*
X1769640Y553467D01*
G01X1769627Y550295D02*
X1769626Y550289D01*
G01X1769628Y550302D02*
X1769627Y550295D01*
G01X1769631Y550307D02*
X1769628Y550302D01*
G01X1769635Y550313D02*
X1769631Y550307D01*
G01X1769640Y550317D02*
X1769635Y550313D01*
G01X1769645Y550321D02*
X1769640Y550317D01*
G01X1769627Y547146D02*
X1769626Y547139D01*
G01X1769628Y547152D02*
X1769627Y547146D01*
G01X1769631Y547158D02*
X1769628Y547152D01*
G01X1769635Y547163D02*
X1769631Y547158D01*
G01X1769640Y547168D02*
X1769635Y547163D01*
G01X1769645Y547171D02*
X1769640Y547168D01*
G01X1769627Y543996D02*
X1769626Y543990D01*
G01X1769628Y544002D02*
X1769627Y543996D01*
G01X1769631Y544008D02*
X1769628Y544002D01*
G01X1769635Y544013D02*
X1769631Y544008D01*
G01X1769640Y544018D02*
X1769635Y544013D01*
G01X1769645Y544022D02*
X1769640Y544018D01*
G01X1769627Y540846D02*
X1769626Y540840D01*
G01X1769628Y540853D02*
X1769627Y540846D01*
G01X1769631Y540859D02*
X1769628Y540853D01*
G01X1769635Y540864D02*
X1769631Y540859D01*
G01X1769640Y540869D02*
X1769635Y540864D01*
G01X1769645Y540872D02*
X1769640Y540869D01*
G01X1769627Y537697D02*
X1769626Y537691D01*
G01X1769628Y537703D02*
X1769627Y537697D01*
G01X1769631Y537709D02*
X1769628Y537703D01*
G01X1769635Y537714D02*
X1769631Y537709D01*
G01X1769640Y537719D02*
X1769635Y537714D01*
G01X1769645Y537722D02*
X1769640Y537719D01*
G01X1769648Y552286D02*
X1769663Y552283D01*
G01X1769636Y552294D02*
X1769648Y552286D01*
G01X1769624Y552314D02*
X1769636Y552294D01*
G01X1770610Y542868D02*
Y542860D01*
G01X1770609Y542872D02*
X1770610Y542868D01*
G01X1770609Y542874D02*
Y542872D01*
G01X1770610Y546018D02*
Y546010D01*
G01X1770609Y546022D02*
X1770610Y546018D01*
G01X1770609Y546024D02*
Y546022D01*
G01X1770610Y549167D02*
Y549159D01*
G01X1770609Y549172D02*
X1770610Y549167D01*
G01X1770609Y549173D02*
Y549172D01*
G01X1770610Y552317D02*
Y552309D01*
G01X1770609Y552321D02*
X1770610Y552317D01*
G01X1770609Y552323D02*
Y552321D01*
G01X1770610Y555467D02*
Y555459D01*
G01X1770609Y555471D02*
X1770610Y555467D01*
G01X1770609Y555472D02*
Y555471D01*
G01X1769648Y555436D02*
X1769663Y555433D01*
G01X1769636Y555444D02*
X1769648Y555436D01*
G01X1769624Y555464D02*
X1769636Y555444D01*
G01X1769648Y536538D02*
X1769663Y536535D01*
G01X1769635Y536547D02*
X1769648Y536538D01*
G01X1769624Y536567D02*
X1769635Y536547D01*
G01X1770609Y537697D02*
X1770610Y537691D01*
G01X1770608Y537704D02*
X1770609Y537697D01*
G01X1770605Y537709D02*
X1770608Y537704D01*
G01X1770609Y540847D02*
X1770610Y540840D01*
G01X1770608Y540853D02*
X1770609Y540847D01*
G01X1770605Y540859D02*
X1770608Y540853D01*
G01X1770609Y543996D02*
X1770610Y543990D01*
G01X1770608Y544003D02*
X1770609Y543996D01*
G01X1770605Y544009D02*
X1770608Y544003D01*
G01X1770609Y547146D02*
X1770610Y547139D01*
G01X1770608Y547152D02*
X1770609Y547146D01*
G01X1770605Y547158D02*
X1770608Y547152D01*
G01X1770609Y550296D02*
X1770610Y550289D01*
G01X1770608Y550302D02*
X1770609Y550296D01*
G01X1770605Y550308D02*
X1770608Y550302D01*
G01X1770609Y553445D02*
X1770610Y553439D01*
G01X1770608Y553452D02*
X1770609Y553445D01*
G01X1770605Y553457D02*
X1770608Y553452D01*
G01X1770609Y556595D02*
X1770610Y556588D01*
G01X1770608Y556601D02*
X1770609Y556595D01*
G01X1770605Y556607D02*
X1770608Y556601D01*
G01X1770571Y536530D02*
X1770572Y536524D01*
G01X1770570Y536534D02*
X1770571Y536530D01*
G01X1770569Y536535D02*
X1770570Y536534D01*
G01X1770571Y539680D02*
X1770572Y539674D01*
G01X1770570Y539683D02*
X1770571Y539680D01*
G01X1770569Y539685D02*
X1770570Y539683D01*
G01X1770571Y542830D02*
X1770572Y542823D01*
G01X1770570Y542833D02*
X1770571Y542830D01*
G01X1770569Y542835D02*
X1770570Y542833D01*
G01X1770571Y545979D02*
X1770572Y545973D01*
G01X1770570Y545983D02*
X1770571Y545979D01*
G01X1770569Y545984D02*
X1770570Y545983D01*
G01X1770571Y549129D02*
X1770572Y549122D01*
G01X1770570Y549132D02*
X1770571Y549129D01*
G01X1770569Y549134D02*
X1770570Y549132D01*
G01X1770571Y555428D02*
X1770572Y555422D01*
G01X1770570Y555431D02*
X1770571Y555428D01*
G01X1770569Y555433D02*
X1770570Y555431D01*
G01X1783051Y504771D02*
Y504780D01*
G01X1783052Y504765D02*
X1783051Y504771D01*
G01X1783053Y504764D02*
X1783052Y504765D01*
G01X1783051Y509771D02*
Y509780D01*
G01X1783052Y509765D02*
X1783051Y509771D01*
G01X1783053Y509764D02*
X1783052Y509765D01*
G01X1783051Y514771D02*
Y514780D01*
G01X1783052Y514765D02*
X1783051Y514771D01*
G01X1783053Y514764D02*
X1783052Y514765D01*
G01X1783051Y519771D02*
Y519780D01*
G01X1783052Y519765D02*
X1783051Y519771D01*
G01X1783053Y519764D02*
X1783052Y519765D01*
G01X1783051Y524771D02*
Y524780D01*
G01X1783052Y524765D02*
X1783051Y524771D01*
G01X1783053Y524764D02*
X1783052Y524765D01*
G01X1783051Y529771D02*
Y529780D01*
G01X1783052Y529765D02*
X1783051Y529771D01*
G01X1783053Y529764D02*
X1783052Y529765D01*
G01X1783051Y534771D02*
Y534780D01*
G01X1783052Y534765D02*
X1783051Y534771D01*
G01X1783053Y534764D02*
X1783052Y534765D01*
G01X1783051Y559771D02*
Y559780D01*
G01X1783052Y559765D02*
X1783051Y559771D01*
G01X1783053Y559764D02*
X1783052Y559765D01*
G01X1783051Y564771D02*
Y564780D01*
G01X1783052Y564765D02*
X1783051Y564771D01*
G01X1783053Y564764D02*
X1783052Y564765D01*
G01X1784028Y504907D02*
X1784035Y504881D01*
G01X1784018Y504934D02*
X1784028Y504907D01*
G01X1784006Y504961D02*
X1784018Y504934D01*
G01X1784028Y509907D02*
X1784035Y509881D01*
G01X1784018Y509934D02*
X1784028Y509907D01*
G01X1784006Y509961D02*
X1784018Y509934D01*
G01X1784028Y514907D02*
X1784035Y514881D01*
G01X1784018Y514934D02*
X1784028Y514907D01*
G01X1784006Y514961D02*
X1784018Y514934D01*
G01X1784028Y519907D02*
X1784035Y519881D01*
G01X1784018Y519934D02*
X1784028Y519907D01*
G01X1784006Y519961D02*
X1784018Y519934D01*
G01X1784028Y524907D02*
X1784035Y524881D01*
G01X1784018Y524934D02*
X1784028Y524907D01*
G01X1784006Y524961D02*
X1784018Y524934D01*
G01X1784028Y529907D02*
X1784035Y529881D01*
G01X1784018Y529934D02*
X1784028Y529907D01*
G01X1784006Y529961D02*
X1784018Y529934D01*
G01X1784028Y534907D02*
X1784035Y534881D01*
G01X1784018Y534934D02*
X1784028Y534907D01*
G01X1784006Y534961D02*
X1784018Y534934D01*
G01X1769626Y556581D02*
Y556588D01*
G01X1769625Y556576D02*
X1769626Y556581D01*
G01X1769624Y556575D02*
X1769625Y556576D01*
G01X1769626Y553431D02*
Y553439D01*
G01X1769625Y553427D02*
X1769626Y553431D01*
G01X1769624Y553425D02*
X1769625Y553427D01*
G01X1769626Y550281D02*
Y550289D01*
G01X1769625Y550277D02*
X1769626Y550281D01*
G01X1769624Y550276D02*
X1769625Y550277D01*
G01X1769626Y547132D02*
Y547139D01*
G01X1769625Y547128D02*
X1769626Y547132D01*
G01X1769624Y547126D02*
X1769625Y547128D01*
G01X1769626Y543982D02*
Y543990D01*
G01X1769625Y543978D02*
X1769626Y543982D01*
G01X1769624Y543976D02*
X1769625Y543978D01*
G01X1769626Y540833D02*
Y540840D01*
G01X1769625Y540828D02*
X1769626Y540833D01*
G01X1769624Y540827D02*
X1769625Y540828D01*
G01X1769626Y537683D02*
Y537691D01*
G01X1769625Y537679D02*
X1769626Y537683D01*
G01X1769624Y537677D02*
X1769625Y537679D01*
G01X1770608Y549147D02*
X1770610Y549159D01*
G01X1770601Y549136D02*
X1770608Y549147D01*
G01X1770591Y549128D02*
X1770601Y549136D01*
G01X1770608Y545998D02*
X1770610Y546010D01*
G01X1770601Y545986D02*
X1770608Y545998D01*
G01X1770591Y545978D02*
X1770601Y545986D01*
G01X1770608Y542848D02*
X1770610Y542860D01*
G01X1770601Y542837D02*
X1770608Y542848D01*
G01X1770591Y542829D02*
X1770601Y542837D01*
G01X1770608Y539698D02*
X1770610Y539711D01*
G01X1770601Y539687D02*
X1770608Y539698D01*
G01X1770591Y539679D02*
X1770601Y539687D01*
G01X1770608Y536549D02*
X1770610Y536561D01*
G01X1770601Y536537D02*
X1770608Y536549D01*
G01X1770591Y536530D02*
X1770601Y536537D01*
G01X1783051Y569771D02*
Y569780D01*
G01X1783052Y569765D02*
X1783051Y569771D01*
G01X1783053Y569764D02*
X1783052Y569765D01*
G01X1784028Y559907D02*
X1784035Y559881D01*
G01X1784018Y559934D02*
X1784028Y559907D01*
G01X1784006Y559961D02*
X1784018Y559934D01*
G01X1784028Y564907D02*
X1784035Y564881D01*
G01X1784018Y564934D02*
X1784028Y564907D01*
G01X1784006Y564961D02*
X1784018Y564934D01*
G01X1784028Y569907D02*
X1784035Y569881D01*
G01X1784018Y569934D02*
X1784028Y569907D01*
G01X1784006Y569961D02*
X1784018Y569934D01*
G01X1769644Y545989D02*
X1769663Y545984D01*
G01X1769630Y546002D02*
X1769644Y545989D01*
G01X1769624Y546019D02*
X1769630Y546002D01*
G01X1784018Y504759D02*
X1783999Y504764D01*
G01X1784033Y504744D02*
X1784018Y504759D01*
G01X1784038Y504724D02*
X1784033Y504744D01*
G01X1784018Y509759D02*
X1783999Y509764D01*
G01X1784033Y509744D02*
X1784018Y509759D01*
G01X1784038Y509724D02*
X1784033Y509744D01*
G01X1784018Y514759D02*
X1783999Y514764D01*
G01X1784033Y514744D02*
X1784018Y514759D01*
G01X1784038Y514724D02*
X1784033Y514744D01*
G01X1784018Y519759D02*
X1783999Y519764D01*
G01X1784033Y519744D02*
X1784018Y519759D01*
G01X1784038Y519724D02*
X1784033Y519744D01*
G01X1784018Y524759D02*
X1783999Y524764D01*
G01X1784033Y524744D02*
X1784018Y524759D01*
G01X1784038Y524724D02*
X1784033Y524744D01*
G01X1784018Y529759D02*
X1783999Y529764D01*
G01X1784033Y529744D02*
X1784018Y529759D01*
G01X1784038Y529724D02*
X1784033Y529744D01*
G01X1784018Y534759D02*
X1783999Y534764D01*
G01X1784033Y534744D02*
X1784018Y534759D01*
G01X1784038Y534724D02*
X1784033Y534744D01*
G01X1784018Y559759D02*
X1783999Y559764D01*
G01X1784033Y559744D02*
X1784018Y559759D01*
G01X1784038Y559724D02*
X1784033Y559744D01*
G01X1784018Y564759D02*
X1783999Y564764D01*
G01X1784033Y564744D02*
X1784018Y564759D01*
G01X1784038Y564724D02*
X1784033Y564744D01*
G01X1784018Y569759D02*
X1783999Y569764D01*
G01X1784033Y569744D02*
X1784018Y569759D01*
G01X1784038Y569724D02*
X1784033Y569744D01*
G01X1784002Y504862D02*
X1784006Y504961D01*
G01X1783997Y504790D02*
X1784002Y504862D01*
G01X1783999Y504764D02*
X1783997Y504790D01*
G01X1784002Y509862D02*
X1784006Y509961D01*
G01X1783997Y509790D02*
X1784002Y509862D01*
G01X1783999Y509764D02*
X1783997Y509790D01*
G01X1784002Y514862D02*
X1784006Y514961D01*
G01X1783997Y514790D02*
X1784002Y514862D01*
G01X1783999Y514764D02*
X1783997Y514790D01*
G01X1784002Y519862D02*
X1784006Y519961D01*
G01X1783997Y519790D02*
X1784002Y519862D01*
G01X1783999Y519764D02*
X1783997Y519790D01*
G01X1784002Y524862D02*
X1784006Y524961D01*
G01X1783997Y524790D02*
X1784002Y524862D01*
G01X1783999Y524764D02*
X1783997Y524790D01*
G01X1784002Y529862D02*
X1784006Y529961D01*
G01X1783997Y529790D02*
X1784002Y529862D01*
G01X1783999Y529764D02*
X1783997Y529790D01*
G01X1784002Y534862D02*
X1784006Y534961D01*
G01X1783997Y534790D02*
X1784002Y534862D01*
G01X1783999Y534764D02*
X1783997Y534790D01*
G01X1784002Y559862D02*
X1784006Y559961D01*
G01X1783997Y559790D02*
X1784002Y559862D01*
G01X1783999Y559764D02*
X1783997Y559790D01*
G01X1784002Y564862D02*
X1784006Y564961D01*
G01X1783997Y564790D02*
X1784002Y564862D01*
G01X1783999Y564764D02*
X1783997Y564790D01*
G01X1784002Y569862D02*
X1784006Y569961D01*
G01X1783997Y569790D02*
X1784002Y569862D01*
G01X1783999Y569764D02*
X1783997Y569790D01*
G01X1769626Y549167D02*
Y549160D01*
G01X1769625Y549172D02*
X1769626Y549167D01*
G01X1769625Y549162D02*
Y549172D01*
G01X1769666Y556798D02*
X1769665Y556811D01*
G01X1769663Y556785D02*
X1769666Y556798D01*
G01X1769663Y556772D02*
Y556785D01*
G01X1769666Y553649D02*
X1769665Y553661D01*
G01X1769663Y553636D02*
X1769666Y553649D01*
G01X1769663Y553622D02*
Y553636D01*
G01X1769666Y550499D02*
X1769665Y550512D01*
G01X1769663Y550486D02*
X1769666Y550499D01*
G01X1769663Y550472D02*
Y550486D01*
G01X1769666Y547350D02*
X1769665Y547362D01*
G01X1769663Y547337D02*
X1769666Y547350D01*
G01X1769663Y547323D02*
Y547337D01*
G01X1769666Y544200D02*
X1769665Y544213D01*
G01X1769663Y544187D02*
X1769666Y544200D01*
G01X1769663Y544173D02*
Y544187D01*
G01X1769666Y541050D02*
X1769665Y541063D01*
G01X1769663Y541037D02*
X1769666Y541050D01*
G01X1769663Y541024D02*
Y541037D01*
G01X1769666Y537901D02*
X1769665Y537913D01*
G01X1769663Y537888D02*
X1769666Y537901D01*
G01X1769663Y537874D02*
Y537888D01*
G01X1783052Y568384D02*
X1783053Y568386D01*
G01X1783051Y568378D02*
X1783052Y568384D01*
G01X1783051Y568370D02*
Y568378D01*
G01X1783052Y563384D02*
X1783053Y563386D01*
G01X1783051Y563378D02*
X1783052Y563384D01*
G01X1783051Y563370D02*
Y563378D01*
G01X1783052Y558384D02*
X1783053Y558386D01*
G01X1783051Y558378D02*
X1783052Y558384D01*
G01X1783051Y558370D02*
Y558378D01*
G01X1783052Y533384D02*
X1783053Y533386D01*
G01X1783051Y533378D02*
X1783052Y533384D01*
G01X1783051Y533370D02*
Y533378D01*
G01X1783052Y528384D02*
X1783053Y528386D01*
G01X1783051Y528378D02*
X1783052Y528384D01*
G01X1783051Y528370D02*
Y528378D01*
G01X1783052Y523384D02*
X1783053Y523386D01*
G01X1783051Y523378D02*
X1783052Y523384D01*
G01X1783051Y523370D02*
Y523378D01*
G01X1783052Y518384D02*
X1783053Y518386D01*
G01X1783051Y518378D02*
X1783052Y518384D01*
G01X1783051Y518370D02*
Y518378D01*
G01X1783052Y513384D02*
X1783053Y513386D01*
G01X1783051Y513378D02*
X1783052Y513384D01*
G01X1783051Y513370D02*
Y513378D01*
G01X1783052Y508384D02*
X1783053Y508386D01*
G01X1783051Y508378D02*
X1783052Y508384D01*
G01X1783051Y508370D02*
Y508378D01*
G01X1783052Y503384D02*
X1783053Y503386D01*
G01X1783051Y503378D02*
X1783052Y503384D01*
G01X1783051Y503370D02*
Y503378D01*
G01X1769626Y555467D02*
Y555459D01*
G01X1769625Y555471D02*
X1769626Y555467D01*
G01X1769625Y555463D02*
Y555471D01*
G01X1769663Y555261D02*
X1769662Y555275D01*
G01X1769666Y555249D02*
X1769663Y555261D01*
G01X1769665Y555236D02*
X1769666Y555249D01*
G01X1769663Y552112D02*
X1769662Y552126D01*
G01X1769666Y552099D02*
X1769663Y552112D01*
G01X1769665Y552087D02*
X1769666Y552099D01*
G01X1769663Y548962D02*
X1769662Y548976D01*
G01X1769666Y548950D02*
X1769663Y548962D01*
G01X1769665Y548937D02*
X1769666Y548950D01*
G01X1769663Y545813D02*
X1769662Y545826D01*
G01X1769666Y545800D02*
X1769663Y545813D01*
G01X1769665Y545787D02*
X1769666Y545800D01*
G01X1769663Y542663D02*
X1769662Y542677D01*
G01X1769666Y542650D02*
X1769663Y542663D01*
G01X1769665Y542638D02*
X1769666Y542650D01*
G01X1769663Y539513D02*
X1769662Y539527D01*
G01X1769666Y539501D02*
X1769663Y539513D01*
G01X1769665Y539488D02*
X1769666Y539501D01*
G01X1769663Y536364D02*
X1769662Y536378D01*
G01X1769666Y536351D02*
X1769663Y536364D01*
G01X1769665Y536339D02*
X1769666Y536351D01*
G01X1770573Y556785D02*
X1770574Y556772D01*
G01X1770570Y556798D02*
X1770573Y556785D01*
G01X1770571Y556811D02*
X1770570Y556798D01*
G01X1770573Y553636D02*
X1770574Y553622D01*
G01X1770570Y553649D02*
X1770573Y553636D01*
G01X1770571Y553661D02*
X1770570Y553649D01*
G01X1770573Y550486D02*
X1770574Y550472D01*
G01X1770570Y550499D02*
X1770573Y550486D01*
G01X1770571Y550512D02*
X1770570Y550499D01*
G01X1770573Y547337D02*
X1770574Y547323D01*
G01X1770570Y547350D02*
X1770573Y547337D01*
G01X1770571Y547362D02*
X1770570Y547350D01*
G01X1770573Y544187D02*
X1770574Y544173D01*
G01X1770570Y544200D02*
X1770573Y544187D01*
G01X1770571Y544213D02*
X1770570Y544200D01*
G01X1770573Y541037D02*
X1770574Y541024D01*
G01X1770570Y541050D02*
X1770573Y541037D01*
G01X1770571Y541063D02*
X1770570Y541050D01*
G01X1770573Y537888D02*
X1770574Y537874D01*
G01X1770570Y537901D02*
X1770573Y537888D01*
G01X1770571Y537913D02*
X1770570Y537901D01*
G01X1769626Y542868D02*
Y542861D01*
G01X1769625Y542872D02*
X1769626Y542868D01*
G01X1769624Y542865D02*
X1769625Y542872D01*
G01X1769626Y552317D02*
Y552309D01*
G01X1769625Y552321D02*
X1769626Y552317D01*
G01X1769624Y552314D02*
X1769625Y552321D01*
G01X1770570Y555249D02*
X1770571Y555236D01*
G01X1770573Y555261D02*
X1770570Y555249D01*
G01X1770574Y555275D02*
X1770573Y555261D01*
G01X1770570Y552099D02*
X1770571Y552087D01*
G01X1770573Y552112D02*
X1770570Y552099D01*
G01X1770574Y552126D02*
X1770573Y552112D01*
G01X1770570Y548950D02*
X1770571Y548937D01*
G01X1770573Y548962D02*
X1770570Y548950D01*
G01X1770574Y548976D02*
X1770573Y548962D01*
G01X1770570Y545800D02*
X1770571Y545787D01*
G01X1770573Y545813D02*
X1770570Y545800D01*
G01X1770574Y545826D02*
X1770573Y545813D01*
G01X1770570Y542650D02*
X1770571Y542638D01*
G01X1770573Y542663D02*
X1770570Y542650D01*
G01X1770574Y542677D02*
X1770573Y542663D01*
G01X1770570Y539501D02*
X1770571Y539488D01*
G01X1770573Y539513D02*
X1770570Y539501D01*
G01X1770574Y539527D02*
X1770573Y539513D01*
G01X1770570Y536351D02*
X1770571Y536339D01*
G01X1770573Y536364D02*
X1770570Y536351D01*
G01X1770574Y536378D02*
X1770573Y536364D01*
G01X1769626Y536569D02*
Y536561D01*
G01X1769625Y536573D02*
X1769626Y536569D01*
G01X1769624Y536567D02*
X1769625Y536573D01*
G01X1769639Y556606D02*
X1769663Y556614D01*
G01X1769628Y556591D02*
X1769639Y556606D01*
G01X1769626Y556584D02*
X1769628Y556591D01*
G01X1769639Y553456D02*
X1769663Y553465D01*
G01X1769628Y553441D02*
X1769639Y553456D01*
G01X1769626Y553435D02*
X1769628Y553441D01*
G01X1769639Y550306D02*
X1769663Y550315D01*
G01X1769628Y550292D02*
X1769639Y550306D01*
G01X1769626Y550285D02*
X1769628Y550292D01*
G01X1769639Y547157D02*
X1769663Y547165D01*
G01X1769628Y547142D02*
X1769639Y547157D01*
G01X1769626Y547135D02*
X1769628Y547142D01*
G01X1769639Y544007D02*
X1769663Y544016D01*
G01X1769628Y543993D02*
X1769639Y544007D01*
G01X1769626Y543986D02*
X1769628Y543993D01*
G01X1769639Y540857D02*
X1769663Y540866D01*
G01X1769628Y540843D02*
X1769639Y540857D01*
G01X1769626Y540836D02*
X1769628Y540843D01*
G01X1770610Y556581D02*
Y556588D01*
G01Y556576D02*
Y556581D01*
G01X1770609Y556575D02*
X1770610Y556576D01*
G01Y553431D02*
Y553439D01*
G01Y553427D02*
Y553431D01*
G01X1770609Y553425D02*
X1770610Y553427D01*
G01Y550282D02*
Y550289D01*
G01Y550277D02*
Y550282D01*
G01X1770609Y550276D02*
X1770610Y550277D01*
G01Y547132D02*
Y547139D01*
G01Y547128D02*
Y547132D01*
G01X1770609Y547126D02*
X1770610Y547128D01*
G01Y543983D02*
Y543990D01*
G01Y543978D02*
Y543983D01*
G01X1770609Y543976D02*
X1770610Y543978D01*
G01Y540833D02*
Y540840D01*
G01Y540828D02*
Y540833D01*
G01X1770609Y540827D02*
X1770610Y540828D01*
G01Y537683D02*
Y537691D01*
G01Y537679D02*
Y537683D01*
G01X1770609Y537677D02*
X1770610Y537679D01*
G01X1769626Y546018D02*
Y546010D01*
G01X1769625Y546022D02*
X1769626Y546018D01*
G01X1769624Y546019D02*
X1769625Y546022D01*
G01X1769626Y539719D02*
Y539711D01*
G01X1769625Y539723D02*
X1769626Y539719D01*
G01X1769624Y539721D02*
X1769625Y539723D01*
G01X1770571Y556619D02*
Y556625D01*
G01X1770570Y556615D02*
X1770571Y556619D01*
G01X1770569Y556614D02*
X1770570Y556615D01*
G01X1770571Y553470D02*
Y553476D01*
G01X1770570Y553466D02*
X1770571Y553470D01*
G01X1770569Y553465D02*
X1770570Y553466D01*
G01X1770571Y550320D02*
Y550326D01*
G01X1770570Y550316D02*
X1770571Y550320D01*
G01X1770569Y550315D02*
X1770570Y550316D01*
G01X1770571Y547170D02*
Y547176D01*
G01X1770570Y547167D02*
X1770571Y547170D01*
G01X1770569Y547165D02*
X1770570Y547167D01*
G01X1770571Y544021D02*
Y544027D01*
G01X1770570Y544017D02*
X1770571Y544021D01*
G01X1770569Y544016D02*
X1770570Y544017D01*
G01X1770571Y540871D02*
Y540877D01*
G01X1770570Y540867D02*
X1770571Y540871D01*
G01X1770569Y540866D02*
X1770570Y540867D01*
G01X1770571Y537722D02*
Y537728D01*
G01X1770570Y537718D02*
X1770571Y537722D01*
G01X1770569Y537717D02*
X1770570Y537718D01*
G01X1784036Y568378D02*
X1784035Y568369D01*
G01X1784037Y568384D02*
X1784036Y568378D01*
G01X1784038Y568386D02*
X1784037Y568384D01*
G01X1784036Y563378D02*
X1784035Y563369D01*
G01X1784037Y563384D02*
X1784036Y563378D01*
G01X1784038Y563386D02*
X1784037Y563384D01*
G01X1784036Y558378D02*
X1784035Y558369D01*
G01X1784037Y558384D02*
X1784036Y558378D01*
G01X1784038Y558386D02*
X1784037Y558384D01*
G01X1784036Y533378D02*
X1784035Y533369D01*
G01X1784037Y533384D02*
X1784036Y533378D01*
G01X1784038Y533386D02*
X1784037Y533384D01*
G01X1784036Y528378D02*
X1784035Y528369D01*
G01X1784037Y528384D02*
X1784036Y528378D01*
G01X1784038Y528386D02*
X1784037Y528384D01*
G01X1784036Y523378D02*
X1784035Y523369D01*
G01X1784037Y523384D02*
X1784036Y523378D01*
G01X1784038Y523386D02*
X1784037Y523384D01*
G01X1784036Y518378D02*
X1784035Y518369D01*
G01X1784037Y518384D02*
X1784036Y518378D01*
G01X1784038Y518386D02*
X1784037Y518384D01*
G01X1784036Y513378D02*
X1784035Y513369D01*
G01X1784037Y513384D02*
X1784036Y513378D01*
G01X1784038Y513386D02*
X1784037Y513384D01*
G01X1784036Y508378D02*
X1784035Y508369D01*
G01X1784037Y508384D02*
X1784036Y508378D01*
G01X1784038Y508386D02*
X1784037Y508384D01*
G01X1784036Y503378D02*
X1784035Y503369D01*
G01X1784037Y503384D02*
X1784036Y503378D01*
G01X1784038Y503386D02*
X1784037Y503384D01*
G01X1770603Y543998D02*
X1770595Y544006D01*
G01X1770607Y543987D02*
X1770603Y543998D01*
G01X1770609Y543976D02*
X1770607Y543987D01*
G01X1770603Y537698D02*
X1770595Y537707D01*
G01X1770607Y537688D02*
X1770603Y537698D01*
G01X1770609Y537677D02*
X1770607Y537688D01*
G01X1770603Y540848D02*
X1770595Y540856D01*
G01X1770607Y540838D02*
X1770603Y540848D01*
G01X1770609Y540827D02*
X1770607Y540838D01*
G01X1770603Y547147D02*
X1770595Y547156D01*
G01X1770607Y547137D02*
X1770603Y547147D01*
G01X1770609Y547126D02*
X1770607Y547137D01*
G01X1770603Y550297D02*
X1770595Y550305D01*
G01X1770607Y550287D02*
X1770603Y550297D01*
G01X1770609Y550276D02*
X1770607Y550287D01*
G01X1770603Y553446D02*
X1770595Y553455D01*
G01X1770607Y553436D02*
X1770603Y553446D01*
G01X1770609Y553425D02*
X1770607Y553436D01*
G01X1770603Y556596D02*
X1770595Y556604D01*
G01X1770607Y556586D02*
X1770603Y556596D01*
G01X1770609Y556575D02*
X1770607Y556586D01*
G01X1769639Y537708D02*
X1769663Y537717D01*
G01X1769628Y537693D02*
X1769639Y537708D01*
G01X1769626Y537687D02*
X1769628Y537693D01*
G01X1779646Y492264D02*
G03I-1103J0D01*
G01X1781102Y486988D02*
G03X1782283Y488169I0J1181D01*
G01X1774803D02*
G03X1775984Y486988I1181J0D01*
G01X1780118Y492264D02*
G03I-1575J0D01*
G01X1774606Y477894D02*
G03X1775197Y477303I591J0D01*
G01X1781890D02*
G03X1782480Y477894I0J590D01*
G01X1779724Y479075D02*
G03Y481043I0J984D01*
G01X1777362D02*
G03Y479075I0J-984D01*
G01X1767717Y478484D02*
G03X1769685Y476516I1968J0D01*
G01X1787402D02*
G03X1789370Y478484I0J1968D01*
G01X1775052Y487444D02*
X1777362Y491673D01*
G01X1774016Y500256D02*
X1772835Y499075D01*
G01X1771063Y497579D02*
X1767717Y494232D01*
G01X1781028Y495335D02*
X1779724Y493366D01*
G01X1770610Y537679D02*
Y537691D01*
G01Y540829D02*
Y540840D01*
G01Y543978D02*
Y543990D01*
G01Y547128D02*
Y547139D01*
G01Y550278D02*
Y550289D01*
G01Y553427D02*
Y553439D01*
G01Y556577D02*
Y556588D01*
G01X1784035Y504738D02*
X1784036Y504746D01*
G01X1784035Y509738D02*
X1784036Y509746D01*
G01X1784035Y514738D02*
X1784036Y514746D01*
G01X1784035Y519738D02*
X1784036Y519746D01*
G01X1784035Y524738D02*
X1784036Y524746D01*
G01X1784035Y529738D02*
X1784036Y529746D01*
G01X1784035Y534738D02*
X1784036Y534746D01*
G01X1784035Y559738D02*
X1784036Y559746D01*
G01X1784035Y564738D02*
X1784036Y564746D01*
G01X1784035Y569738D02*
X1784036Y569746D01*
G01X1789370Y478484D02*
Y494232D01*
G01X1788386Y568386D02*
Y569764D01*
G01Y563386D02*
Y564764D01*
G01Y558386D02*
Y559764D01*
G01Y533386D02*
Y534764D01*
G01Y528386D02*
Y529764D01*
G01Y523386D02*
Y524764D01*
G01Y518386D02*
Y519764D01*
G01Y513386D02*
Y514764D01*
G01Y508386D02*
Y509764D01*
G01Y503386D02*
Y504764D01*
G01X1786024Y635571D02*
Y497579D01*
G01X1785433Y637815D02*
Y495335D01*
G01X1785217Y504764D02*
Y503386D01*
G01Y509764D02*
Y508386D01*
G01Y514764D02*
Y513386D01*
G01Y519764D02*
Y518386D01*
G01Y524764D02*
Y523386D01*
G01Y529764D02*
Y528386D01*
G01Y534764D02*
Y533386D01*
G01Y559764D02*
Y558386D01*
G01Y564764D02*
Y563386D01*
G01Y569764D02*
Y568386D01*
G01X1784646Y557618D02*
Y535531D01*
G01X1784035Y509738D02*
Y509881D01*
G01Y504738D02*
Y504881D01*
G01Y519738D02*
Y519881D01*
G01Y514738D02*
Y514881D01*
G01Y529738D02*
Y529881D01*
G01Y524738D02*
Y524881D01*
G01Y534738D02*
Y534881D01*
G01Y559738D02*
Y559881D01*
G01Y569738D02*
Y569881D01*
G01Y564738D02*
Y564881D01*
G01Y567894D02*
Y570256D01*
G01Y562894D02*
Y565256D01*
G01Y557894D02*
Y560256D01*
G01Y532894D02*
Y535256D01*
G01Y527894D02*
Y530256D01*
G01Y522894D02*
Y525256D01*
G01Y517894D02*
Y520256D01*
G01Y512894D02*
Y515256D01*
G01Y507894D02*
Y510256D01*
G01Y502894D02*
Y505256D01*
G01X1783465Y556437D02*
Y536713D01*
G01X1783051Y505256D02*
Y502894D01*
G01Y510256D02*
Y507894D01*
G01Y515256D02*
Y512894D01*
G01Y520256D02*
Y517894D01*
G01Y525256D02*
Y522894D01*
G01Y530256D02*
Y527894D01*
G01Y535256D02*
Y532894D01*
G01Y560256D02*
Y557894D01*
G01Y565256D02*
Y562894D01*
G01Y570256D02*
Y567894D01*
G01X1782480Y483996D02*
Y477894D01*
G01X1782283Y496713D02*
Y488169D01*
G01X1780709Y535531D02*
Y499075D01*
G01Y634075D02*
Y557618D01*
G01X1779724Y493366D02*
Y491673D01*
G01X1779528Y536713D02*
Y500256D01*
G01Y632894D02*
Y556437D01*
G01X1777362Y491673D02*
Y493366D01*
G01X1774803Y488169D02*
Y496713D01*
G01X1774606Y483996D02*
Y477894D01*
G01X1774016Y500256D02*
Y632894D01*
G01X1772835Y499075D02*
Y634075D01*
G01X1771063Y534370D02*
Y495335D01*
G01Y637815D02*
Y558780D01*
G01X1770610Y555275D02*
Y556772D01*
G01Y552126D02*
Y553622D01*
G01Y548976D02*
Y550472D01*
G01Y545826D02*
Y547323D01*
G01Y542677D02*
Y544173D01*
G01Y539527D02*
Y541024D01*
G01Y536378D02*
Y537874D01*
G01X1770571Y536524D02*
Y536377D01*
G01Y539674D02*
Y539527D01*
G01Y541024D02*
Y540877D01*
G01Y537874D02*
Y537728D01*
G01Y545973D02*
Y545826D01*
G01Y542823D02*
Y542676D01*
G01Y544174D02*
Y544027D01*
G01Y549122D02*
Y548976D01*
G01Y550473D02*
Y550326D01*
G01Y547323D02*
Y547176D01*
G01Y555422D02*
Y555275D01*
G01Y552272D02*
Y552125D01*
G01Y553622D02*
Y553476D01*
G01Y556772D02*
Y556625D01*
G01X1769665D02*
Y556772D01*
G01Y555275D02*
Y555422D01*
G01Y552125D02*
Y552272D01*
G01Y553476D02*
Y553622D01*
G01Y548976D02*
Y549122D01*
G01Y550326D02*
Y550473D01*
G01Y547176D02*
Y547323D01*
G01Y545826D02*
Y545973D01*
G01Y542676D02*
Y542823D01*
G01Y544027D02*
Y544174D01*
G01Y539527D02*
Y539674D01*
G01Y540877D02*
Y541024D01*
G01Y537728D02*
Y537874D01*
G01Y536377D02*
Y536524D01*
G01X1769626Y541024D02*
Y539528D01*
G01Y537874D02*
Y536378D01*
G01Y544173D02*
Y542677D01*
G01Y550472D02*
Y548976D01*
G01Y547323D02*
Y545827D01*
G01Y553622D02*
Y552126D01*
G01Y556772D02*
Y555276D01*
G01X1768445Y537717D02*
Y536535D01*
G01Y540866D02*
Y539685D01*
G01Y547165D02*
Y545984D01*
G01Y544016D02*
Y542835D01*
G01Y550315D02*
Y549134D01*
G01Y556614D02*
Y555433D01*
G01Y553465D02*
Y552283D01*
G01X1768110Y558780D02*
Y534370D01*
G01X1767717D02*
Y558780D01*
G01Y494232D02*
Y478484D01*
G01X1764685Y555433D02*
Y556614D01*
G01Y552283D02*
Y553465D01*
G01Y549134D02*
Y550315D01*
G01Y545984D02*
Y547165D01*
G01Y542835D02*
Y544016D01*
G01Y539685D02*
Y540866D01*
G01Y536535D02*
Y537717D01*
G01X1770610Y555459D02*
Y555470D01*
G01Y552309D02*
Y552320D01*
G01Y549160D02*
Y549170D01*
G01Y546010D02*
Y546021D01*
G01Y542861D02*
Y542871D01*
G01Y539711D02*
Y539722D01*
G01Y536561D02*
Y536572D01*
G01X1770569Y552283D02*
X1770573Y552272D01*
G01X1783465Y556437D02*
X1784646Y557618D01*
G01X1779528Y556437D02*
X1780709Y557618D01*
G01X1779724Y491673D02*
X1782035Y487444D01*
G01X1777362Y493366D02*
X1776059Y495335D01*
G01X1783465Y536713D02*
X1784646Y535531D01*
G01X1779528Y536713D02*
X1780709Y535531D01*
G01X1789370Y494232D02*
X1786024Y497579D01*
G01X1779528Y500256D02*
X1780709Y499075D01*
G01X1769513Y555472D02*
X1769624Y555464D01*
G01Y546019D02*
X1769513Y546024D01*
G01X1769624Y539721D02*
X1769513Y539724D01*
G01X1769624Y549170D02*
X1769513Y549173D01*
G01X1784035Y570256D02*
X1783051D01*
G01X1783053Y569764D02*
X1788386D01*
G01Y569724D02*
X1784038D01*
G01X1788386Y568386D02*
X1783053D01*
G01X1783051Y567894D02*
X1784035D01*
G01Y565256D02*
X1783051D01*
G01X1783053Y564764D02*
X1788386D01*
G01Y564724D02*
X1784038D01*
G01X1788386Y563386D02*
X1783053D01*
G01X1783051Y562894D02*
X1784035D01*
G01Y560256D02*
X1783051D01*
G01X1783053Y559764D02*
X1788386D01*
G01Y559724D02*
X1784038D01*
G01X1771063Y558780D02*
X1767717D01*
G01X1788386Y558386D02*
X1783053D01*
G01X1783051Y557894D02*
X1784035D01*
G01X1780709Y557618D02*
X1784646D01*
G01X1770571Y556811D02*
X1769665D01*
G01X1770610Y556772D02*
X1769626D01*
G01X1770569Y556614D02*
X1764685D01*
G01Y556575D02*
X1770609D01*
G01X1779528Y556437D02*
X1783465D01*
G01X1770609Y555472D02*
X1764685D01*
G01X1770569Y555433D02*
X1764685D01*
G01X1769626Y555276D02*
X1770610D01*
G01X1769665Y555236D02*
X1770571D01*
G01Y553661D02*
X1769665D01*
G01X1770610Y553622D02*
X1769626D01*
G01X1770569Y553465D02*
X1764685D01*
G01Y553425D02*
X1770609D01*
G01Y552323D02*
X1764685D01*
G01X1770569Y552283D02*
X1764685D01*
G01X1769626Y552126D02*
X1770610D01*
G01X1769665Y552087D02*
X1770571D01*
G01Y550512D02*
X1769665D01*
G01X1770610Y550472D02*
X1769626D01*
G01X1770569Y550315D02*
X1764685D01*
G01Y550276D02*
X1770609D01*
G01X1768879Y549173D02*
X1768445D01*
G01X1770609D02*
X1764685D01*
G01X1770569Y549134D02*
X1764685D01*
G01X1769626Y548976D02*
X1770610D01*
G01X1769665Y548937D02*
X1770571D01*
G01Y547362D02*
X1769665D01*
G01X1770610Y547323D02*
X1769626D01*
G01X1770569Y547165D02*
X1764685D01*
G01Y547126D02*
X1770609D01*
G01X1768879Y546024D02*
X1768445D01*
G01X1770609D02*
X1764685D01*
G01X1770569Y545984D02*
X1764685D01*
G01X1769626Y545827D02*
X1770610D01*
G01X1769665Y545787D02*
X1770571D01*
G01Y544213D02*
X1769665D01*
G01X1770610Y544173D02*
X1769626D01*
G01X1770569Y544016D02*
X1764685D01*
G01Y543976D02*
X1770609D01*
G01Y542874D02*
X1764685D01*
G01X1770569Y542835D02*
X1764685D01*
G01X1769626Y542677D02*
X1770610D01*
G01X1769665Y542638D02*
X1770571D01*
G01Y541063D02*
X1769665D01*
G01X1770610Y541024D02*
X1769626D01*
G01X1770569Y540866D02*
X1764685D01*
G01Y540827D02*
X1770609D01*
G01X1768879Y539724D02*
X1768445D01*
G01X1770609D02*
X1764685D01*
G01X1770569Y539685D02*
X1764685D01*
G01X1769626Y539528D02*
X1770610D01*
G01X1769665Y539488D02*
X1770571D01*
G01Y537913D02*
X1769665D01*
G01X1770610Y537874D02*
X1769626D01*
G01X1770569Y537717D02*
X1764685D01*
G01Y537677D02*
X1770609D01*
G01X1783465Y536713D02*
X1779528D01*
G01X1770609Y536575D02*
X1764685D01*
G01X1770569Y536535D02*
X1764685D01*
G01X1769626Y536378D02*
X1770610D01*
G01X1769665Y536339D02*
X1770571D01*
G01X1784646Y535531D02*
X1780709D01*
G01X1784035Y535256D02*
X1783051D01*
G01X1783053Y534764D02*
X1788386D01*
G01Y534724D02*
X1784038D01*
G01X1771063Y534370D02*
X1767717D01*
G01X1788386Y533386D02*
X1783053D01*
G01X1783051Y532894D02*
X1784035D01*
G01Y530256D02*
X1783051D01*
G01X1783053Y529764D02*
X1788386D01*
G01Y529724D02*
X1784038D01*
G01X1788386Y528386D02*
X1783053D01*
G01X1783051Y569959D02*
X1784006Y569961D01*
G01X1784035Y568190D02*
X1783051Y568189D01*
G01Y564959D02*
X1784006Y564961D01*
G01X1784035Y563190D02*
X1783051Y563189D01*
G01Y559959D02*
X1784006Y559961D01*
G01X1784035Y558190D02*
X1783051Y558189D01*
G01Y534959D02*
X1784006Y534961D01*
G01X1784035Y533190D02*
X1783051Y533189D01*
G01Y529959D02*
X1784006Y529961D01*
G01X1783051Y527894D02*
X1784035D01*
G01Y525256D02*
X1783051D01*
G01X1783053Y524764D02*
X1788386D01*
G01Y524724D02*
X1784038D01*
G01X1788386Y523386D02*
X1783053D01*
G01X1783051Y522894D02*
X1784035D01*
G01Y520256D02*
X1783051D01*
G01X1783053Y519764D02*
X1788386D01*
G01Y519724D02*
X1784038D01*
G01X1788386Y518386D02*
X1783053D01*
G01X1783051Y517894D02*
X1784035D01*
G01Y515256D02*
X1783051D01*
G01X1783053Y514764D02*
X1788386D01*
G01Y514724D02*
X1784038D01*
G01X1788386Y513386D02*
X1783053D01*
G01X1783051Y512894D02*
X1784035D01*
G01Y510256D02*
X1783051D01*
G01X1783053Y509764D02*
X1788386D01*
G01Y509724D02*
X1784038D01*
G01X1788386Y508386D02*
X1783053D01*
G01X1783051Y507894D02*
X1784035D01*
G01Y505256D02*
X1783051D01*
G01X1783053Y504764D02*
X1788386D01*
G01Y504724D02*
X1784038D01*
G01X1788386Y503386D02*
X1783053D01*
G01X1783051Y502894D02*
X1784035D01*
G01X1779528Y500256D02*
X1774016D01*
G01X1780709Y499075D02*
X1772835D01*
G01X1786024Y497579D02*
X1771063D01*
G01X1782283Y496713D02*
X1785433D01*
G01X1774803D02*
X1771063D01*
G01Y495335D02*
X1785433D01*
G01X1779724Y493366D02*
X1777362D01*
G01X1779724Y491673D02*
X1777362D01*
G01X1781102Y486988D02*
X1775984D01*
G01X1789370Y486949D02*
X1767717D01*
G01X1782480Y483996D02*
X1774606D01*
G01Y482421D02*
X1782480D01*
G01X1779724Y481043D02*
X1777362D01*
G01Y479075D02*
X1779724D01*
G01X1781890Y477303D02*
X1775197D01*
G01X1787402Y476516D02*
X1769685D01*
G01X1784035Y528190D02*
X1783051Y528189D01*
G01Y524959D02*
X1784006Y524961D01*
G01X1784035Y523190D02*
X1783051Y523189D01*
G01Y519959D02*
X1784006Y519961D01*
G01X1784035Y518190D02*
X1783051Y518189D01*
G01Y514959D02*
X1784006Y514961D01*
G01X1784035Y513190D02*
X1783051Y513189D01*
G01Y509959D02*
X1784006Y509961D01*
G01X1784035Y508190D02*
X1783051Y508189D01*
G01Y504959D02*
X1784006Y504961D01*
G01X1784035Y503190D02*
X1783051Y503189D01*
G01X1784023Y574755D02*
X1784034Y574740D01*
G01X1783998Y574764D02*
X1784023Y574755D01*
G01Y579755D02*
X1784034Y579740D01*
G01X1783998Y579764D02*
X1784023Y579755D01*
G01Y584755D02*
X1784034Y584740D01*
G01X1783998Y584764D02*
X1784023Y584755D01*
G01Y589755D02*
X1784034Y589740D01*
G01X1783998Y589764D02*
X1784023Y589755D01*
G01Y594755D02*
X1784034Y594740D01*
G01X1783998Y594764D02*
X1784023Y594755D01*
G01Y599755D02*
X1784034Y599740D01*
G01X1783998Y599764D02*
X1784023Y599755D01*
G01Y604755D02*
X1784034Y604740D01*
G01X1783998Y604764D02*
X1784023Y604755D01*
G01Y609755D02*
X1784034Y609740D01*
G01X1783998Y609764D02*
X1784023Y609755D01*
G01X1784034Y614740D02*
X1784035Y614734D01*
G01X1784023Y614755D02*
X1784034Y614740D01*
G01X1783998Y614764D02*
X1784023Y614755D01*
G01Y619755D02*
X1784034Y619740D01*
G01X1783998Y619764D02*
X1784023Y619755D01*
G01Y624755D02*
X1784034Y624740D01*
G01X1783998Y624764D02*
X1784023Y624755D01*
G01Y629755D02*
X1784034Y629740D01*
G01X1783998Y629764D02*
X1784023Y629755D01*
G01X1784036Y574731D02*
X1784035Y574738D01*
G01X1784037Y574726D02*
X1784036Y574731D01*
G01X1784038Y574724D02*
X1784037Y574726D01*
G01X1784036Y579731D02*
X1784035Y579738D01*
G01X1784037Y579726D02*
X1784036Y579731D01*
G01X1784038Y579724D02*
X1784037Y579726D01*
G01X1784036Y584731D02*
X1784035Y584738D01*
G01X1784037Y584726D02*
X1784036Y584731D01*
G01X1784038Y584724D02*
X1784037Y584726D01*
G01X1784036Y589731D02*
X1784035Y589738D01*
G01X1784037Y589726D02*
X1784036Y589731D01*
G01X1784038Y589724D02*
X1784037Y589726D01*
G01X1784036Y594731D02*
X1784035Y594738D01*
G01X1784037Y594726D02*
X1784036Y594731D01*
G01X1784038Y594724D02*
X1784037Y594726D01*
G01X1784036Y599731D02*
X1784035Y599738D01*
G01X1784037Y599726D02*
X1784036Y599731D01*
G01X1784038Y599724D02*
X1784037Y599726D01*
G01X1784036Y604731D02*
X1784035Y604738D01*
G01X1784037Y604726D02*
X1784036Y604731D01*
G01X1784038Y604724D02*
X1784037Y604726D01*
G01X1784036Y609731D02*
X1784035Y609738D01*
G01X1784037Y609726D02*
X1784036Y609731D01*
G01X1784038Y609724D02*
X1784037Y609726D01*
G01X1784036Y614731D02*
X1784035Y614738D01*
G01X1784037Y614726D02*
X1784036Y614731D01*
G01X1784038Y614724D02*
X1784037Y614726D01*
G01X1784036Y619731D02*
X1784035Y619738D01*
G01X1784037Y619726D02*
X1784036Y619731D01*
G01X1784038Y619724D02*
X1784037Y619726D01*
G01X1784036Y624731D02*
X1784035Y624738D01*
G01X1784037Y624726D02*
X1784036Y624731D01*
G01X1784038Y624724D02*
X1784037Y624726D01*
G01X1784036Y629731D02*
X1784035Y629738D01*
G01X1784037Y629726D02*
X1784036Y629731D01*
G01X1784038Y629724D02*
X1784037Y629726D01*
G01X1784036Y628378D02*
X1784035Y628369D01*
G01X1784037Y628384D02*
X1784036Y628378D01*
G01X1784038Y628386D02*
X1784037Y628384D01*
G01X1784036Y623378D02*
X1784035Y623369D01*
G01X1784037Y623384D02*
X1784036Y623378D01*
G01X1784038Y623386D02*
X1784037Y623384D01*
G01X1784036Y618378D02*
X1784035Y618369D01*
G01X1784037Y618384D02*
X1784036Y618378D01*
G01X1784038Y618386D02*
X1784037Y618384D01*
G01X1784036Y613378D02*
X1784035Y613369D01*
G01X1784037Y613384D02*
X1784036Y613378D01*
G01X1784038Y613386D02*
X1784037Y613384D01*
G01X1784036Y608378D02*
X1784035Y608369D01*
G01X1784037Y608384D02*
X1784036Y608378D01*
G01X1784038Y608386D02*
X1784037Y608384D01*
G01X1784036Y603378D02*
X1784035Y603369D01*
G01X1784037Y603384D02*
X1784036Y603378D01*
G01X1784038Y603386D02*
X1784037Y603384D01*
G01X1784036Y598378D02*
X1784035Y598369D01*
G01X1784037Y598384D02*
X1784036Y598378D01*
G01X1784038Y598386D02*
X1784037Y598384D01*
G01X1784036Y593378D02*
X1784035Y593369D01*
G01X1784037Y593384D02*
X1784036Y593378D01*
G01X1784038Y593386D02*
X1784037Y593384D01*
G01X1784036Y588378D02*
X1784035Y588369D01*
G01X1784037Y588384D02*
X1784036Y588378D01*
G01X1784038Y588386D02*
X1784037Y588384D01*
G01X1784036Y583378D02*
X1784035Y583369D01*
G01X1784037Y583384D02*
X1784036Y583378D01*
G01X1784038Y583386D02*
X1784037Y583384D01*
G01X1783051Y574771D02*
Y574780D01*
G01X1783052Y574765D02*
X1783051Y574771D01*
G01X1783053Y574764D02*
X1783052Y574765D01*
G01X1783051Y579771D02*
Y579780D01*
G01X1783052Y579765D02*
X1783051Y579771D01*
G01X1783053Y579764D02*
X1783052Y579765D01*
G01X1783051Y584771D02*
Y584780D01*
G01X1783052Y584765D02*
X1783051Y584771D01*
G01X1783053Y584764D02*
X1783052Y584765D01*
G01X1783051Y589771D02*
Y589780D01*
G01X1783052Y589765D02*
X1783051Y589771D01*
G01X1783053Y589764D02*
X1783052Y589765D01*
G01X1783051Y594771D02*
Y594780D01*
G01X1783052Y594765D02*
X1783051Y594771D01*
G01X1783053Y594764D02*
X1783052Y594765D01*
G01X1783051Y599771D02*
Y599780D01*
G01X1783052Y599765D02*
X1783051Y599771D01*
G01X1783053Y599764D02*
X1783052Y599765D01*
G01X1783051Y604771D02*
Y604780D01*
G01X1783052Y604765D02*
X1783051Y604771D01*
G01X1783053Y604764D02*
X1783052Y604765D01*
G01X1783051Y609771D02*
Y609780D01*
G01X1783052Y609765D02*
X1783051Y609771D01*
G01X1783053Y609764D02*
X1783052Y609765D01*
G01X1783051Y614771D02*
Y614780D01*
G01X1783052Y614765D02*
X1783051Y614771D01*
G01X1783053Y614764D02*
X1783052Y614765D01*
G01X1783051Y619771D02*
Y619780D01*
G01X1783052Y619765D02*
X1783051Y619771D01*
G01X1783053Y619764D02*
X1783052Y619765D01*
G01X1783051Y624771D02*
Y624780D01*
G01X1783052Y624765D02*
X1783051Y624771D01*
G01X1783053Y624764D02*
X1783052Y624765D01*
G01X1783051Y629771D02*
Y629780D01*
G01X1783052Y629765D02*
X1783051Y629771D01*
G01X1783053Y629764D02*
X1783052Y629765D01*
G01X1784028Y574907D02*
X1784035Y574881D01*
G01X1784018Y574934D02*
X1784028Y574907D01*
G01X1784006Y574961D02*
X1784018Y574934D01*
G01X1784028Y579907D02*
X1784035Y579881D01*
G01X1784018Y579934D02*
X1784028Y579907D01*
G01X1784006Y579961D02*
X1784018Y579934D01*
G01X1784028Y584907D02*
X1784035Y584881D01*
G01X1784018Y584934D02*
X1784028Y584907D01*
G01X1784006Y584961D02*
X1784018Y584934D01*
G01X1784028Y589907D02*
X1784035Y589881D01*
G01X1784018Y589934D02*
X1784028Y589907D01*
G01X1784006Y589961D02*
X1784018Y589934D01*
G01X1784028Y594907D02*
X1784035Y594881D01*
G01X1784018Y594934D02*
X1784028Y594907D01*
G01X1784006Y594961D02*
X1784018Y594934D01*
G01X1784028Y599907D02*
X1784035Y599881D01*
G01X1784018Y599934D02*
X1784028Y599907D01*
G01X1784006Y599961D02*
X1784018Y599934D01*
G01X1784028Y604907D02*
X1784035Y604881D01*
G01X1784018Y604934D02*
X1784028Y604907D01*
G01X1784006Y604961D02*
X1784018Y604934D01*
G01X1784028Y609907D02*
X1784035Y609881D01*
G01X1784018Y609934D02*
X1784028Y609907D01*
G01X1784006Y609961D02*
X1784018Y609934D01*
G01X1784028Y614907D02*
X1784035Y614881D01*
G01X1784018Y614934D02*
X1784028Y614907D01*
G01X1784006Y614961D02*
X1784018Y614934D01*
G01X1784028Y619907D02*
X1784035Y619881D01*
G01X1784018Y619934D02*
X1784028Y619907D01*
G01X1784006Y619961D02*
X1784018Y619934D01*
G01X1784028Y624907D02*
X1784035Y624881D01*
G01X1784018Y624934D02*
X1784028Y624907D01*
G01X1784006Y624961D02*
X1784018Y624934D01*
G01X1784028Y629907D02*
X1784035Y629881D01*
G01X1784018Y629934D02*
X1784028Y629907D01*
G01X1784006Y629961D02*
X1784018Y629934D01*
G01Y574759D02*
X1783999Y574764D01*
G01X1784033Y574744D02*
X1784018Y574759D01*
G01X1784038Y574724D02*
X1784033Y574744D01*
G01X1784018Y579759D02*
X1783999Y579764D01*
G01X1784033Y579744D02*
X1784018Y579759D01*
G01X1784038Y579724D02*
X1784033Y579744D01*
G01X1784018Y584759D02*
X1783999Y584764D01*
G01X1784033Y584744D02*
X1784018Y584759D01*
G01X1784038Y584724D02*
X1784033Y584744D01*
G01X1784018Y589759D02*
X1783999Y589764D01*
G01X1784033Y589744D02*
X1784018Y589759D01*
G01X1784038Y589724D02*
X1784033Y589744D01*
G01X1784018Y594759D02*
X1783999Y594764D01*
G01X1784033Y594744D02*
X1784018Y594759D01*
G01X1784038Y594724D02*
X1784033Y594744D01*
G01X1784018Y599759D02*
X1783999Y599764D01*
G01X1784033Y599744D02*
X1784018Y599759D01*
G01X1784038Y599724D02*
X1784033Y599744D01*
G01X1784018Y604759D02*
X1783999Y604764D01*
G01X1784033Y604744D02*
X1784018Y604759D01*
G01X1784038Y604724D02*
X1784033Y604744D01*
G01X1784018Y609759D02*
X1783999Y609764D01*
G01X1784033Y609744D02*
X1784018Y609759D01*
G01X1784038Y609724D02*
X1784033Y609744D01*
G01X1784002Y574862D02*
X1784006Y574961D01*
G01X1783997Y574790D02*
X1784002Y574862D01*
G01X1783999Y574764D02*
X1783997Y574790D01*
G01X1784002Y579862D02*
X1784006Y579961D01*
G01X1783997Y579790D02*
X1784002Y579862D01*
G01X1783999Y579764D02*
X1783997Y579790D01*
G01X1784002Y584862D02*
X1784006Y584961D01*
G01X1783997Y584790D02*
X1784002Y584862D01*
G01X1783999Y584764D02*
X1783997Y584790D01*
G01X1784002Y589862D02*
X1784006Y589961D01*
G01X1783997Y589790D02*
X1784002Y589862D01*
G01X1783999Y589764D02*
X1783997Y589790D01*
G01X1784002Y594862D02*
X1784006Y594961D01*
G01X1783997Y594790D02*
X1784002Y594862D01*
G01X1783999Y594764D02*
X1783997Y594790D01*
G01X1784002Y599862D02*
X1784006Y599961D01*
G01X1783997Y599790D02*
X1784002Y599862D01*
G01X1783999Y599764D02*
X1783997Y599790D01*
G01X1784002Y604862D02*
X1784006Y604961D01*
G01X1783997Y604790D02*
X1784002Y604862D01*
G01X1783999Y604764D02*
X1783997Y604790D01*
G01X1784002Y609862D02*
X1784006Y609961D01*
G01X1783997Y609790D02*
X1784002Y609862D01*
G01X1783999Y609764D02*
X1783997Y609790D01*
G01X1784002Y614862D02*
X1784006Y614961D01*
G01X1783997Y614790D02*
X1784002Y614862D01*
G01X1783999Y614764D02*
X1783997Y614790D01*
G01X1784002Y619862D02*
X1784006Y619961D01*
G01X1783997Y619790D02*
X1784002Y619862D01*
G01X1783999Y619764D02*
X1783997Y619790D01*
G01X1784002Y624862D02*
X1784006Y624961D01*
G01X1783997Y624790D02*
X1784002Y624862D01*
G01X1783999Y624764D02*
X1783997Y624790D01*
G01X1784002Y629862D02*
X1784006Y629961D01*
G01X1783997Y629790D02*
X1784002Y629862D01*
G01X1783999Y629764D02*
X1783997Y629790D01*
G01X1783052Y628384D02*
X1783053Y628386D01*
G01X1783051Y628378D02*
X1783052Y628384D01*
G01X1783051Y628370D02*
Y628378D01*
G01X1783052Y623384D02*
X1783053Y623386D01*
G01X1783051Y623378D02*
X1783052Y623384D01*
G01X1783051Y623370D02*
Y623378D01*
G01X1783052Y618384D02*
X1783053Y618386D01*
G01X1783051Y618378D02*
X1783052Y618384D01*
G01X1783051Y618370D02*
Y618378D01*
G01X1783052Y613384D02*
X1783053Y613386D01*
G01X1783051Y613378D02*
X1783052Y613384D01*
G01X1783051Y613370D02*
Y613378D01*
G01X1783052Y608384D02*
X1783053Y608386D01*
G01X1783051Y608378D02*
X1783052Y608384D01*
G01X1783051Y608370D02*
Y608378D01*
G01X1783052Y603384D02*
X1783053Y603386D01*
G01X1783051Y603378D02*
X1783052Y603384D01*
G01X1783051Y603370D02*
Y603378D01*
G01X1783052Y598384D02*
X1783053Y598386D01*
G01X1783051Y598378D02*
X1783052Y598384D01*
G01X1783051Y598370D02*
Y598378D01*
G01X1783052Y593384D02*
X1783053Y593386D01*
G01X1783051Y593378D02*
X1783052Y593384D01*
G01X1783051Y593370D02*
Y593378D01*
G01X1783052Y588384D02*
X1783053Y588386D01*
G01X1783051Y588378D02*
X1783052Y588384D01*
G01X1783051Y588370D02*
Y588378D01*
G01X1783052Y583384D02*
X1783053Y583386D01*
G01X1783051Y583378D02*
X1783052Y583384D01*
G01X1783051Y583370D02*
Y583378D01*
G01X1783052Y578384D02*
X1783053Y578386D01*
G01X1783051Y578378D02*
X1783052Y578384D01*
G01X1783051Y578370D02*
Y578378D01*
G01X1783052Y573384D02*
X1783053Y573386D01*
G01X1783051Y573378D02*
X1783052Y573384D01*
G01X1783051Y573370D02*
Y573378D01*
G01X1784036Y578378D02*
X1784035Y578369D01*
G01X1784037Y578384D02*
X1784036Y578378D01*
G01X1784038Y578386D02*
X1784037Y578384D01*
G01X1784036Y573378D02*
X1784035Y573369D01*
G01X1784037Y573384D02*
X1784036Y573378D01*
G01X1784038Y573386D02*
X1784037Y573384D01*
G01X1784018Y614759D02*
X1783999Y614764D01*
G01X1784033Y614744D02*
X1784018Y614759D01*
G01X1784038Y614724D02*
X1784033Y614744D01*
G01X1784018Y619759D02*
X1783999Y619764D01*
G01X1784033Y619744D02*
X1784018Y619759D01*
G01X1784038Y619724D02*
X1784033Y619744D01*
G01X1784018Y624759D02*
X1783999Y624764D01*
G01X1784033Y624744D02*
X1784018Y624759D01*
G01X1784038Y624724D02*
X1784033Y624744D01*
G01X1784018Y629759D02*
X1783999Y629764D01*
G01X1784033Y629744D02*
X1784018Y629759D01*
G01X1784038Y629724D02*
X1784033Y629744D01*
G01X1782480Y655256D02*
G03X1781890Y655846I-590J0D01*
G01X1775197D02*
G03X1774606Y655256I0J-591D01*
G01X1777362Y654075D02*
G03Y652106I0J-985D01*
G01X1779724D02*
G03Y654075I0J984D01*
G01X1775984Y646161D02*
G03X1774803Y644980I0J-1181D01*
G01X1782283D02*
G03X1781102Y646161I-1181J0D01*
G01X1780433Y640886D02*
G03I-1890J0D01*
G01X1789370Y654665D02*
G03X1787402Y656634I-1969J0D01*
G01X1769685D02*
G03X1767717Y654665I0J-1968D01*
G01X1780906Y640886D02*
G03I-2363J0D01*
G01X1782035Y645706D02*
X1779724Y641476D01*
G01X1784035Y574738D02*
X1784036Y574746D01*
G01X1784035Y579738D02*
X1784036Y579746D01*
G01X1784035Y584738D02*
X1784036Y584746D01*
G01X1784035Y589738D02*
X1784036Y589746D01*
G01X1784035Y594738D02*
X1784036Y594746D01*
G01X1784035Y599738D02*
X1784036Y599746D01*
G01X1784035Y604738D02*
X1784036Y604746D01*
G01X1784035Y609738D02*
X1784036Y609746D01*
G01X1784035Y614738D02*
X1784036Y614746D01*
G01X1784035Y619738D02*
X1784036Y619746D01*
G01X1784035Y624738D02*
X1784036Y624746D01*
G01X1784035Y629738D02*
X1784036Y629746D01*
G01X1789370Y638917D02*
Y654665D01*
G01X1788386Y628386D02*
Y629764D01*
G01Y623386D02*
Y624764D01*
G01Y618386D02*
Y619764D01*
G01Y613386D02*
Y614764D01*
G01Y608386D02*
Y609764D01*
G01Y603386D02*
Y604764D01*
G01Y598386D02*
Y599764D01*
G01Y593386D02*
Y594764D01*
G01Y588386D02*
Y589764D01*
G01Y583386D02*
Y584764D01*
G01Y578386D02*
Y579764D01*
G01Y573386D02*
Y574764D01*
G01X1785217D02*
Y573386D01*
G01Y579764D02*
Y578386D01*
G01Y584764D02*
Y583386D01*
G01Y589764D02*
Y588386D01*
G01Y594764D02*
Y593386D01*
G01Y599764D02*
Y598386D01*
G01Y604764D02*
Y603386D01*
G01Y609764D02*
Y608386D01*
G01Y614764D02*
Y613386D01*
G01Y619764D02*
Y618386D01*
G01Y624764D02*
Y623386D01*
G01Y629764D02*
Y628386D01*
G01X1784035Y627894D02*
Y630256D01*
G01Y622894D02*
Y625256D01*
G01Y617894D02*
Y620256D01*
G01Y612894D02*
Y615256D01*
G01Y607894D02*
Y610256D01*
G01Y602894D02*
Y605256D01*
G01Y597894D02*
Y600256D01*
G01Y592894D02*
Y595256D01*
G01Y587894D02*
Y590256D01*
G01Y582894D02*
Y585256D01*
G01Y577894D02*
Y580256D01*
G01Y572894D02*
Y575256D01*
G01X1783051D02*
Y572894D01*
G01Y580256D02*
Y577894D01*
G01Y585256D02*
Y582894D01*
G01Y590256D02*
Y587894D01*
G01Y595256D02*
Y592894D01*
G01Y600256D02*
Y597894D01*
G01Y605256D02*
Y602894D01*
G01Y610256D02*
Y607894D01*
G01Y615256D02*
Y612894D01*
G01Y620256D02*
Y617894D01*
G01Y625256D02*
Y622894D01*
G01Y630256D02*
Y627894D01*
G01X1782480Y649154D02*
Y655256D01*
G01X1782283Y644980D02*
Y636437D01*
G01X1779724Y641476D02*
Y639783D01*
G01X1777362D02*
Y641476D01*
G01X1774803Y636437D02*
Y644980D01*
G01X1774606Y649154D02*
Y655256D01*
G01X1767717Y654665D02*
Y638917D01*
G01X1789370D02*
X1786024Y635571D01*
G01X1776059Y637815D02*
X1777362Y639783D01*
G01Y641476D02*
X1775052Y645706D01*
G01X1779724Y639783D02*
X1781028Y637815D01*
G01X1779528Y632894D02*
X1780709Y634075D01*
G01X1772835D02*
X1774016Y632894D01*
G01X1767717Y638917D02*
X1771063Y635571D01*
G01X1787402Y656634D02*
X1769685D01*
G01X1781890Y655846D02*
X1775197D01*
G01X1779724Y654075D02*
X1777362D01*
G01Y652106D02*
X1779724D01*
G01X1782480Y650728D02*
X1774606D01*
G01Y649154D02*
X1782480D01*
G01X1789370Y646201D02*
X1767717D01*
G01X1775984Y646161D02*
X1781102D01*
G01X1777362Y641476D02*
X1779724D01*
G01X1777362Y639783D02*
X1779724D01*
G01X1771063Y637815D02*
X1785433D01*
G01X1771063Y636437D02*
X1774803D01*
G01X1785433D02*
X1782283D01*
G01X1771063Y635571D02*
X1786024D01*
G01X1772835Y634075D02*
X1780709D01*
G01X1774016Y632894D02*
X1779528D01*
G01X1784035Y630256D02*
X1783051D01*
G01X1783053Y629764D02*
X1788386D01*
G01Y629724D02*
X1784038D01*
G01X1788386Y628386D02*
X1783053D01*
G01X1783051Y627894D02*
X1784035D01*
G01Y625256D02*
X1783051D01*
G01X1783053Y624764D02*
X1788386D01*
G01Y624724D02*
X1784038D01*
G01X1788386Y623386D02*
X1783053D01*
G01X1783051Y622894D02*
X1784035D01*
G01Y620256D02*
X1783051D01*
G01X1783053Y619764D02*
X1788386D01*
G01Y619724D02*
X1784038D01*
G01X1788386Y618386D02*
X1783053D01*
G01X1783051Y617894D02*
X1784035D01*
G01Y615256D02*
X1783051D01*
G01X1783053Y614764D02*
X1788386D01*
G01Y614724D02*
X1784038D01*
G01X1788386Y613386D02*
X1783053D01*
G01X1783051Y612894D02*
X1784035D01*
G01Y610256D02*
X1783051D01*
G01Y629959D02*
X1784006Y629961D01*
G01X1784035Y628190D02*
X1783051Y628189D01*
G01Y624959D02*
X1784006Y624961D01*
G01X1784035Y623190D02*
X1783051Y623189D01*
G01Y619959D02*
X1784006Y619961D01*
G01X1784035Y618190D02*
X1783051Y618189D01*
G01Y614959D02*
X1784006Y614961D01*
G01X1784035Y613190D02*
X1783051Y613189D01*
G01X1783053Y609764D02*
X1788386D01*
G01Y609724D02*
X1784038D01*
G01X1788386Y608386D02*
X1783053D01*
G01X1783051Y607894D02*
X1784035D01*
G01Y605256D02*
X1783051D01*
G01X1783053Y604764D02*
X1788386D01*
G01Y604724D02*
X1784038D01*
G01X1788386Y603386D02*
X1783053D01*
G01X1783051Y602894D02*
X1784035D01*
G01Y600256D02*
X1783051D01*
G01X1783053Y599764D02*
X1788386D01*
G01Y599724D02*
X1784038D01*
G01X1788386Y598386D02*
X1783053D01*
G01X1783051Y597894D02*
X1784035D01*
G01Y595256D02*
X1783051D01*
G01X1783053Y594764D02*
X1788386D01*
G01Y594724D02*
X1784038D01*
G01X1788386Y593386D02*
X1783053D01*
G01X1783051Y592894D02*
X1784035D01*
G01Y590256D02*
X1783051D01*
G01X1783053Y589764D02*
X1788386D01*
G01Y589724D02*
X1784038D01*
G01X1788386Y588386D02*
X1783053D01*
G01X1783051Y587894D02*
X1784035D01*
G01Y585256D02*
X1783051D01*
G01X1783053Y584764D02*
X1788386D01*
G01Y584724D02*
X1784038D01*
G01X1788386Y583386D02*
X1783053D01*
G01X1783051Y582894D02*
X1784035D01*
G01Y580256D02*
X1783051D01*
G01X1783053Y579764D02*
X1788386D01*
G01Y579724D02*
X1784038D01*
G01X1788386Y578386D02*
X1783053D01*
G01X1783051Y577894D02*
X1784035D01*
G01Y575256D02*
X1783051D01*
G01X1783053Y574764D02*
X1788386D01*
G01Y574724D02*
X1784038D01*
G01X1788386Y573386D02*
X1783053D01*
G01X1783051Y572894D02*
X1784035D01*
G01X1783051Y609959D02*
X1784006Y609961D01*
G01X1784035Y608190D02*
X1783051Y608189D01*
G01Y604959D02*
X1784006Y604961D01*
G01X1784035Y603190D02*
X1783051Y603189D01*
G01Y599959D02*
X1784006Y599961D01*
G01X1784035Y598190D02*
X1783051Y598189D01*
G01Y594959D02*
X1784006Y594961D01*
G01X1784035Y593190D02*
X1783051Y593189D01*
G01Y589959D02*
X1784006Y589961D01*
G01X1784035Y588190D02*
X1783051Y588189D01*
G01Y584959D02*
X1784006Y584961D01*
G01X1784035Y583190D02*
X1783051Y583189D01*
G01Y579959D02*
X1784006Y579961D01*
G01X1784035Y578190D02*
X1783051Y578189D01*
G01Y574959D02*
X1784006Y574961D01*
G01X1784035Y573190D02*
X1783051Y573189D01*
G01X1781028Y717468D02*
G03X1814838I16905J-13531D01*
G01X1807914Y730599D02*
G03X1814838Y717468I37663J11469D01*
G01X1807914Y730599D02*
G03X1787953I-9980J-3040D01*
G01X1781028Y717468D02*
G03X1787954Y730599I-30736J24604D01*
G01X1807913D02*
G03X1814839Y717468I37661J11473D01*
G01X1738583Y713386D02*
G03X1739764I590J0D01*
G01Y707087D02*
G03X1738583I-590J0D01*
G01X1736614D02*
G03X1735433I-591J0D01*
G01Y713386D02*
G03X1736614I590J0D01*
G01X1738583D02*
G03X1739764I590J0D01*
G01Y707087D02*
G03X1738583I-590J0D01*
G01X1736614D02*
G03X1735433I-591J0D01*
G01Y713386D02*
G03X1736614I590J0D01*
G01X1807913Y730599D02*
G03X1787953I-9980J-3040D01*
G01X1781028Y717468D02*
G03X1814839I16906J-13531D01*
G01X1781028D02*
G03X1787953Y730599I-30737J24602D01*
G01X1740551Y707087D02*
Y713386D01*
G01Y707087D02*
Y713386D01*
G01X1734646Y707087D02*
Y713386D01*
G01D02*
Y707087D01*
G01X1738583Y713386D02*
X1736614D01*
G01X1735433D02*
X1734646D01*
G01X1738583D02*
X1736614D01*
G01X1735433D02*
X1734646D01*
G01X1740551D02*
X1739764D01*
G01X1740551D02*
X1739764D01*
G01X1740551Y712402D02*
X1734646D01*
G01Y712205D02*
X1740551D01*
G01X1734646Y708268D02*
X1740551D01*
G01Y708071D02*
X1734646D01*
G01X1739764Y707087D02*
X1740551D01*
G01X1739764D02*
X1740551D01*
G01X1736614D02*
X1738583D01*
G01X1734646D02*
X1735433D01*
G01X1736614D02*
X1738583D01*
G01X1734646D02*
X1735433D01*
G01X1779646Y945020D02*
G03I-1103J0D01*
G01X1781102Y939744D02*
G03X1782283Y940925I0J1181D01*
G01X1774803D02*
G03X1775984Y939744I1181J0D01*
G01X1780118Y945020D02*
G03I-1575J0D01*
G01X1774606Y930650D02*
G03X1775197Y930059I591J0D01*
G01X1781890D02*
G03X1782480Y930650I0J590D01*
G01X1779724Y931831D02*
G03Y933799I0J984D01*
G01X1777362D02*
G03Y931831I0J-984D01*
G01X1767717Y931240D02*
G03X1769685Y929272I1968J0D01*
G01X1787402D02*
G03X1789370Y931240I0J1968D01*
G01X1779724Y944429D02*
X1782035Y940200D01*
G01X1777362Y946122D02*
X1776059Y948091D01*
G01X1789370Y931240D02*
Y946988D01*
G01X1786024Y1088327D02*
Y950335D01*
G01X1785433Y1090571D02*
Y948091D01*
G01X1782480Y936752D02*
Y930650D01*
G01X1782283Y949469D02*
Y940925D01*
G01X1780709Y988287D02*
Y951831D01*
G01X1779724Y946122D02*
Y944429D01*
G01X1777362D02*
Y946122D01*
G01X1774803Y940925D02*
Y949469D01*
G01X1774606Y936752D02*
Y930650D01*
G01X1772835Y951831D02*
Y1086831D01*
G01X1771063Y987126D02*
Y948091D01*
G01X1767717Y946988D02*
Y931240D01*
G01X1786024Y950335D02*
X1789370Y946988D01*
G01X1779528Y953012D02*
X1780709Y951831D01*
G01X1775052Y940200D02*
X1777362Y944429D01*
G01X1781028Y948091D02*
X1779724Y946122D01*
G01X1774016Y953012D02*
X1772835Y951831D01*
G01X1771063Y950335D02*
X1767717Y946988D01*
G01X1780709Y951831D02*
X1772835D01*
G01X1786024Y950335D02*
X1771063D01*
G01X1782283Y949469D02*
X1785433D01*
G01X1774803D02*
X1771063D01*
G01Y948091D02*
X1785433D01*
G01X1779724Y946122D02*
X1777362D01*
G01X1779724Y944429D02*
X1777362D01*
G01X1781102Y939744D02*
X1775984D01*
G01X1789370Y939705D02*
X1767717D01*
G01X1782480Y936752D02*
X1774606D01*
G01Y935177D02*
X1782480D01*
G01X1779724Y933799D02*
X1777362D01*
G01Y931831D02*
X1779724D01*
G01X1781890Y930059D02*
X1775197D01*
G01X1787402Y929272D02*
X1769685D01*
G01X1769629Y990453D02*
X1769624Y990433D01*
G01X1769643Y990467D02*
X1769629Y990453D01*
G01X1769663Y990472D02*
X1769643Y990467D01*
G01X1770604Y989311D02*
X1770609Y989331D01*
G01X1770589Y989296D02*
X1770604Y989311D01*
G01X1770569Y989291D02*
X1770589Y989296D01*
G01X1769629Y993602D02*
X1769624Y993583D01*
G01X1769643Y993617D02*
X1769629Y993602D01*
G01X1769663Y993622D02*
X1769643Y993617D01*
G01X1769629Y996752D02*
X1769624Y996732D01*
G01X1769643Y996766D02*
X1769629Y996752D01*
G01X1769663Y996772D02*
X1769643Y996766D01*
G01X1769629Y999902D02*
X1769624Y999882D01*
G01X1769643Y999916D02*
X1769629Y999902D01*
G01X1769663Y999921D02*
X1769643Y999916D01*
G01X1769629Y1003051D02*
X1769624Y1003031D01*
G01X1769643Y1003065D02*
X1769629Y1003051D01*
G01X1769663Y1003071D02*
X1769643Y1003065D01*
G01X1769629Y1006201D02*
X1769624Y1006181D01*
G01X1769643Y1006215D02*
X1769629Y1006201D01*
G01X1769663Y1006220D02*
X1769643Y1006215D01*
G01X1769629Y1009350D02*
X1769624Y1009331D01*
G01X1769643Y1009365D02*
X1769629Y1009350D01*
G01X1769663Y1009370D02*
X1769643Y1009365D01*
G01X1770604Y992461D02*
X1770609Y992480D01*
G01X1770589Y992446D02*
X1770604Y992461D01*
G01X1770569Y992441D02*
X1770589Y992446D01*
G01X1770604Y995610D02*
X1770609Y995630D01*
G01X1770589Y995596D02*
X1770604Y995610D01*
G01X1770569Y995591D02*
X1770589Y995596D01*
G01X1770604Y998760D02*
X1770609Y998780D01*
G01X1770589Y998745D02*
X1770604Y998760D01*
G01X1770569Y998740D02*
X1770589Y998745D01*
G01X1770604Y1001909D02*
X1770609Y1001929D01*
G01X1770589Y1001895D02*
X1770604Y1001909D01*
G01X1770569Y1001890D02*
X1770589Y1001895D01*
G01X1770604Y1005059D02*
X1770609Y1005079D01*
G01X1770589Y1005044D02*
X1770604Y1005059D01*
G01X1770569Y1005039D02*
X1770589Y1005044D01*
G01X1770604Y1008209D02*
X1770609Y1008228D01*
G01X1770589Y1008194D02*
X1770604Y1008209D01*
G01X1770569Y1008189D02*
X1770589Y1008194D01*
G01X1770581Y1008191D02*
X1770569Y1008189D01*
G01X1770592Y1008196D02*
X1770581Y1008191D01*
G01Y1005041D02*
X1770569Y1005039D01*
G01X1770592Y1005046D02*
X1770581Y1005041D01*
G01Y1001892D02*
X1770569Y1001890D01*
G01X1770592Y1001896D02*
X1770581Y1001892D01*
G01Y998742D02*
X1770569Y998740D01*
G01X1770592Y998747D02*
X1770581Y998742D01*
G01Y995593D02*
X1770569Y995591D01*
G01X1770592Y995597D02*
X1770581Y995593D01*
G01Y992443D02*
X1770569Y992441D01*
G01X1770592Y992448D02*
X1770581Y992443D01*
G01Y989293D02*
X1770569Y989291D01*
G01X1770592Y989298D02*
X1770581Y989293D01*
G01X1770609Y1005058D02*
X1770610Y1005065D01*
G01X1770607Y1005051D02*
X1770609Y1005058D01*
G01X1770604Y1005044D02*
X1770607Y1005051D01*
G01X1770599Y1005039D02*
X1770604Y1005044D01*
G01X1770593Y1005034D02*
X1770599Y1005039D01*
G01X1770586Y1005031D02*
X1770593Y1005034D01*
G01X1770579Y1005029D02*
X1770586Y1005031D01*
G01X1770571Y1005028D02*
X1770579Y1005029D01*
G01X1769627Y1009350D02*
X1769626Y1009344D01*
G01X1769628Y1009357D02*
X1769627Y1009350D01*
G01X1769631Y1009363D02*
X1769628Y1009357D01*
G01X1769635Y1009368D02*
X1769631Y1009363D01*
G01X1769640Y1009372D02*
X1769635Y1009368D01*
G01X1769645Y1009376D02*
X1769640Y1009372D01*
G01X1769627Y1006201D02*
X1769626Y1006194D01*
G01X1769628Y1006207D02*
X1769627Y1006201D01*
G01X1769631Y1006213D02*
X1769628Y1006207D01*
G01X1769635Y1006218D02*
X1769631Y1006213D01*
G01X1769640Y1006223D02*
X1769635Y1006218D01*
G01X1769645Y1006226D02*
X1769640Y1006223D01*
G01X1769627Y1003051D02*
X1769626Y1003045D01*
G01X1769628Y1003057D02*
X1769627Y1003051D01*
G01X1769631Y1003063D02*
X1769628Y1003057D01*
G01X1769635Y1003069D02*
X1769631Y1003063D01*
G01X1769640Y1003073D02*
X1769635Y1003069D01*
G01X1769645Y1003077D02*
X1769640Y1003073D01*
G01X1769627Y999902D02*
X1769626Y999895D01*
G01X1769628Y999908D02*
X1769627Y999902D01*
G01X1769631Y999914D02*
X1769628Y999908D01*
G01X1769635Y999919D02*
X1769631Y999914D01*
G01X1769640Y999924D02*
X1769635Y999919D01*
G01X1769645Y999927D02*
X1769640Y999924D01*
G01X1770588Y989283D02*
X1770591Y989285D01*
G01X1770585Y989282D02*
X1770588Y989283D01*
G01X1770581Y989281D02*
X1770585Y989282D01*
G01X1770578Y989281D02*
X1770581D01*
G01X1770574Y989280D02*
X1770578Y989281D01*
G01X1770571Y989280D02*
X1770574D01*
G01X1769648Y990480D02*
X1769645Y990478D01*
G01X1769652Y990481D02*
X1769648Y990480D01*
G01X1769655Y990482D02*
X1769652Y990481D01*
G01X1769658Y990483D02*
X1769655Y990482D01*
G01X1769662Y990483D02*
X1769658D01*
G01X1769665D02*
X1769662D01*
G01X1770588Y992433D02*
X1770591Y992435D01*
G01X1770585Y992432D02*
X1770588Y992433D01*
G01X1770581Y992431D02*
X1770585Y992432D01*
G01X1770578Y992430D02*
X1770581Y992431D01*
G01X1770574Y992430D02*
X1770578D01*
G01X1770571D02*
X1770574D01*
G01X1769648Y993630D02*
X1769645Y993628D01*
G01X1769652Y993631D02*
X1769648Y993630D01*
G01X1769655Y993632D02*
X1769652Y993631D01*
G01X1769658Y993633D02*
X1769655Y993632D01*
G01X1769662Y993633D02*
X1769658D01*
G01X1769665D02*
X1769662D01*
G01X1770588Y995583D02*
X1770591Y995585D01*
G01X1770585Y995581D02*
X1770588Y995583D01*
G01X1770581Y995581D02*
X1770585D01*
G01X1770578Y995580D02*
X1770581Y995581D01*
G01X1770574Y995580D02*
X1770578D01*
G01X1770571Y995579D02*
X1770574Y995580D01*
G01X1769648Y996779D02*
X1769645Y996778D01*
G01X1769652Y996780D02*
X1769648Y996779D01*
G01X1769655Y996781D02*
X1769652Y996780D01*
G01X1769658Y996782D02*
X1769655Y996781D01*
G01X1769662Y996783D02*
X1769658Y996782D01*
G01X1769665Y996783D02*
X1769662D01*
G01X1770588Y998732D02*
X1770591Y998734D01*
G01X1770585Y998731D02*
X1770588Y998732D01*
G01X1770581Y998730D02*
X1770585Y998731D01*
G01X1770578Y998730D02*
X1770581D01*
G01X1770574Y998729D02*
X1770578Y998730D01*
G01X1770571Y998729D02*
X1770574D01*
G01X1769648Y999929D02*
X1769645Y999927D01*
G01X1769652Y999930D02*
X1769648Y999929D01*
G01X1769655Y999931D02*
X1769652Y999930D01*
G01X1769658Y999932D02*
X1769655Y999931D01*
G01X1769662Y999932D02*
X1769658D01*
G01X1769665D02*
X1769662D01*
G01X1770588Y1001882D02*
X1770591Y1001884D01*
G01X1770585Y1001881D02*
X1770588Y1001882D01*
G01X1770581Y1001880D02*
X1770585Y1001881D01*
G01X1770578Y1001879D02*
X1770581Y1001880D01*
G01X1770574Y1001879D02*
X1770578D01*
G01X1770571Y1001878D02*
X1770574Y1001879D01*
G01X1769648Y1003078D02*
X1769645Y1003077D01*
G01X1769652Y1003080D02*
X1769648Y1003078D01*
G01X1769655Y1003081D02*
X1769652Y1003080D01*
G01X1769658Y1003081D02*
X1769655D01*
G01X1769662Y1003082D02*
X1769658Y1003081D01*
G01X1769665Y1003082D02*
X1769662D01*
G01X1769648Y1006228D02*
X1769645Y1006226D01*
G01X1769652Y1006229D02*
X1769648Y1006228D01*
G01X1769655Y1006230D02*
X1769652Y1006229D01*
G01X1769658Y1006231D02*
X1769655Y1006230D01*
G01X1769662Y1006231D02*
X1769658D01*
G01X1769665D02*
X1769662D01*
G01X1770588Y1008181D02*
X1770591Y1008183D01*
G01X1770585Y1008180D02*
X1770588Y1008181D01*
G01X1770581Y1008179D02*
X1770585Y1008180D01*
G01X1770578Y1008178D02*
X1770581Y1008179D01*
G01X1770574Y1008178D02*
X1770578D01*
G01X1770571D02*
X1770574D01*
G01X1769648Y1009378D02*
X1769645Y1009376D01*
G01X1769652Y1009379D02*
X1769648Y1009378D01*
G01X1769655Y1009380D02*
X1769652Y1009379D01*
G01X1769658Y1009381D02*
X1769655Y1009380D01*
G01X1769662Y1009381D02*
X1769658D01*
G01X1769665D02*
X1769662D01*
G01X1770608Y1008202D02*
X1770610Y1008215D01*
G01X1770601Y1008191D02*
X1770608Y1008202D01*
G01X1770591Y1008183D02*
X1770601Y1008191D01*
G01X1770608Y1001903D02*
X1770610Y1001915D01*
G01X1770601Y1001892D02*
X1770608Y1001903D01*
G01X1770591Y1001884D02*
X1770601Y1001892D01*
G01X1770608Y998754D02*
X1770610Y998766D01*
G01X1770601Y998742D02*
X1770608Y998754D01*
G01X1770591Y998734D02*
X1770601Y998742D01*
G01X1770608Y995604D02*
X1770610Y995616D01*
G01X1770601Y995593D02*
X1770608Y995604D01*
G01X1770591Y995585D02*
X1770601Y995593D01*
G01X1770608Y992454D02*
X1770610Y992467D01*
G01X1770601Y992443D02*
X1770608Y992454D01*
G01X1770591Y992435D02*
X1770601Y992443D01*
G01X1770608Y989305D02*
X1770610Y989317D01*
G01X1770601Y989293D02*
X1770608Y989305D01*
G01X1770591Y989285D02*
X1770601Y989293D01*
G01X1769665Y1009375D02*
Y1009381D01*
G01Y1009371D02*
Y1009375D01*
G01X1769663Y1009370D02*
X1769665Y1009371D01*
G01Y1006225D02*
Y1006231D01*
G01Y1006222D02*
Y1006225D01*
G01X1769663Y1006220D02*
X1769665Y1006222D01*
G01Y1003076D02*
Y1003082D01*
G01Y1003072D02*
Y1003076D01*
G01X1769663Y1003071D02*
X1769665Y1003072D01*
G01Y999926D02*
Y999932D01*
G01Y999922D02*
Y999926D01*
G01X1769663Y999921D02*
X1769665Y999922D01*
G01Y996776D02*
Y996783D01*
G01Y996773D02*
Y996776D01*
G01X1769663Y996772D02*
X1769665Y996773D01*
G01Y993627D02*
Y993633D01*
G01Y993623D02*
Y993627D01*
G01X1769663Y993622D02*
X1769665Y993623D01*
G01Y990477D02*
Y990483D01*
G01Y990474D02*
Y990477D01*
G01X1769663Y990472D02*
X1769665Y990474D01*
G01X1769627Y996752D02*
X1769626Y996746D01*
G01X1769628Y996758D02*
X1769627Y996752D01*
G01X1769631Y996764D02*
X1769628Y996758D01*
G01X1769635Y996769D02*
X1769631Y996764D01*
G01X1769640Y996774D02*
X1769635Y996769D01*
G01X1769645Y996778D02*
X1769640Y996774D01*
G01X1769627Y993602D02*
X1769626Y993596D01*
G01X1769628Y993609D02*
X1769627Y993602D01*
G01X1769631Y993615D02*
X1769628Y993609D01*
G01X1769635Y993620D02*
X1769631Y993615D01*
G01X1769640Y993624D02*
X1769635Y993620D01*
G01X1769645Y993628D02*
X1769640Y993624D01*
G01X1769627Y990453D02*
X1769626Y990446D01*
G01X1769628Y990459D02*
X1769627Y990453D01*
G01X1769631Y990465D02*
X1769628Y990459D01*
G01X1769635Y990470D02*
X1769631Y990465D01*
G01X1769640Y990475D02*
X1769635Y990470D01*
G01X1769645Y990478D02*
X1769640Y990475D01*
G01X1770601Y990471D02*
X1770605Y990465D01*
G01X1770596Y990475D02*
X1770601Y990471D01*
G01X1770590Y990479D02*
X1770596Y990475D01*
G01X1770584Y990481D02*
X1770590Y990479D01*
G01X1770578Y990483D02*
X1770584Y990481D01*
G01X1770571Y990483D02*
X1770578D01*
G01X1770601Y993620D02*
X1770605Y993615D01*
G01X1770596Y993625D02*
X1770601Y993620D01*
G01X1770590Y993628D02*
X1770596Y993625D01*
G01X1770584Y993631D02*
X1770590Y993628D01*
G01X1770578Y993633D02*
X1770584Y993631D01*
G01X1770571Y993633D02*
X1770578D01*
G01X1770601Y996770D02*
X1770605Y996765D01*
G01X1770596Y996774D02*
X1770601Y996770D01*
G01X1770590Y996778D02*
X1770596Y996774D01*
G01X1770584Y996781D02*
X1770590Y996778D01*
G01X1770578Y996782D02*
X1770584Y996781D01*
G01X1770571Y996783D02*
X1770578Y996782D01*
G01X1770601Y999920D02*
X1770605Y999914D01*
G01X1770596Y999924D02*
X1770601Y999920D01*
G01X1770590Y999928D02*
X1770596Y999924D01*
G01X1770584Y999930D02*
X1770590Y999928D01*
G01X1770578Y999932D02*
X1770584Y999930D01*
G01X1770571Y999932D02*
X1770578D01*
G01X1770601Y1003069D02*
X1770605Y1003064D01*
G01X1770596Y1003074D02*
X1770601Y1003069D01*
G01X1770590Y1003077D02*
X1770596Y1003074D01*
G01X1770584Y1003080D02*
X1770590Y1003077D01*
G01X1770578Y1003081D02*
X1770584Y1003080D01*
G01X1770571Y1003082D02*
X1770578Y1003081D01*
G01X1770601Y1006219D02*
X1770605Y1006213D01*
G01X1770596Y1006223D02*
X1770601Y1006219D01*
G01X1770590Y1006227D02*
X1770596Y1006223D01*
G01X1770584Y1006230D02*
X1770590Y1006227D01*
G01X1770578Y1006231D02*
X1770584Y1006230D01*
G01X1770571Y1006231D02*
X1770578D01*
G01X1770601Y1009369D02*
X1770605Y1009363D01*
G01X1770596Y1009373D02*
X1770601Y1009369D01*
G01X1770590Y1009376D02*
X1770596Y1009373D01*
G01X1770584Y1009379D02*
X1770590Y1009376D01*
G01X1770578Y1009381D02*
X1770584Y1009379D01*
G01X1770571Y1009381D02*
X1770578D01*
G01X1769627Y989310D02*
X1769626Y989317D01*
G01X1769629Y989303D02*
X1769627Y989310D01*
G01X1769633Y989296D02*
X1769629Y989303D01*
G01X1769637Y989291D02*
X1769633Y989296D01*
G01X1769644Y989286D02*
X1769637Y989291D01*
G01X1769650Y989283D02*
X1769644Y989286D01*
G01X1769658Y989281D02*
X1769650Y989283D01*
G01X1769665Y989280D02*
X1769658Y989281D01*
G01X1769627Y992459D02*
X1769626Y992467D01*
G01X1769629Y992452D02*
X1769627Y992459D01*
G01X1769633Y992446D02*
X1769629Y992452D01*
G01X1769637Y992441D02*
X1769633Y992446D01*
G01X1769644Y992436D02*
X1769637Y992441D01*
G01X1769650Y992432D02*
X1769644Y992436D01*
G01X1769658Y992430D02*
X1769650Y992432D01*
G01X1769665Y992430D02*
X1769658D01*
G01X1769627Y995609D02*
X1769626Y995616D01*
G01X1769629Y995602D02*
X1769627Y995609D01*
G01X1769633Y995596D02*
X1769629Y995602D01*
G01X1769637Y995590D02*
X1769633Y995596D01*
G01X1769644Y995585D02*
X1769637Y995590D01*
G01X1769650Y995582D02*
X1769644Y995585D01*
G01X1769658Y995580D02*
X1769650Y995582D01*
G01X1769665Y995579D02*
X1769658Y995580D01*
G01X1769627Y998759D02*
X1769626Y998766D01*
G01X1769629Y998752D02*
X1769627Y998759D01*
G01X1769633Y998745D02*
X1769629Y998752D01*
G01X1769637Y998740D02*
X1769633Y998745D01*
G01X1769644Y998735D02*
X1769637Y998740D01*
G01X1769650Y998731D02*
X1769644Y998735D01*
G01X1769658Y998730D02*
X1769650Y998731D01*
G01X1769665Y998729D02*
X1769658Y998730D01*
G01X1769627Y1001908D02*
X1769626Y1001915D01*
G01X1769629Y1001901D02*
X1769627Y1001908D01*
G01X1769633Y1001895D02*
X1769629Y1001901D01*
G01X1769637Y1001889D02*
X1769633Y1001895D01*
G01X1769644Y1001885D02*
X1769637Y1001889D01*
G01X1769650Y1001881D02*
X1769644Y1001885D01*
G01X1769658Y1001879D02*
X1769650Y1001881D01*
G01X1769665Y1001878D02*
X1769658Y1001879D01*
G01X1769627Y1005058D02*
X1769626Y1005065D01*
G01X1769629Y1005051D02*
X1769627Y1005058D01*
G01X1769633Y1005044D02*
X1769629Y1005051D01*
G01X1769637Y1005039D02*
X1769633Y1005044D01*
G01X1769644Y1005034D02*
X1769637Y1005039D01*
G01X1769650Y1005031D02*
X1769644Y1005034D01*
G01X1769658Y1005029D02*
X1769650Y1005031D01*
G01X1769665Y1005028D02*
X1769658Y1005029D01*
G01X1769627Y1008207D02*
X1769626Y1008215D01*
G01X1769629Y1008200D02*
X1769627Y1008207D01*
G01X1769633Y1008194D02*
X1769629Y1008200D01*
G01X1769637Y1008189D02*
X1769633Y1008194D01*
G01X1769644Y1008184D02*
X1769637Y1008189D01*
G01X1769650Y1008180D02*
X1769644Y1008184D01*
G01X1769658Y1008178D02*
X1769650Y1008180D01*
G01X1769665Y1008178D02*
X1769658D01*
G01X1770580Y990471D02*
X1770589Y990467D01*
G01X1770569Y990472D02*
X1770580Y990471D01*
G01Y993620D02*
X1770589Y993617D01*
G01X1770569Y993622D02*
X1770580Y993620D01*
G01Y996770D02*
X1770589Y996766D01*
G01X1770569Y996772D02*
X1770580Y996770D01*
G01Y999920D02*
X1770589Y999916D01*
G01X1770569Y999921D02*
X1770580Y999920D01*
G01Y1003069D02*
X1770589Y1003065D01*
G01X1770569Y1003071D02*
X1770580Y1003069D01*
G01Y1006219D02*
X1770589Y1006215D01*
G01X1770569Y1006220D02*
X1770580Y1006219D01*
G01Y1009369D02*
X1770589Y1009365D01*
G01X1770569Y1009370D02*
X1770580Y1009369D01*
G01X1784036Y1046134D02*
X1784035Y1046125D01*
G01X1784037Y1046140D02*
X1784036Y1046134D01*
G01X1784038Y1046142D02*
X1784037Y1046140D01*
G01X1784036Y1041134D02*
X1784035Y1041125D01*
G01X1784037Y1041140D02*
X1784036Y1041134D01*
G01X1784038Y1041142D02*
X1784037Y1041140D01*
G01X1784036Y1036134D02*
X1784035Y1036125D01*
G01X1784037Y1036140D02*
X1784036Y1036134D01*
G01X1784038Y1036142D02*
X1784037Y1036140D01*
G01X1784036Y1031134D02*
X1784035Y1031125D01*
G01X1784037Y1031140D02*
X1784036Y1031134D01*
G01X1784038Y1031142D02*
X1784037Y1031140D01*
G01X1784036Y1026134D02*
X1784035Y1026125D01*
G01X1784037Y1026140D02*
X1784036Y1026134D01*
G01X1784038Y1026142D02*
X1784037Y1026140D01*
G01X1784036Y1021134D02*
X1784035Y1021125D01*
G01X1784037Y1021140D02*
X1784036Y1021134D01*
G01X1784038Y1021142D02*
X1784037Y1021140D01*
G01X1784036Y1016134D02*
X1784035Y1016125D01*
G01X1784037Y1016140D02*
X1784036Y1016134D01*
G01X1784038Y1016142D02*
X1784037Y1016140D01*
G01X1784036Y1011134D02*
X1784035Y1011125D01*
G01X1784037Y1011140D02*
X1784036Y1011134D01*
G01X1784038Y1011142D02*
X1784037Y1011140D01*
G01X1784036Y986134D02*
X1784035Y986125D01*
G01X1784037Y986140D02*
X1784036Y986134D01*
G01X1784038Y986142D02*
X1784037Y986140D01*
G01X1784036Y981134D02*
X1784035Y981125D01*
G01X1784037Y981140D02*
X1784036Y981134D01*
G01X1784038Y981142D02*
X1784037Y981140D01*
G01X1784036Y976134D02*
X1784035Y976125D01*
G01X1784037Y976140D02*
X1784036Y976134D01*
G01X1784038Y976142D02*
X1784037Y976140D01*
G01X1769626Y1009337D02*
Y1009344D01*
G01X1769625Y1009332D02*
X1769626Y1009337D01*
G01X1769624Y1009331D02*
X1769625Y1009332D01*
G01X1769626Y1006187D02*
Y1006194D01*
G01X1769625Y1006183D02*
X1769626Y1006187D01*
G01X1769624Y1006181D02*
X1769625Y1006183D01*
G01X1769626Y1003037D02*
Y1003045D01*
G01X1769625Y1003033D02*
X1769626Y1003037D01*
G01X1769624Y1003031D02*
X1769625Y1003033D01*
G01X1769626Y999888D02*
Y999895D01*
G01X1769625Y999883D02*
X1769626Y999888D01*
G01X1769624Y999882D02*
X1769625Y999883D01*
G01X1769626Y996738D02*
Y996746D01*
G01X1769625Y996734D02*
X1769626Y996738D01*
G01X1769624Y996732D02*
X1769625Y996734D01*
G01X1769626Y993589D02*
Y993596D01*
G01X1769625Y993584D02*
X1769626Y993589D01*
G01X1769624Y993583D02*
X1769625Y993584D01*
G01X1769626Y990439D02*
Y990446D01*
G01X1769625Y990435D02*
X1769626Y990439D01*
G01X1769624Y990433D02*
X1769625Y990435D01*
G01X1769626Y992470D02*
Y992467D01*
G01X1769628Y992464D02*
X1769626Y992470D01*
G01X1769639Y992449D02*
X1769628Y992464D01*
G01X1769664Y992441D02*
X1769639Y992449D01*
G01X1769626Y995620D02*
Y995616D01*
G01X1769628Y995614D02*
X1769626Y995620D01*
G01X1769639Y995599D02*
X1769628Y995614D01*
G01X1769663Y995591D02*
X1769639Y995599D01*
G01X1769626Y1001919D02*
Y1001915D01*
G01X1769628Y1001913D02*
X1769626Y1001919D01*
G01X1769639Y1001898D02*
X1769628Y1001913D01*
G01X1769663Y1001890D02*
X1769639Y1001898D01*
G01X1769626Y1005069D02*
Y1005065D01*
G01X1769628Y1005063D02*
X1769626Y1005069D01*
G01X1769639Y1005048D02*
X1769628Y1005063D01*
G01X1769663Y1005039D02*
X1769639Y1005048D01*
G01X1769626Y989321D02*
Y989317D01*
G01X1769628Y989315D02*
X1769626Y989321D01*
G01X1769639Y989300D02*
X1769628Y989315D01*
G01X1769663Y989291D02*
X1769639Y989300D01*
G01X1769626Y1008219D02*
Y1008215D01*
G01X1769628Y1008213D02*
X1769626Y1008219D01*
G01X1769639Y1008197D02*
X1769628Y1008213D01*
G01X1769663Y1008189D02*
X1769639Y1008197D01*
G01X1784023Y957511D02*
X1784034Y957496D01*
G01X1783998Y957520D02*
X1784023Y957511D01*
G01Y962511D02*
X1784034Y962496D01*
G01X1783998Y962520D02*
X1784023Y962511D01*
G01Y967511D02*
X1784034Y967496D01*
G01X1783998Y967520D02*
X1784023Y967511D01*
G01Y972511D02*
X1784034Y972496D01*
G01X1783998Y972520D02*
X1784023Y972511D01*
G01Y977511D02*
X1784034Y977496D01*
G01X1783998Y977520D02*
X1784023Y977511D01*
G01Y982511D02*
X1784034Y982496D01*
G01X1783998Y982520D02*
X1784023Y982511D01*
G01Y987511D02*
X1784034Y987496D01*
G01X1783998Y987520D02*
X1784023Y987511D01*
G01X1769626Y992474D02*
Y992467D01*
G01X1769625Y992479D02*
X1769626Y992474D01*
G01X1769624Y992477D02*
X1769625Y992479D01*
G01X1770571Y1009375D02*
Y1009381D01*
G01X1770570Y1009371D02*
X1770571Y1009375D01*
G01X1770569Y1009370D02*
X1770570Y1009371D01*
G01X1770571Y1006226D02*
Y1006231D01*
G01X1770570Y1006222D02*
X1770571Y1006226D01*
G01X1770569Y1006220D02*
X1770570Y1006222D01*
G01X1770571Y1003076D02*
Y1003082D01*
G01X1770570Y1003072D02*
X1770571Y1003076D01*
G01X1770569Y1003071D02*
X1770570Y1003072D01*
G01X1770571Y999926D02*
Y999932D01*
G01X1770570Y999922D02*
X1770571Y999926D01*
G01X1770569Y999921D02*
X1770570Y999922D01*
G01X1770571Y996777D02*
Y996783D01*
G01X1770570Y996773D02*
X1770571Y996777D01*
G01X1770569Y996772D02*
X1770570Y996773D01*
G01X1770571Y993627D02*
Y993633D01*
G01X1770570Y993623D02*
X1770571Y993627D01*
G01X1770569Y993622D02*
X1770570Y993623D01*
G01X1770571Y990478D02*
Y990483D01*
G01X1770570Y990474D02*
X1770571Y990478D01*
G01X1770569Y990472D02*
X1770570Y990474D01*
G01X1784036Y971134D02*
X1784035Y971125D01*
G01X1784037Y971140D02*
X1784036Y971134D01*
G01X1784038Y971142D02*
X1784037Y971140D01*
G01X1784036Y966134D02*
X1784035Y966125D01*
G01X1784037Y966140D02*
X1784036Y966134D01*
G01X1784038Y966142D02*
X1784037Y966140D01*
G01X1784036Y961134D02*
X1784035Y961125D01*
G01X1784037Y961140D02*
X1784036Y961134D01*
G01X1784038Y961142D02*
X1784037Y961140D01*
G01X1784036Y956134D02*
X1784035Y956125D01*
G01X1784037Y956140D02*
X1784036Y956134D01*
G01X1784038Y956142D02*
X1784037Y956140D01*
G01X1784023Y1012511D02*
X1784034Y1012496D01*
G01X1783998Y1012520D02*
X1784023Y1012511D01*
G01Y1017511D02*
X1784034Y1017496D01*
G01X1783998Y1017520D02*
X1784023Y1017511D01*
G01Y1022511D02*
X1784034Y1022496D01*
G01X1783998Y1022520D02*
X1784023Y1022511D01*
G01Y1027511D02*
X1784034Y1027496D01*
G01X1783998Y1027520D02*
X1784023Y1027511D01*
G01Y1032511D02*
X1784034Y1032496D01*
G01X1783998Y1032520D02*
X1784023Y1032511D01*
G01Y1037511D02*
X1784034Y1037496D01*
G01X1783998Y1037520D02*
X1784023Y1037511D01*
G01Y1042511D02*
X1784034Y1042496D01*
G01X1783998Y1042520D02*
X1784023Y1042511D01*
G01Y1047511D02*
X1784034Y1047496D01*
G01X1783998Y1047520D02*
X1784023Y1047511D01*
G01X1769626Y998770D02*
Y998766D01*
G01X1769628Y998764D02*
X1769626Y998770D01*
G01X1769638Y998750D02*
X1769628Y998764D01*
G01X1769661Y998740D02*
X1769638Y998750D01*
G01X1770610Y1009337D02*
Y1009344D01*
G01Y1009332D02*
Y1009337D01*
G01X1770609Y1009331D02*
X1770610Y1009332D01*
G01Y1006187D02*
Y1006194D01*
G01Y1006183D02*
Y1006187D01*
G01X1770609Y1006181D02*
X1770610Y1006183D01*
G01Y1003038D02*
Y1003045D01*
G01Y1003033D02*
Y1003038D01*
G01X1770609Y1003031D02*
X1770610Y1003033D01*
G01Y999888D02*
Y999895D01*
G01Y999883D02*
Y999888D01*
G01X1770609Y999882D02*
X1770610Y999883D01*
G01Y996739D02*
Y996746D01*
G01Y996734D02*
Y996739D01*
G01X1770609Y996732D02*
X1770610Y996734D01*
G01Y993589D02*
Y993596D01*
G01Y993584D02*
Y993589D01*
G01X1770609Y993583D02*
X1770610Y993584D01*
G01Y990439D02*
Y990446D01*
G01Y990435D02*
Y990439D01*
G01X1770609Y990433D02*
X1770610Y990435D01*
G01X1769626Y998774D02*
Y998766D01*
G01X1769625Y998778D02*
X1769626Y998774D01*
G01X1769624Y998775D02*
X1769625Y998778D01*
G01X1770579Y996770D02*
X1770569Y996772D01*
G01X1770587Y996767D02*
X1770579Y996770D01*
G01X1770595Y996762D02*
X1770587Y996767D01*
G01X1770579Y990471D02*
X1770569Y990472D01*
G01X1770588Y990468D02*
X1770579Y990471D01*
G01X1770595Y990463D02*
X1770588Y990468D01*
G01X1770579Y993621D02*
X1770569Y993622D01*
G01X1770588Y993618D02*
X1770579Y993621D01*
G01X1770595Y993612D02*
X1770588Y993618D01*
G01X1770579Y999920D02*
X1770569Y999921D01*
G01X1770588Y999917D02*
X1770579Y999920D01*
G01X1770595Y999911D02*
X1770588Y999917D01*
G01X1770579Y1003070D02*
X1770569Y1003071D01*
G01X1770588Y1003067D02*
X1770579Y1003070D01*
G01X1770595Y1003061D02*
X1770588Y1003067D01*
G01X1770579Y1006219D02*
X1770569Y1006220D01*
G01X1770588Y1006216D02*
X1770579Y1006219D01*
G01X1770595Y1006211D02*
X1770588Y1006216D01*
G01X1770579Y1009369D02*
X1770569Y1009370D01*
G01X1770588Y1009366D02*
X1770579Y1009369D01*
G01X1770595Y1009360D02*
X1770588Y1009366D01*
G01X1769639Y1009361D02*
X1769663Y1009370D01*
G01X1769628Y1009347D02*
X1769639Y1009361D01*
G01X1769626Y1009340D02*
X1769628Y1009347D01*
G01X1769639Y1006212D02*
X1769663Y1006220D01*
G01X1769628Y1006197D02*
X1769639Y1006212D01*
G01X1769626Y1006191D02*
X1769628Y1006197D01*
G01X1769639Y1003062D02*
X1769663Y1003071D01*
G01X1769628Y1003048D02*
X1769639Y1003062D01*
G01X1769626Y1003041D02*
X1769628Y1003048D01*
G01X1769639Y999913D02*
X1769663Y999921D01*
G01X1769628Y999898D02*
X1769639Y999913D01*
G01X1769626Y999891D02*
X1769628Y999898D01*
G01X1769639Y996763D02*
X1769663Y996772D01*
G01X1769628Y996748D02*
X1769639Y996763D01*
G01X1769626Y996742D02*
X1769628Y996748D01*
G01X1769639Y993613D02*
X1769663Y993622D01*
G01X1769628Y993599D02*
X1769639Y993613D01*
G01X1769626Y993592D02*
X1769628Y993599D01*
G01X1769639Y990464D02*
X1769663Y990472D01*
G01X1769628Y990449D02*
X1769639Y990464D01*
G01X1769626Y990443D02*
X1769628Y990449D01*
G01X1769665Y989286D02*
Y989280D01*
G01X1769664Y989290D02*
X1769665Y989286D01*
G01X1769663Y989291D02*
X1769664Y989290D01*
G01X1769665Y992436D02*
Y992430D01*
G01X1769664Y992440D02*
X1769665Y992436D01*
G01X1769663Y992441D02*
X1769664Y992440D01*
G01X1769665Y995585D02*
Y995579D01*
G01X1769664Y995589D02*
X1769665Y995585D01*
G01X1769663Y995591D02*
X1769664Y995589D01*
G01X1769665Y998735D02*
Y998729D01*
G01X1769664Y998739D02*
X1769665Y998735D01*
G01X1769663Y998740D02*
X1769664Y998739D01*
G01X1769665Y1001885D02*
Y1001878D01*
G01X1769664Y1001889D02*
X1769665Y1001885D01*
G01X1769663Y1001890D02*
X1769664Y1001889D01*
G01X1769665Y1005034D02*
Y1005028D01*
G01X1769664Y1005038D02*
X1769665Y1005034D01*
G01X1769663Y1005039D02*
X1769664Y1005038D01*
G01X1769665Y1008184D02*
Y1008178D01*
G01X1769664Y1008188D02*
X1769665Y1008184D01*
G01X1769663Y1008189D02*
X1769664Y1008188D01*
G01X1784002Y957618D02*
X1784006Y957717D01*
G01X1783997Y957546D02*
X1784002Y957618D01*
G01X1783999Y957520D02*
X1783997Y957546D01*
G01X1784002Y962618D02*
X1784006Y962717D01*
G01X1783997Y962546D02*
X1784002Y962618D01*
G01X1783999Y962520D02*
X1783997Y962546D01*
G01X1784002Y967618D02*
X1784006Y967717D01*
G01X1783997Y967546D02*
X1784002Y967618D01*
G01X1783999Y967520D02*
X1783997Y967546D01*
G01X1784002Y972618D02*
X1784006Y972717D01*
G01X1783997Y972546D02*
X1784002Y972618D01*
G01X1783999Y972520D02*
X1783997Y972546D01*
G01X1784002Y977618D02*
X1784006Y977717D01*
G01X1783997Y977546D02*
X1784002Y977618D01*
G01X1783999Y977520D02*
X1783997Y977546D01*
G01X1784002Y982618D02*
X1784006Y982717D01*
G01X1783997Y982546D02*
X1784002Y982618D01*
G01X1783999Y982520D02*
X1783997Y982546D01*
G01X1784002Y987618D02*
X1784006Y987717D01*
G01X1783997Y987546D02*
X1784002Y987618D01*
G01X1783999Y987520D02*
X1783997Y987546D01*
G01X1784002Y1012618D02*
X1784006Y1012717D01*
G01X1783997Y1012546D02*
X1784002Y1012618D01*
G01X1783999Y1012520D02*
X1783997Y1012546D01*
G01X1784002Y1017618D02*
X1784006Y1017717D01*
G01X1783997Y1017546D02*
X1784002Y1017618D01*
G01X1783999Y1017520D02*
X1783997Y1017546D01*
G01X1784002Y1022618D02*
X1784006Y1022717D01*
G01X1783997Y1022546D02*
X1784002Y1022618D01*
G01X1783999Y1022520D02*
X1783997Y1022546D01*
G01X1769626Y1001923D02*
Y1001916D01*
G01X1769625Y1001928D02*
X1769626Y1001923D01*
G01X1769625Y1001918D02*
Y1001928D01*
G01X1769666Y1009554D02*
X1769665Y1009567D01*
G01X1769663Y1009541D02*
X1769666Y1009554D01*
G01X1769663Y1009528D02*
Y1009541D01*
G01X1769666Y1006405D02*
X1769665Y1006417D01*
G01X1769663Y1006392D02*
X1769666Y1006405D01*
G01X1769663Y1006378D02*
Y1006392D01*
G01X1769666Y1003255D02*
X1769665Y1003268D01*
G01X1769663Y1003242D02*
X1769666Y1003255D01*
G01X1769663Y1003228D02*
Y1003242D01*
G01X1769666Y1000106D02*
X1769665Y1000118D01*
G01X1769663Y1000093D02*
X1769666Y1000106D01*
G01X1769663Y1000079D02*
Y1000093D01*
G01X1769666Y996956D02*
X1769665Y996969D01*
G01X1769663Y996943D02*
X1769666Y996956D01*
G01X1769663Y996929D02*
Y996943D01*
G01X1769666Y993806D02*
X1769665Y993819D01*
G01X1769663Y993793D02*
X1769666Y993806D01*
G01X1769663Y993780D02*
Y993793D01*
G01X1769666Y990657D02*
X1769665Y990669D01*
G01X1769663Y990644D02*
X1769666Y990657D01*
G01X1769663Y990630D02*
Y990644D01*
G01X1783052Y1046140D02*
X1783053Y1046142D01*
G01X1783051Y1046134D02*
X1783052Y1046140D01*
G01X1783051Y1046126D02*
Y1046134D01*
G01X1783052Y1041140D02*
X1783053Y1041142D01*
G01X1783051Y1041134D02*
X1783052Y1041140D01*
G01X1783051Y1041126D02*
Y1041134D01*
G01X1783052Y1036140D02*
X1783053Y1036142D01*
G01X1783051Y1036134D02*
X1783052Y1036140D01*
G01X1783051Y1036126D02*
Y1036134D01*
G01X1783052Y1031140D02*
X1783053Y1031142D01*
G01X1783051Y1031134D02*
X1783052Y1031140D01*
G01X1783051Y1031126D02*
Y1031134D01*
G01X1783052Y1026140D02*
X1783053Y1026142D01*
G01X1783051Y1026134D02*
X1783052Y1026140D01*
G01X1783051Y1026126D02*
Y1026134D01*
G01X1783052Y1021140D02*
X1783053Y1021142D01*
G01X1783051Y1021134D02*
X1783052Y1021140D01*
G01X1783051Y1021126D02*
Y1021134D01*
G01X1783052Y1016140D02*
X1783053Y1016142D01*
G01X1783051Y1016134D02*
X1783052Y1016140D01*
G01X1783051Y1016126D02*
Y1016134D01*
G01X1783052Y1011140D02*
X1783053Y1011142D01*
G01X1783051Y1011134D02*
X1783052Y1011140D01*
G01X1783051Y1011126D02*
Y1011134D01*
G01X1783052Y986140D02*
X1783053Y986142D01*
G01X1783051Y986134D02*
X1783052Y986140D01*
G01X1783051Y986126D02*
Y986134D01*
G01X1783052Y981140D02*
X1783053Y981142D01*
G01X1783051Y981134D02*
X1783052Y981140D01*
G01X1783051Y981126D02*
Y981134D01*
G01X1783052Y976140D02*
X1783053Y976142D01*
G01X1783051Y976134D02*
X1783052Y976140D01*
G01X1783051Y976126D02*
Y976134D01*
G01X1783052Y971140D02*
X1783053Y971142D01*
G01X1783051Y971134D02*
X1783052Y971140D01*
G01X1783051Y971126D02*
Y971134D01*
G01X1783052Y966140D02*
X1783053Y966142D01*
G01X1783051Y966134D02*
X1783052Y966140D01*
G01X1783051Y966126D02*
Y966134D01*
G01X1783052Y961140D02*
X1783053Y961142D01*
G01X1783051Y961134D02*
X1783052Y961140D01*
G01X1783051Y961126D02*
Y961134D01*
G01X1783052Y956140D02*
X1783053Y956142D01*
G01X1783051Y956134D02*
X1783052Y956140D01*
G01X1783051Y956126D02*
Y956134D01*
G01X1769626Y1008222D02*
Y1008215D01*
G01X1769625Y1008227D02*
X1769626Y1008222D01*
G01X1769625Y1008219D02*
Y1008227D01*
G01X1769663Y1008017D02*
X1769662Y1008031D01*
G01X1769666Y1008005D02*
X1769663Y1008017D01*
G01X1769665Y1007992D02*
X1769666Y1008005D01*
G01X1769663Y1004868D02*
X1769662Y1004881D01*
G01X1769666Y1004855D02*
X1769663Y1004868D01*
G01X1769665Y1004843D02*
X1769666Y1004855D01*
G01X1769663Y1001718D02*
X1769662Y1001732D01*
G01X1769666Y1001706D02*
X1769663Y1001718D01*
G01X1769665Y1001693D02*
X1769666Y1001706D01*
G01X1769663Y998569D02*
X1769662Y998582D01*
G01X1769666Y998556D02*
X1769663Y998569D01*
G01X1769665Y998543D02*
X1769666Y998556D01*
G01X1769663Y995419D02*
X1769662Y995433D01*
G01X1769666Y995406D02*
X1769663Y995419D01*
G01X1769665Y995394D02*
X1769666Y995406D01*
G01X1769663Y992269D02*
X1769662Y992283D01*
G01X1769666Y992257D02*
X1769663Y992269D01*
G01X1769665Y992244D02*
X1769666Y992257D01*
G01X1769663Y989120D02*
X1769662Y989133D01*
G01X1769666Y989107D02*
X1769663Y989120D01*
G01X1769665Y989094D02*
X1769666Y989107D01*
G01X1770573Y1009541D02*
X1770574Y1009528D01*
G01X1770570Y1009554D02*
X1770573Y1009541D01*
G01X1770571Y1009567D02*
X1770570Y1009554D01*
G01X1770573Y1006392D02*
X1770574Y1006378D01*
G01X1770570Y1006405D02*
X1770573Y1006392D01*
G01X1770571Y1006417D02*
X1770570Y1006405D01*
G01X1770573Y1003242D02*
X1770574Y1003228D01*
G01X1770570Y1003255D02*
X1770573Y1003242D01*
G01X1770571Y1003268D02*
X1770570Y1003255D01*
G01X1770573Y1000093D02*
X1770574Y1000079D01*
G01X1770570Y1000106D02*
X1770573Y1000093D01*
G01X1770571Y1000118D02*
X1770570Y1000106D01*
G01X1770573Y996943D02*
X1770574Y996929D01*
G01X1770570Y996956D02*
X1770573Y996943D01*
G01X1770571Y996969D02*
X1770570Y996956D01*
G01X1770573Y993793D02*
X1770574Y993780D01*
G01X1770570Y993806D02*
X1770573Y993793D01*
G01X1770571Y993819D02*
X1770570Y993806D01*
G01X1770573Y990644D02*
X1770574Y990630D01*
G01X1770570Y990657D02*
X1770573Y990644D01*
G01X1770571Y990669D02*
X1770570Y990657D01*
G01X1769626Y995624D02*
Y995617D01*
G01X1769625Y995628D02*
X1769626Y995624D01*
G01X1769624Y995621D02*
X1769625Y995628D01*
G01X1769626Y1005073D02*
Y1005065D01*
G01X1769625Y1005077D02*
X1769626Y1005073D01*
G01X1769624Y1005070D02*
X1769625Y1005077D01*
G01X1770570Y1008005D02*
X1770571Y1007992D01*
G01X1770573Y1008017D02*
X1770570Y1008005D01*
G01X1770574Y1008031D02*
X1770573Y1008017D01*
G01X1770570Y1004855D02*
X1770571Y1004843D01*
G01X1770573Y1004868D02*
X1770570Y1004855D01*
G01X1770574Y1004881D02*
X1770573Y1004868D01*
G01X1770570Y1001706D02*
X1770571Y1001693D01*
G01X1770573Y1001718D02*
X1770570Y1001706D01*
G01X1770574Y1001732D02*
X1770573Y1001718D01*
G01X1770570Y998556D02*
X1770571Y998543D01*
G01X1770573Y998569D02*
X1770570Y998556D01*
G01X1770574Y998582D02*
X1770573Y998569D01*
G01X1770570Y995406D02*
X1770571Y995394D01*
G01X1770573Y995419D02*
X1770570Y995406D01*
G01X1770574Y995433D02*
X1770573Y995419D01*
G01X1770570Y992257D02*
X1770571Y992244D01*
G01X1770573Y992269D02*
X1770570Y992257D01*
G01X1770574Y992283D02*
X1770573Y992269D01*
G01X1770570Y989107D02*
X1770571Y989094D01*
G01X1770573Y989120D02*
X1770570Y989107D01*
G01X1770574Y989133D02*
X1770573Y989120D01*
G01X1769626Y989325D02*
Y989317D01*
G01X1769625Y989329D02*
X1769626Y989325D01*
G01X1769624Y989323D02*
X1769625Y989329D01*
G01X1784036Y957487D02*
X1784035Y957494D01*
G01X1784037Y957482D02*
X1784036Y957487D01*
G01X1784038Y957480D02*
X1784037Y957482D01*
G01X1784036Y962487D02*
X1784035Y962494D01*
G01X1784037Y962482D02*
X1784036Y962487D01*
G01X1784038Y962480D02*
X1784037Y962482D01*
G01X1784036Y967487D02*
X1784035Y967494D01*
G01X1784037Y967482D02*
X1784036Y967487D01*
G01X1784038Y967480D02*
X1784037Y967482D01*
G01X1784036Y972487D02*
X1784035Y972494D01*
G01X1784037Y972482D02*
X1784036Y972487D01*
G01X1784038Y972480D02*
X1784037Y972482D01*
G01X1784036Y977487D02*
X1784035Y977494D01*
G01X1784037Y977482D02*
X1784036Y977487D01*
G01X1784038Y977480D02*
X1784037Y977482D01*
G01X1784036Y982487D02*
X1784035Y982494D01*
G01X1784037Y982482D02*
X1784036Y982487D01*
G01X1784038Y982480D02*
X1784037Y982482D01*
G01X1784036Y987487D02*
X1784035Y987494D01*
G01X1784037Y987482D02*
X1784036Y987487D01*
G01X1784038Y987480D02*
X1784037Y987482D01*
G01X1784036Y1012487D02*
X1784035Y1012494D01*
G01X1784037Y1012482D02*
X1784036Y1012487D01*
G01X1784038Y1012480D02*
X1784037Y1012482D01*
G01X1784036Y1017487D02*
X1784035Y1017494D01*
G01X1784037Y1017482D02*
X1784036Y1017487D01*
G01X1784038Y1017480D02*
X1784037Y1017482D01*
G01X1784036Y1022487D02*
X1784035Y1022494D01*
G01X1784037Y1022482D02*
X1784036Y1022487D01*
G01X1784038Y1022480D02*
X1784037Y1022482D01*
G01X1784036Y1027487D02*
X1784035Y1027494D01*
G01X1784037Y1027482D02*
X1784036Y1027487D01*
G01X1784038Y1027480D02*
X1784037Y1027482D01*
G01X1784036Y1032487D02*
X1784035Y1032494D01*
G01X1784037Y1032482D02*
X1784036Y1032487D01*
G01X1784038Y1032480D02*
X1784037Y1032482D01*
G01X1784036Y1037487D02*
X1784035Y1037494D01*
G01X1784037Y1037482D02*
X1784036Y1037487D01*
G01X1784038Y1037480D02*
X1784037Y1037482D01*
G01X1784036Y1042487D02*
X1784035Y1042494D01*
G01X1784037Y1042482D02*
X1784036Y1042487D01*
G01X1784038Y1042480D02*
X1784037Y1042482D01*
G01X1784036Y1047487D02*
X1784035Y1047494D01*
G01X1784037Y1047482D02*
X1784036Y1047487D01*
G01X1784038Y1047480D02*
X1784037Y1047482D01*
G01X1769649Y992443D02*
X1769663Y992441D01*
G01X1769637Y992450D02*
X1769649Y992443D01*
G01X1769625Y992469D02*
X1769637Y992450D01*
G01X1769649Y1001892D02*
X1769663Y1001890D01*
G01X1769637Y1001900D02*
X1769649Y1001892D01*
G01X1769625Y1001918D02*
X1769637Y1001900D01*
G01X1769648Y995593D02*
X1769663Y995591D01*
G01X1769636Y995601D02*
X1769648Y995593D01*
G01X1769624Y995621D02*
X1769636Y995601D01*
G01X1769648Y1005042D02*
X1769663Y1005039D01*
G01X1769636Y1005050D02*
X1769648Y1005042D01*
G01X1769624Y1005070D02*
X1769636Y1005050D01*
G01X1770610Y989325D02*
Y989317D01*
G01X1770609Y989329D02*
X1770610Y989325D01*
G01X1770609Y989331D02*
Y989329D01*
G01X1770610Y992474D02*
Y992467D01*
G01X1770609Y992479D02*
X1770610Y992474D01*
G01X1770609Y992480D02*
Y992479D01*
G01X1770610Y995624D02*
Y995616D01*
G01X1770609Y995628D02*
X1770610Y995624D01*
G01X1770609Y995630D02*
Y995628D01*
G01X1770610Y998774D02*
Y998766D01*
G01X1770609Y998778D02*
X1770610Y998774D01*
G01X1770609Y998780D02*
Y998778D01*
G01X1770610Y1001923D02*
Y1001915D01*
G01X1770609Y1001928D02*
X1770610Y1001923D01*
G01X1770609Y1001929D02*
Y1001928D01*
G01X1770610Y1005073D02*
Y1005065D01*
G01X1770609Y1005077D02*
X1770610Y1005073D01*
G01X1770609Y1005079D02*
Y1005077D01*
G01X1770610Y1008222D02*
Y1008215D01*
G01X1770609Y1008227D02*
X1770610Y1008222D01*
G01X1770609Y1008228D02*
Y1008227D01*
G01X1769648Y1008192D02*
X1769663Y1008189D01*
G01X1769636Y1008200D02*
X1769648Y1008192D01*
G01X1769624Y1008220D02*
X1769636Y1008200D01*
G01X1769648Y989294D02*
X1769663Y989291D01*
G01X1769635Y989303D02*
X1769648Y989294D01*
G01X1769624Y989323D02*
X1769635Y989303D01*
G01X1770609Y990453D02*
X1770610Y990446D01*
G01X1770608Y990459D02*
X1770609Y990453D01*
G01X1770605Y990465D02*
X1770608Y990459D01*
G01X1770609Y993603D02*
X1770610Y993596D01*
G01X1770608Y993609D02*
X1770609Y993603D01*
G01X1770605Y993615D02*
X1770608Y993609D01*
G01X1770609Y996752D02*
X1770610Y996746D01*
G01X1770608Y996759D02*
X1770609Y996752D01*
G01X1770605Y996765D02*
X1770608Y996759D01*
G01X1770609Y999902D02*
X1770610Y999895D01*
G01X1770608Y999908D02*
X1770609Y999902D01*
G01X1770605Y999914D02*
X1770608Y999908D01*
G01X1770609Y1003052D02*
X1770610Y1003045D01*
G01X1770608Y1003058D02*
X1770609Y1003052D01*
G01X1770605Y1003064D02*
X1770608Y1003058D01*
G01X1770609Y1006201D02*
X1770610Y1006194D01*
G01X1770608Y1006207D02*
X1770609Y1006201D01*
G01X1770605Y1006213D02*
X1770608Y1006207D01*
G01X1770609Y1009351D02*
X1770610Y1009344D01*
G01X1770608Y1009357D02*
X1770609Y1009351D01*
G01X1770605Y1009363D02*
X1770608Y1009357D01*
G01X1770571Y989286D02*
X1770572Y989280D01*
G01X1770570Y989290D02*
X1770571Y989286D01*
G01X1770569Y989291D02*
X1770570Y989290D01*
G01X1770571Y992436D02*
X1770572Y992430D01*
G01X1770570Y992439D02*
X1770571Y992436D01*
G01X1770569Y992441D02*
X1770570Y992439D01*
G01X1770571Y995585D02*
X1770572Y995579D01*
G01X1770570Y995589D02*
X1770571Y995585D01*
G01X1770569Y995591D02*
X1770570Y995589D01*
G01X1770571Y998735D02*
X1770572Y998729D01*
G01X1770570Y998739D02*
X1770571Y998735D01*
G01X1770569Y998740D02*
X1770570Y998739D01*
G01X1770571Y1001885D02*
X1770572Y1001878D01*
G01X1770570Y1001888D02*
X1770571Y1001885D01*
G01X1770569Y1001890D02*
X1770570Y1001888D01*
G01X1770571Y1008184D02*
X1770572Y1008178D01*
G01X1770570Y1008187D02*
X1770571Y1008184D01*
G01X1770569Y1008189D02*
X1770570Y1008187D01*
G01X1783051Y957527D02*
Y957536D01*
G01X1783052Y957521D02*
X1783051Y957527D01*
G01X1783053Y957520D02*
X1783052Y957521D01*
G01X1783051Y962527D02*
Y962536D01*
G01X1783052Y962521D02*
X1783051Y962527D01*
G01X1783053Y962520D02*
X1783052Y962521D01*
G01X1783051Y967527D02*
Y967536D01*
G01X1783052Y967521D02*
X1783051Y967527D01*
G01X1783053Y967520D02*
X1783052Y967521D01*
G01X1783051Y972527D02*
Y972536D01*
G01X1783052Y972521D02*
X1783051Y972527D01*
G01X1783053Y972520D02*
X1783052Y972521D01*
G01X1784028Y957663D02*
X1784035Y957637D01*
G01X1784018Y957690D02*
X1784028Y957663D01*
G01X1784006Y957717D02*
X1784018Y957690D01*
G01X1784028Y962663D02*
X1784035Y962637D01*
G01X1784018Y962690D02*
X1784028Y962663D01*
G01X1784006Y962717D02*
X1784018Y962690D01*
G01X1784028Y967663D02*
X1784035Y967637D01*
G01X1784018Y967690D02*
X1784028Y967663D01*
G01X1784006Y967717D02*
X1784018Y967690D01*
G01X1770603Y996754D02*
X1770595Y996762D01*
G01X1770607Y996743D02*
X1770603Y996754D01*
G01X1770609Y996732D02*
X1770607Y996743D01*
G01X1770603Y990454D02*
X1770595Y990463D01*
G01X1770607Y990444D02*
X1770603Y990454D01*
G01X1770609Y990433D02*
X1770607Y990444D01*
G01X1770603Y993604D02*
X1770595Y993612D01*
G01X1770607Y993594D02*
X1770603Y993604D01*
G01X1770609Y993583D02*
X1770607Y993594D01*
G01X1770603Y999903D02*
X1770595Y999911D01*
G01X1770607Y999893D02*
X1770603Y999903D01*
G01X1770609Y999882D02*
X1770607Y999893D01*
G01X1770603Y1003053D02*
X1770595Y1003061D01*
G01X1770607Y1003043D02*
X1770603Y1003053D01*
G01X1770609Y1003031D02*
X1770607Y1003043D01*
G01X1770603Y1006202D02*
X1770595Y1006211D01*
G01X1770607Y1006192D02*
X1770603Y1006202D01*
G01X1770609Y1006181D02*
X1770607Y1006192D01*
G01X1770603Y1009352D02*
X1770595Y1009360D01*
G01X1770607Y1009342D02*
X1770603Y1009352D01*
G01X1770609Y1009331D02*
X1770607Y1009342D01*
G01X1784002Y1027618D02*
X1784006Y1027717D01*
G01X1783997Y1027546D02*
X1784002Y1027618D01*
G01X1783999Y1027520D02*
X1783997Y1027546D01*
G01X1784002Y1032618D02*
X1784006Y1032717D01*
G01X1783997Y1032546D02*
X1784002Y1032618D01*
G01X1783999Y1032520D02*
X1783997Y1032546D01*
G01X1784002Y1037618D02*
X1784006Y1037717D01*
G01X1783997Y1037546D02*
X1784002Y1037618D01*
G01X1783999Y1037520D02*
X1783997Y1037546D01*
G01X1784002Y1042618D02*
X1784006Y1042717D01*
G01X1783997Y1042546D02*
X1784002Y1042618D01*
G01X1783999Y1042520D02*
X1783997Y1042546D01*
G01X1783051Y977527D02*
Y977536D01*
G01X1783052Y977521D02*
X1783051Y977527D01*
G01X1783053Y977520D02*
X1783052Y977521D01*
G01X1783051Y982527D02*
Y982536D01*
G01X1783052Y982521D02*
X1783051Y982527D01*
G01X1783053Y982520D02*
X1783052Y982521D01*
G01X1783051Y987527D02*
Y987536D01*
G01X1783052Y987521D02*
X1783051Y987527D01*
G01X1783053Y987520D02*
X1783052Y987521D01*
G01X1783051Y1012527D02*
Y1012536D01*
G01X1783052Y1012521D02*
X1783051Y1012527D01*
G01X1783053Y1012520D02*
X1783052Y1012521D01*
G01X1783051Y1017527D02*
Y1017536D01*
G01X1783052Y1017521D02*
X1783051Y1017527D01*
G01X1783053Y1017520D02*
X1783052Y1017521D01*
G01X1783051Y1022527D02*
Y1022536D01*
G01X1783052Y1022521D02*
X1783051Y1022527D01*
G01X1783053Y1022520D02*
X1783052Y1022521D01*
G01X1783051Y1027527D02*
Y1027536D01*
G01X1783052Y1027521D02*
X1783051Y1027527D01*
G01X1783053Y1027520D02*
X1783052Y1027521D01*
G01X1783051Y1032527D02*
Y1032536D01*
G01X1783052Y1032521D02*
X1783051Y1032527D01*
G01X1783053Y1032520D02*
X1783052Y1032521D01*
G01X1783051Y1037527D02*
Y1037536D01*
G01X1783052Y1037521D02*
X1783051Y1037527D01*
G01X1783053Y1037520D02*
X1783052Y1037521D01*
G01X1783051Y1042527D02*
Y1042536D01*
G01X1783052Y1042521D02*
X1783051Y1042527D01*
G01X1783053Y1042520D02*
X1783052Y1042521D01*
G01X1783053Y1047520D02*
X1783052Y1047521D01*
G01X1784028Y972663D02*
X1784035Y972637D01*
G01X1784018Y972690D02*
X1784028Y972663D01*
G01X1784006Y972717D02*
X1784018Y972690D01*
G01X1784028Y977663D02*
X1784035Y977637D01*
G01X1784018Y977690D02*
X1784028Y977663D01*
G01X1784006Y977717D02*
X1784018Y977690D01*
G01X1784028Y982663D02*
X1784035Y982637D01*
G01X1784018Y982690D02*
X1784028Y982663D01*
G01X1784006Y982717D02*
X1784018Y982690D01*
G01X1784028Y987663D02*
X1784035Y987637D01*
G01X1784018Y987690D02*
X1784028Y987663D01*
G01X1784006Y987717D02*
X1784018Y987690D01*
G01X1784028Y1012663D02*
X1784035Y1012637D01*
G01X1784018Y1012690D02*
X1784028Y1012663D01*
G01X1784006Y1012717D02*
X1784018Y1012690D01*
G01X1784028Y1017663D02*
X1784035Y1017637D01*
G01X1784018Y1017690D02*
X1784028Y1017663D01*
G01X1784006Y1017717D02*
X1784018Y1017690D01*
G01X1784028Y1022663D02*
X1784035Y1022637D01*
G01X1784018Y1022690D02*
X1784028Y1022663D01*
G01X1784006Y1022717D02*
X1784018Y1022690D01*
G01X1784028Y1027663D02*
X1784035Y1027637D01*
G01X1784018Y1027690D02*
X1784028Y1027663D01*
G01X1784006Y1027717D02*
X1784018Y1027690D01*
G01X1784028Y1032663D02*
X1784035Y1032637D01*
G01X1784018Y1032690D02*
X1784028Y1032663D01*
G01X1784006Y1032717D02*
X1784018Y1032690D01*
G01X1784028Y1037663D02*
X1784035Y1037637D01*
G01X1784018Y1037690D02*
X1784028Y1037663D01*
G01X1784006Y1037717D02*
X1784018Y1037690D01*
G01X1784028Y1042663D02*
X1784035Y1042637D01*
G01X1784018Y1042690D02*
X1784028Y1042663D01*
G01X1784006Y1042717D02*
X1784018Y1042690D01*
G01X1769644Y998745D02*
X1769663Y998740D01*
G01X1769630Y998757D02*
X1769644Y998745D01*
G01X1769624Y998775D02*
X1769630Y998757D01*
G01X1784018Y957515D02*
X1783999Y957520D01*
G01X1784033Y957500D02*
X1784018Y957515D01*
G01X1784038Y957480D02*
X1784033Y957500D01*
G01X1784018Y962515D02*
X1783999Y962520D01*
G01X1784033Y962500D02*
X1784018Y962515D01*
G01X1784038Y962480D02*
X1784033Y962500D01*
G01X1784018Y967515D02*
X1783999Y967520D01*
G01X1784033Y967500D02*
X1784018Y967515D01*
G01X1784038Y967480D02*
X1784033Y967500D01*
G01X1784018Y972515D02*
X1783999Y972520D01*
G01X1784033Y972500D02*
X1784018Y972515D01*
G01X1784038Y972480D02*
X1784033Y972500D01*
G01X1784018Y977515D02*
X1783999Y977520D01*
G01X1784033Y977500D02*
X1784018Y977515D01*
G01X1784038Y977480D02*
X1784033Y977500D01*
G01X1784018Y982515D02*
X1783999Y982520D01*
G01X1784033Y982500D02*
X1784018Y982515D01*
G01X1784038Y982480D02*
X1784033Y982500D01*
G01X1784018Y987515D02*
X1783999Y987520D01*
G01X1784033Y987500D02*
X1784018Y987515D01*
G01X1784038Y987480D02*
X1784033Y987500D01*
G01X1784018Y1012515D02*
X1783999Y1012520D01*
G01X1784033Y1012500D02*
X1784018Y1012515D01*
G01X1784038Y1012480D02*
X1784033Y1012500D01*
G01X1784018Y1017515D02*
X1783999Y1017520D01*
G01X1784033Y1017500D02*
X1784018Y1017515D01*
G01X1784038Y1017480D02*
X1784033Y1017500D01*
G01X1784018Y1022515D02*
X1783999Y1022520D01*
G01X1784033Y1022500D02*
X1784018Y1022515D01*
G01X1784038Y1022480D02*
X1784033Y1022500D01*
G01X1784018Y1027515D02*
X1783999Y1027520D01*
G01X1784033Y1027500D02*
X1784018Y1027515D01*
G01X1784038Y1027480D02*
X1784033Y1027500D01*
G01X1784018Y1032515D02*
X1783999Y1032520D01*
G01X1784033Y1032500D02*
X1784018Y1032515D01*
G01X1784038Y1032480D02*
X1784033Y1032500D01*
G01X1784018Y1037515D02*
X1783999Y1037520D01*
G01X1784033Y1037500D02*
X1784018Y1037515D01*
G01X1784038Y1037480D02*
X1784033Y1037500D01*
G01X1784018Y1042515D02*
X1783999Y1042520D01*
G01X1784033Y1042500D02*
X1784018Y1042515D01*
G01X1784038Y1042480D02*
X1784033Y1042500D01*
G01X1784018Y1047515D02*
X1783999Y1047520D01*
G01X1784033Y1047500D02*
X1784018Y1047515D01*
G01X1784038Y1047480D02*
X1784033Y1047500D01*
G01X1770569Y1005039D02*
X1770573Y1005028D01*
G01X1770610Y990435D02*
Y990446D01*
G01Y993585D02*
Y993596D01*
G01Y996734D02*
Y996746D01*
G01Y999884D02*
Y999895D01*
G01Y1003033D02*
Y1003045D01*
G01Y1006183D02*
Y1006194D01*
G01Y1009333D02*
Y1009344D01*
G01X1784035Y957494D02*
X1784036Y957502D01*
G01X1784035Y962494D02*
X1784036Y962502D01*
G01X1784035Y967494D02*
X1784036Y967502D01*
G01X1784035Y972494D02*
X1784036Y972502D01*
G01X1784035Y977494D02*
X1784036Y977502D01*
G01X1784035Y982494D02*
X1784036Y982502D01*
G01X1784035Y987494D02*
X1784036Y987502D01*
G01X1784035Y1012494D02*
X1784036Y1012502D01*
G01X1784035Y1017494D02*
X1784036Y1017502D01*
G01X1784035Y1022494D02*
X1784036Y1022502D01*
G01X1784035Y1027494D02*
X1784036Y1027502D01*
G01X1784035Y1032494D02*
X1784036Y1032502D01*
G01X1784035Y1037494D02*
X1784036Y1037502D01*
G01X1784035Y1042494D02*
X1784036Y1042502D01*
G01X1788386Y1046142D02*
Y1047520D01*
G01Y1041142D02*
Y1042520D01*
G01Y1036142D02*
Y1037520D01*
G01Y1031142D02*
Y1032520D01*
G01Y1026142D02*
Y1027520D01*
G01Y1021142D02*
Y1022520D01*
G01Y1016142D02*
Y1017520D01*
G01Y1011142D02*
Y1012520D01*
G01Y986142D02*
Y987520D01*
G01Y981142D02*
Y982520D01*
G01Y976142D02*
Y977520D01*
G01Y971142D02*
Y972520D01*
G01Y966142D02*
Y967520D01*
G01Y961142D02*
Y962520D01*
G01Y956142D02*
Y957520D01*
G01X1785217D02*
Y956142D01*
G01Y962520D02*
Y961142D01*
G01Y967520D02*
Y966142D01*
G01Y972520D02*
Y971142D01*
G01Y977520D02*
Y976142D01*
G01Y982520D02*
Y981142D01*
G01Y987520D02*
Y986142D01*
G01Y1012520D02*
Y1011142D01*
G01Y1017520D02*
Y1016142D01*
G01Y1022520D02*
Y1021142D01*
G01Y1027520D02*
Y1026142D01*
G01Y1032520D02*
Y1031142D01*
G01Y1037520D02*
Y1036142D01*
G01Y1042520D02*
Y1041142D01*
G01Y1047520D02*
Y1046142D01*
G01X1784646Y1010374D02*
Y988287D01*
G01X1784035Y1045650D02*
Y1048012D01*
G01Y1040650D02*
Y1043012D01*
G01Y1035650D02*
Y1038012D01*
G01Y1030650D02*
Y1033012D01*
G01Y1025650D02*
Y1028012D01*
G01Y1020650D02*
Y1023012D01*
G01Y1015650D02*
Y1018012D01*
G01Y1010650D02*
Y1013012D01*
G01Y985650D02*
Y988012D01*
G01Y980650D02*
Y983012D01*
G01Y975650D02*
Y978012D01*
G01Y970650D02*
Y973012D01*
G01Y965650D02*
Y968012D01*
G01Y960650D02*
Y963012D01*
G01Y955650D02*
Y958012D01*
G01Y967494D02*
Y967637D01*
G01Y962494D02*
Y962637D01*
G01Y977494D02*
Y977637D01*
G01Y972494D02*
Y972637D01*
G01Y987494D02*
Y987637D01*
G01Y982494D02*
Y982637D01*
G01Y1017494D02*
Y1017637D01*
G01Y1012494D02*
Y1012637D01*
G01Y1027494D02*
Y1027637D01*
G01Y1022494D02*
Y1022637D01*
G01Y1037494D02*
Y1037637D01*
G01Y1032494D02*
Y1032637D01*
G01Y1042494D02*
Y1042637D01*
G01X1783465Y1009193D02*
Y989469D01*
G01X1783051Y958012D02*
Y955650D01*
G01Y963012D02*
Y960650D01*
G01Y968012D02*
Y965650D01*
G01Y973012D02*
Y970650D01*
G01Y978012D02*
Y975650D01*
G01Y983012D02*
Y980650D01*
G01Y988012D02*
Y985650D01*
G01Y1013012D02*
Y1010650D01*
G01Y1018012D02*
Y1015650D01*
G01Y1023012D02*
Y1020650D01*
G01Y1028012D02*
Y1025650D01*
G01Y1033012D02*
Y1030650D01*
G01Y1038012D02*
Y1035650D01*
G01Y1043012D02*
Y1040650D01*
G01Y1048012D02*
Y1045650D01*
G01X1780709Y1086831D02*
Y1010374D01*
G01X1779528Y989469D02*
Y953012D01*
G01Y1085650D02*
Y1009193D01*
G01X1774016Y953012D02*
Y1085650D01*
G01X1771063Y1090571D02*
Y1011535D01*
G01X1770610Y1008031D02*
Y1009528D01*
G01Y1004881D02*
Y1006378D01*
G01Y1001732D02*
Y1003228D01*
G01Y998582D02*
Y1000079D01*
G01Y995433D02*
Y996929D01*
G01Y992283D02*
Y993780D01*
G01Y989133D02*
Y990630D01*
G01X1770571Y989280D02*
Y989133D01*
G01Y990630D02*
Y990483D01*
G01Y995579D02*
Y995432D01*
G01Y992430D02*
Y992283D01*
G01Y993780D02*
Y993633D01*
G01Y998729D02*
Y998582D01*
G01Y1000079D02*
Y999932D01*
G01Y996930D02*
Y996783D01*
G01Y1001878D02*
Y1001731D01*
G01Y1003229D02*
Y1003082D01*
G01Y1008178D02*
Y1008031D01*
G01Y1009528D02*
Y1009381D01*
G01Y1005028D02*
Y1004881D01*
G01Y1006378D02*
Y1006231D01*
G01X1769665Y1008031D02*
Y1008178D01*
G01Y1009381D02*
Y1009528D01*
G01Y1004881D02*
Y1005028D01*
G01Y1006231D02*
Y1006378D01*
G01Y1001731D02*
Y1001878D01*
G01Y1003082D02*
Y1003229D01*
G01Y998582D02*
Y998729D01*
G01Y999932D02*
Y1000079D01*
G01Y996783D02*
Y996930D01*
G01Y995432D02*
Y995579D01*
G01Y992283D02*
Y992430D01*
G01Y993633D02*
Y993780D01*
G01Y989133D02*
Y989280D01*
G01Y990483D02*
Y990630D01*
G01X1769626D02*
Y989134D01*
G01Y993780D02*
Y992283D01*
G01Y1000079D02*
Y998583D01*
G01Y996929D02*
Y995433D01*
G01Y1003228D02*
Y1001732D01*
G01Y1009528D02*
Y1008031D01*
G01Y1006378D02*
Y1004882D01*
G01X1768445Y990472D02*
Y989291D01*
G01Y996772D02*
Y995591D01*
G01Y993622D02*
Y992441D01*
G01Y999921D02*
Y998740D01*
G01Y1003071D02*
Y1001890D01*
G01Y1009370D02*
Y1008189D01*
G01Y1006220D02*
Y1005039D01*
G01X1768110Y1011535D02*
Y987126D01*
G01X1767717D02*
Y1011535D01*
G01X1764685Y1008189D02*
Y1009370D01*
G01Y1005039D02*
Y1006220D01*
G01Y1001890D02*
Y1003071D01*
G01Y998740D02*
Y999921D01*
G01Y995591D02*
Y996772D01*
G01Y992441D02*
Y993622D01*
G01Y989291D02*
Y990472D01*
G01X1770610Y1008215D02*
Y1008226D01*
G01Y1005065D02*
Y1005076D01*
G01Y1001916D02*
Y1001926D01*
G01Y998766D02*
Y998777D01*
G01Y995617D02*
Y995627D01*
G01Y992467D02*
Y992478D01*
G01Y989317D02*
Y989328D01*
G01X1783465Y989469D02*
X1784646Y988287D01*
G01X1779528Y989469D02*
X1780709Y988287D01*
G01X1783465Y1009193D02*
X1784646Y1010374D01*
G01X1779528Y1009193D02*
X1780709Y1010374D01*
G01X1769513Y1008228D02*
X1769624Y1008220D01*
G01Y998775D02*
X1769513Y998780D01*
G01X1769624Y1001926D02*
X1769513Y1001929D01*
G01X1788386Y1046142D02*
X1783053D01*
G01X1783051Y1045650D02*
X1784035D01*
G01Y1043012D02*
X1783051D01*
G01X1783053Y1042520D02*
X1788386D01*
G01Y1042480D02*
X1784038D01*
G01X1788386Y1041142D02*
X1783053D01*
G01X1783051Y1040650D02*
X1784035D01*
G01Y1038012D02*
X1783051D01*
G01X1783053Y1037520D02*
X1788386D01*
G01Y1037480D02*
X1784038D01*
G01X1788386Y1036142D02*
X1783053D01*
G01X1783051Y1035650D02*
X1784035D01*
G01Y1033012D02*
X1783051D01*
G01X1783053Y1032520D02*
X1788386D01*
G01Y1032480D02*
X1784038D01*
G01X1788386Y1031142D02*
X1783053D01*
G01X1783051Y1030650D02*
X1784035D01*
G01Y1028012D02*
X1783051D01*
G01X1783053Y1027520D02*
X1788386D01*
G01Y1027480D02*
X1784038D01*
G01X1788386Y1026142D02*
X1783053D01*
G01X1783051Y1025650D02*
X1784035D01*
G01Y1023012D02*
X1783051D01*
G01X1783053Y1022520D02*
X1788386D01*
G01Y1022480D02*
X1784038D01*
G01X1788386Y1021142D02*
X1783053D01*
G01X1784035Y1045946D02*
X1783051Y1045945D01*
G01Y1042715D02*
X1784006Y1042717D01*
G01X1784035Y1040946D02*
X1783051Y1040945D01*
G01Y1037715D02*
X1784006Y1037717D01*
G01X1784035Y1035946D02*
X1783051Y1035945D01*
G01Y1032715D02*
X1784006Y1032717D01*
G01X1784035Y1030946D02*
X1783051Y1030945D01*
G01Y1027715D02*
X1784006Y1027717D01*
G01X1784035Y1025946D02*
X1783051Y1025945D01*
G01Y1022715D02*
X1784006Y1022717D01*
G01X1769624Y992477D02*
X1769513Y992480D01*
G01X1783051Y1020650D02*
X1784035D01*
G01Y1018012D02*
X1783051D01*
G01X1783053Y1017520D02*
X1788386D01*
G01Y1017480D02*
X1784038D01*
G01X1788386Y1016142D02*
X1783053D01*
G01X1783051Y1015650D02*
X1784035D01*
G01Y1013012D02*
X1783051D01*
G01X1783053Y1012520D02*
X1788386D01*
G01Y1012480D02*
X1784038D01*
G01X1771063Y1011535D02*
X1767717D01*
G01X1788386Y1011142D02*
X1783053D01*
G01X1783051Y1010650D02*
X1784035D01*
G01X1780709Y1010374D02*
X1784646D01*
G01X1770571Y1009567D02*
X1769665D01*
G01X1770610Y1009528D02*
X1769626D01*
G01X1770569Y1009370D02*
X1764685D01*
G01Y1009331D02*
X1770609D01*
G01X1779528Y1009193D02*
X1783465D01*
G01X1770609Y1008228D02*
X1764685D01*
G01X1770569Y1008189D02*
X1764685D01*
G01X1769626Y1008031D02*
X1770610D01*
G01X1769665Y1007992D02*
X1770571D01*
G01Y1006417D02*
X1769665D01*
G01X1770610Y1006378D02*
X1769626D01*
G01X1770569Y1006220D02*
X1764685D01*
G01Y1006181D02*
X1770609D01*
G01Y1005079D02*
X1764685D01*
G01X1770569Y1005039D02*
X1764685D01*
G01X1769626Y1004882D02*
X1770610D01*
G01X1769665Y1004843D02*
X1770571D01*
G01Y1003268D02*
X1769665D01*
G01X1770610Y1003228D02*
X1769626D01*
G01X1770569Y1003071D02*
X1764685D01*
G01Y1003031D02*
X1770609D01*
G01X1768879Y1001929D02*
X1768445D01*
G01X1770609D02*
X1764685D01*
G01X1770569Y1001890D02*
X1764685D01*
G01X1769626Y1001732D02*
X1770610D01*
G01X1769665Y1001693D02*
X1770571D01*
G01Y1000118D02*
X1769665D01*
G01X1770610Y1000079D02*
X1769626D01*
G01X1770569Y999921D02*
X1764685D01*
G01Y999882D02*
X1770609D01*
G01X1768879Y998780D02*
X1768445D01*
G01X1770609D02*
X1764685D01*
G01X1770569Y998740D02*
X1764685D01*
G01X1769626Y998583D02*
X1770610D01*
G01X1769665Y998543D02*
X1770571D01*
G01Y996969D02*
X1769665D01*
G01X1770610Y996929D02*
X1769626D01*
G01X1770569Y996772D02*
X1764685D01*
G01Y996732D02*
X1770609D01*
G01Y995630D02*
X1764685D01*
G01X1770569Y995591D02*
X1764685D01*
G01X1769626Y995433D02*
X1770610D01*
G01X1769665Y995394D02*
X1770571D01*
G01Y993819D02*
X1769665D01*
G01X1770610Y993780D02*
X1769626D01*
G01X1770569Y993622D02*
X1764685D01*
G01Y993583D02*
X1770609D01*
G01X1768879Y992480D02*
X1768445D01*
G01X1770609D02*
X1764685D01*
G01X1770569Y992441D02*
X1764685D01*
G01X1769626Y992283D02*
X1770610D01*
G01X1769665Y992244D02*
X1770571D01*
G01Y990669D02*
X1769665D01*
G01X1770610Y990630D02*
X1769626D01*
G01X1770569Y990472D02*
X1764685D01*
G01Y990433D02*
X1770609D01*
G01X1783465Y989469D02*
X1779528D01*
G01X1770609Y989331D02*
X1764685D01*
G01X1770569Y989291D02*
X1764685D01*
G01X1769626Y989134D02*
X1770610D01*
G01X1769665Y989094D02*
X1770571D01*
G01X1784646Y988287D02*
X1780709D01*
G01X1784035Y988012D02*
X1783051D01*
G01X1783053Y987520D02*
X1788386D01*
G01Y987480D02*
X1784038D01*
G01X1771063Y987126D02*
X1767717D01*
G01X1788386Y986142D02*
X1783053D01*
G01X1783051Y985650D02*
X1784035D01*
G01Y983012D02*
X1783051D01*
G01X1783053Y982520D02*
X1788386D01*
G01Y982480D02*
X1784038D01*
G01X1788386Y981142D02*
X1783053D01*
G01X1783051Y980650D02*
X1784035D01*
G01Y978012D02*
X1783051D01*
G01X1783053Y977520D02*
X1788386D01*
G01Y977480D02*
X1784038D01*
G01X1788386Y976142D02*
X1783053D01*
G01X1783051Y975650D02*
X1784035D01*
G01Y973012D02*
X1783051D01*
G01X1783053Y972520D02*
X1788386D01*
G01Y972480D02*
X1784038D01*
G01X1788386Y971142D02*
X1783053D01*
G01X1783051Y970650D02*
X1784035D01*
G01Y968012D02*
X1783051D01*
G01X1783053Y967520D02*
X1788386D01*
G01Y967480D02*
X1784038D01*
G01X1788386Y966142D02*
X1783053D01*
G01X1783051Y965650D02*
X1784035D01*
G01Y963012D02*
X1783051D01*
G01X1783053Y962520D02*
X1788386D01*
G01Y962480D02*
X1784038D01*
G01X1788386Y961142D02*
X1783053D01*
G01X1783051Y960650D02*
X1784035D01*
G01Y958012D02*
X1783051D01*
G01X1783053Y957520D02*
X1788386D01*
G01Y957480D02*
X1784038D01*
G01X1788386Y956142D02*
X1783053D01*
G01X1783051Y955650D02*
X1784035D01*
G01X1779528Y953012D02*
X1774016D01*
G01X1784035Y1020946D02*
X1783051Y1020945D01*
G01Y1017715D02*
X1784006Y1017717D01*
G01X1784035Y1015946D02*
X1783051Y1015945D01*
G01Y1012715D02*
X1784006Y1012717D01*
G01X1784035Y1010946D02*
X1783051Y1010945D01*
G01Y987715D02*
X1784006Y987717D01*
G01X1784035Y985946D02*
X1783051Y985945D01*
G01Y982715D02*
X1784006Y982717D01*
G01X1784035Y980946D02*
X1783051Y980945D01*
G01Y977715D02*
X1784006Y977717D01*
G01X1784035Y975946D02*
X1783051Y975945D01*
G01Y972715D02*
X1784006Y972717D01*
G01X1784035Y970946D02*
X1783051Y970945D01*
G01Y967715D02*
X1784006Y967717D01*
G01X1784035Y965946D02*
X1783051Y965945D01*
G01Y962715D02*
X1784006Y962717D01*
G01X1784035Y960946D02*
X1783051Y960945D01*
G01Y957715D02*
X1784006Y957717D01*
G01X1784035Y955946D02*
X1783051Y955945D01*
G01X1784036Y1081134D02*
X1784035Y1081125D01*
G01X1784037Y1081140D02*
X1784036Y1081134D01*
G01X1784038Y1081142D02*
X1784037Y1081140D01*
G01X1784036Y1076134D02*
X1784035Y1076125D01*
G01X1784037Y1076140D02*
X1784036Y1076134D01*
G01X1784038Y1076142D02*
X1784037Y1076140D01*
G01X1784036Y1071134D02*
X1784035Y1071125D01*
G01X1784037Y1071140D02*
X1784036Y1071134D01*
G01X1784038Y1071142D02*
X1784037Y1071140D01*
G01X1784036Y1066134D02*
X1784035Y1066125D01*
G01X1784037Y1066140D02*
X1784036Y1066134D01*
G01X1784038Y1066142D02*
X1784037Y1066140D01*
G01X1784036Y1061134D02*
X1784035Y1061125D01*
G01X1784037Y1061140D02*
X1784036Y1061134D01*
G01X1784038Y1061142D02*
X1784037Y1061140D01*
G01X1784036Y1056134D02*
X1784035Y1056125D01*
G01X1784037Y1056140D02*
X1784036Y1056134D01*
G01X1784038Y1056142D02*
X1784037Y1056140D01*
G01X1784036Y1051134D02*
X1784035Y1051125D01*
G01X1784037Y1051140D02*
X1784036Y1051134D01*
G01X1784038Y1051142D02*
X1784037Y1051140D01*
G01X1784023Y1052511D02*
X1784034Y1052496D01*
G01X1783998Y1052520D02*
X1784023Y1052511D01*
G01Y1057511D02*
X1784034Y1057496D01*
G01X1783998Y1057520D02*
X1784023Y1057511D01*
G01Y1062511D02*
X1784034Y1062496D01*
G01X1783998Y1062520D02*
X1784023Y1062511D01*
G01Y1067511D02*
X1784034Y1067496D01*
G01X1783998Y1067520D02*
X1784023Y1067511D01*
G01Y1072511D02*
X1784034Y1072496D01*
G01X1783998Y1072520D02*
X1784023Y1072511D01*
G01Y1077511D02*
X1784034Y1077496D01*
G01X1783998Y1077520D02*
X1784023Y1077511D01*
G01Y1082511D02*
X1784034Y1082496D01*
G01X1783998Y1082520D02*
X1784023Y1082511D01*
G01X1783052Y1081140D02*
X1783053Y1081142D01*
G01X1783051Y1081134D02*
X1783052Y1081140D01*
G01X1783051Y1081126D02*
Y1081134D01*
G01X1783052Y1076140D02*
X1783053Y1076142D01*
G01X1783051Y1076134D02*
X1783052Y1076140D01*
G01X1783051Y1076126D02*
Y1076134D01*
G01X1783052Y1071140D02*
X1783053Y1071142D01*
G01X1783051Y1071134D02*
X1783052Y1071140D01*
G01X1783051Y1071126D02*
Y1071134D01*
G01X1783052Y1066140D02*
X1783053Y1066142D01*
G01X1783051Y1066134D02*
X1783052Y1066140D01*
G01X1783051Y1066126D02*
Y1066134D01*
G01X1783052Y1061140D02*
X1783053Y1061142D01*
G01X1783051Y1061134D02*
X1783052Y1061140D01*
G01X1783051Y1061126D02*
Y1061134D01*
G01X1783052Y1056140D02*
X1783053Y1056142D01*
G01X1783051Y1056134D02*
X1783052Y1056140D01*
G01X1783051Y1056126D02*
Y1056134D01*
G01X1783052Y1051140D02*
X1783053Y1051142D01*
G01X1783051Y1051134D02*
X1783052Y1051140D01*
G01X1783051Y1051126D02*
Y1051134D01*
G01X1784036Y1052487D02*
X1784035Y1052494D01*
G01X1784037Y1052482D02*
X1784036Y1052487D01*
G01X1784038Y1052480D02*
X1784037Y1052482D01*
G01X1784036Y1057487D02*
X1784035Y1057494D01*
G01X1784037Y1057482D02*
X1784036Y1057487D01*
G01X1784038Y1057480D02*
X1784037Y1057482D01*
G01X1784036Y1062487D02*
X1784035Y1062494D01*
G01X1784037Y1062482D02*
X1784036Y1062487D01*
G01X1784038Y1062480D02*
X1784037Y1062482D01*
G01X1784002Y1047618D02*
X1784006Y1047717D01*
G01X1783997Y1047546D02*
X1784002Y1047618D01*
G01X1783999Y1047520D02*
X1783997Y1047546D01*
G01X1784002Y1052618D02*
X1784006Y1052717D01*
G01X1783997Y1052546D02*
X1784002Y1052618D01*
G01X1783999Y1052520D02*
X1783997Y1052546D01*
G01X1784002Y1057618D02*
X1784006Y1057717D01*
G01X1783997Y1057546D02*
X1784002Y1057618D01*
G01X1783999Y1057520D02*
X1783997Y1057546D01*
G01X1784002Y1062618D02*
X1784006Y1062717D01*
G01X1783997Y1062546D02*
X1784002Y1062618D01*
G01X1783999Y1062520D02*
X1783997Y1062546D01*
G01X1784002Y1067618D02*
X1784006Y1067717D01*
G01X1783997Y1067546D02*
X1784002Y1067618D01*
G01X1783999Y1067520D02*
X1783997Y1067546D01*
G01X1784002Y1072618D02*
X1784006Y1072717D01*
G01X1783997Y1072546D02*
X1784002Y1072618D01*
G01X1783999Y1072520D02*
X1783997Y1072546D01*
G01X1784002Y1077618D02*
X1784006Y1077717D01*
G01X1783997Y1077546D02*
X1784002Y1077618D01*
G01X1783999Y1077520D02*
X1783997Y1077546D01*
G01X1784002Y1082618D02*
X1784006Y1082717D01*
G01X1783997Y1082546D02*
X1784002Y1082618D01*
G01X1783999Y1082520D02*
X1783997Y1082546D01*
G01X1784036Y1067487D02*
X1784035Y1067494D01*
G01X1784037Y1067482D02*
X1784036Y1067487D01*
G01X1784038Y1067480D02*
X1784037Y1067482D01*
G01X1784036Y1072487D02*
X1784035Y1072494D01*
G01X1784037Y1072482D02*
X1784036Y1072487D01*
G01X1784038Y1072480D02*
X1784037Y1072482D01*
G01X1784036Y1077487D02*
X1784035Y1077494D01*
G01X1784037Y1077482D02*
X1784036Y1077487D01*
G01X1784038Y1077480D02*
X1784037Y1077482D01*
G01X1784036Y1082487D02*
X1784035Y1082494D01*
G01X1784037Y1082482D02*
X1784036Y1082487D01*
G01X1784038Y1082480D02*
X1784037Y1082482D01*
G01X1783051Y1047527D02*
Y1047536D01*
G01X1783052Y1047521D02*
X1783051Y1047527D01*
G01Y1052527D02*
Y1052536D01*
G01X1783052Y1052521D02*
X1783051Y1052527D01*
G01X1783053Y1052520D02*
X1783052Y1052521D01*
G01X1783051Y1057527D02*
Y1057536D01*
G01X1783052Y1057521D02*
X1783051Y1057527D01*
G01X1783053Y1057520D02*
X1783052Y1057521D01*
G01X1783051Y1062527D02*
Y1062536D01*
G01X1783052Y1062521D02*
X1783051Y1062527D01*
G01X1783053Y1062520D02*
X1783052Y1062521D01*
G01X1783051Y1067527D02*
Y1067536D01*
G01X1783052Y1067521D02*
X1783051Y1067527D01*
G01X1783053Y1067520D02*
X1783052Y1067521D01*
G01X1783051Y1072527D02*
Y1072536D01*
G01X1783052Y1072521D02*
X1783051Y1072527D01*
G01X1783053Y1072520D02*
X1783052Y1072521D01*
G01X1783051Y1077527D02*
Y1077536D01*
G01X1783052Y1077521D02*
X1783051Y1077527D01*
G01X1783053Y1077520D02*
X1783052Y1077521D01*
G01X1783051Y1082527D02*
Y1082536D01*
G01X1783052Y1082521D02*
X1783051Y1082527D01*
G01X1783053Y1082520D02*
X1783052Y1082521D01*
G01X1784028Y1047663D02*
X1784035Y1047637D01*
G01X1784018Y1047690D02*
X1784028Y1047663D01*
G01X1784006Y1047717D02*
X1784018Y1047690D01*
G01X1784028Y1052663D02*
X1784035Y1052637D01*
G01X1784018Y1052690D02*
X1784028Y1052663D01*
G01X1784006Y1052717D02*
X1784018Y1052690D01*
G01X1784028Y1057663D02*
X1784035Y1057637D01*
G01X1784018Y1057690D02*
X1784028Y1057663D01*
G01X1784006Y1057717D02*
X1784018Y1057690D01*
G01X1784028Y1062663D02*
X1784035Y1062637D01*
G01X1784018Y1062690D02*
X1784028Y1062663D01*
G01X1784006Y1062717D02*
X1784018Y1062690D01*
G01X1784028Y1067663D02*
X1784035Y1067637D01*
G01X1784018Y1067690D02*
X1784028Y1067663D01*
G01X1784006Y1067717D02*
X1784018Y1067690D01*
G01X1784028Y1072663D02*
X1784035Y1072637D01*
G01X1784018Y1072690D02*
X1784028Y1072663D01*
G01X1784006Y1072717D02*
X1784018Y1072690D01*
G01X1784028Y1077663D02*
X1784035Y1077637D01*
G01X1784018Y1077690D02*
X1784028Y1077663D01*
G01X1784006Y1077717D02*
X1784018Y1077690D01*
G01X1784028Y1082663D02*
X1784035Y1082637D01*
G01X1784018Y1082690D02*
X1784028Y1082663D01*
G01X1784006Y1082717D02*
X1784018Y1082690D01*
G01Y1052515D02*
X1783999Y1052520D01*
G01X1784033Y1052500D02*
X1784018Y1052515D01*
G01X1784038Y1052480D02*
X1784033Y1052500D01*
G01X1784018Y1057515D02*
X1783999Y1057520D01*
G01X1784033Y1057500D02*
X1784018Y1057515D01*
G01X1784038Y1057480D02*
X1784033Y1057500D01*
G01X1784018Y1062515D02*
X1783999Y1062520D01*
G01X1784033Y1062500D02*
X1784018Y1062515D01*
G01X1784038Y1062480D02*
X1784033Y1062500D01*
G01X1784018Y1067515D02*
X1783999Y1067520D01*
G01X1784033Y1067500D02*
X1784018Y1067515D01*
G01X1784038Y1067480D02*
X1784033Y1067500D01*
G01X1784018Y1072515D02*
X1783999Y1072520D01*
G01X1784033Y1072500D02*
X1784018Y1072515D01*
G01X1784038Y1072480D02*
X1784033Y1072500D01*
G01X1784018Y1077515D02*
X1783999Y1077520D01*
G01X1784033Y1077500D02*
X1784018Y1077515D01*
G01X1784038Y1077480D02*
X1784033Y1077500D01*
G01X1784018Y1082515D02*
X1783999Y1082520D01*
G01X1784033Y1082500D02*
X1784018Y1082515D01*
G01X1784038Y1082480D02*
X1784033Y1082500D01*
G01X1781028Y1170224D02*
G03X1814838I16905J-13531D01*
G01X1781028D02*
G03X1814839I16906J-13531D01*
G01X1782480Y1108012D02*
G03X1781890Y1108602I-590J0D01*
G01X1775197D02*
G03X1774606Y1108012I0J-591D01*
G01X1777362Y1106831D02*
G03Y1104862I0J-985D01*
G01X1779724D02*
G03Y1106831I0J984D01*
G01X1789370Y1107421D02*
G03X1787402Y1109390I-1969J0D01*
G01X1769685D02*
G03X1767717Y1107421I0J-1968D01*
G01X1775984Y1098917D02*
G03X1774803Y1097736I0J-1181D01*
G01X1782283D02*
G03X1781102Y1098917I-1181J0D01*
G01X1780433Y1093642D02*
G03I-1890J0D01*
G01X1780906D02*
G03I-2363J0D01*
G01X1777362Y1094232D02*
X1775052Y1098461D01*
G01X1779724Y1092539D02*
X1781028Y1090571D01*
G01X1772835Y1086831D02*
X1774016Y1085650D01*
G01X1767717Y1091673D02*
X1771063Y1088327D01*
G01X1784035Y1047494D02*
X1784036Y1047502D01*
G01X1784035Y1052494D02*
X1784036Y1052502D01*
G01X1784035Y1057494D02*
X1784036Y1057502D01*
G01X1784035Y1062494D02*
X1784036Y1062502D01*
G01X1784035Y1067494D02*
X1784036Y1067502D01*
G01X1784035Y1072494D02*
X1784036Y1072502D01*
G01X1784035Y1077494D02*
X1784036Y1077502D01*
G01X1784035Y1082494D02*
X1784036Y1082502D01*
G01X1789370Y1091673D02*
Y1107421D01*
G01X1788386Y1081142D02*
Y1082520D01*
G01Y1076142D02*
Y1077520D01*
G01Y1071142D02*
Y1072520D01*
G01Y1066142D02*
Y1067520D01*
G01Y1061142D02*
Y1062520D01*
G01Y1056142D02*
Y1057520D01*
G01Y1051142D02*
Y1052520D01*
G01X1785217D02*
Y1051142D01*
G01Y1057520D02*
Y1056142D01*
G01Y1062520D02*
Y1061142D01*
G01Y1067520D02*
Y1066142D01*
G01Y1072520D02*
Y1071142D01*
G01Y1077520D02*
Y1076142D01*
G01Y1082520D02*
Y1081142D01*
G01X1784035Y1080650D02*
Y1083012D01*
G01Y1075650D02*
Y1078012D01*
G01Y1070650D02*
Y1073012D01*
G01Y1065650D02*
Y1068012D01*
G01Y1060650D02*
Y1063012D01*
G01Y1055650D02*
Y1058012D01*
G01Y1050650D02*
Y1053012D01*
G01Y1047494D02*
Y1047637D01*
G01Y1057494D02*
Y1057637D01*
G01Y1052494D02*
Y1052637D01*
G01Y1067494D02*
Y1067637D01*
G01Y1062494D02*
Y1062637D01*
G01Y1077494D02*
Y1077637D01*
G01Y1072494D02*
Y1072637D01*
G01Y1082494D02*
Y1082637D01*
G01X1783051Y1053012D02*
Y1050650D01*
G01Y1058012D02*
Y1055650D01*
G01Y1063012D02*
Y1060650D01*
G01Y1068012D02*
Y1065650D01*
G01Y1073012D02*
Y1070650D01*
G01Y1078012D02*
Y1075650D01*
G01Y1083012D02*
Y1080650D01*
G01X1782480Y1101909D02*
Y1108012D01*
G01X1782283Y1097736D02*
Y1089193D01*
G01X1779724Y1094232D02*
Y1092539D01*
G01X1777362D02*
Y1094232D01*
G01X1774803Y1089193D02*
Y1097736D01*
G01X1774606Y1101909D02*
Y1108012D01*
G01X1767717Y1107421D02*
Y1091673D01*
G01X1782035Y1098461D02*
X1779724Y1094232D01*
G01X1776059Y1090571D02*
X1777362Y1092539D01*
G01X1787402Y1109390D02*
X1769685D01*
G01X1781890Y1108602D02*
X1775197D01*
G01X1779724Y1106831D02*
X1777362D01*
G01Y1104862D02*
X1779724D01*
G01X1782480Y1103484D02*
X1774606D01*
G01X1789370Y1091673D02*
X1786024Y1088327D01*
G01X1779528Y1085650D02*
X1780709Y1086831D01*
G01X1774606Y1101909D02*
X1782480D01*
G01X1789370Y1098957D02*
X1767717D01*
G01X1775984Y1098917D02*
X1781102D01*
G01X1777362Y1094232D02*
X1779724D01*
G01X1777362Y1092539D02*
X1779724D01*
G01X1771063Y1090571D02*
X1785433D01*
G01X1771063Y1089193D02*
X1774803D01*
G01X1785433D02*
X1782283D01*
G01X1771063Y1088327D02*
X1786024D01*
G01X1772835Y1086831D02*
X1780709D01*
G01X1774016Y1085650D02*
X1779528D01*
G01X1784035Y1083012D02*
X1783051D01*
G01X1783053Y1082520D02*
X1788386D01*
G01Y1082480D02*
X1784038D01*
G01X1788386Y1081142D02*
X1783053D01*
G01X1783051Y1080650D02*
X1784035D01*
G01Y1078012D02*
X1783051D01*
G01X1783053Y1077520D02*
X1788386D01*
G01Y1077480D02*
X1784038D01*
G01X1788386Y1076142D02*
X1783053D01*
G01X1783051Y1075650D02*
X1784035D01*
G01Y1073012D02*
X1783051D01*
G01X1783053Y1072520D02*
X1788386D01*
G01Y1072480D02*
X1784038D01*
G01X1788386Y1071142D02*
X1783053D01*
G01X1783051Y1070650D02*
X1784035D01*
G01Y1068012D02*
X1783051D01*
G01X1783053Y1067520D02*
X1788386D01*
G01Y1067480D02*
X1784038D01*
G01X1788386Y1066142D02*
X1783053D01*
G01X1783051Y1065650D02*
X1784035D01*
G01Y1063012D02*
X1783051D01*
G01X1783053Y1062520D02*
X1788386D01*
G01Y1062480D02*
X1784038D01*
G01X1788386Y1061142D02*
X1783053D01*
G01X1783051Y1060650D02*
X1784035D01*
G01Y1058012D02*
X1783051D01*
G01X1783053Y1057520D02*
X1788386D01*
G01Y1057480D02*
X1784038D01*
G01X1788386Y1056142D02*
X1783053D01*
G01X1783051Y1055650D02*
X1784035D01*
G01Y1053012D02*
X1783051D01*
G01X1783053Y1052520D02*
X1788386D01*
G01Y1052480D02*
X1784038D01*
G01X1788386Y1051142D02*
X1783053D01*
G01X1783051Y1050650D02*
X1784035D01*
G01Y1048012D02*
X1783051D01*
G01X1783053Y1047520D02*
X1788386D01*
G01Y1047480D02*
X1784038D01*
G01X1783051Y1082715D02*
X1784006Y1082717D01*
G01X1784035Y1080946D02*
X1783051Y1080945D01*
G01Y1077715D02*
X1784006Y1077717D01*
G01X1784035Y1075946D02*
X1783051Y1075945D01*
G01Y1072715D02*
X1784006Y1072717D01*
G01X1784035Y1070946D02*
X1783051Y1070945D01*
G01Y1067715D02*
X1784006Y1067717D01*
G01X1784035Y1065946D02*
X1783051Y1065945D01*
G01Y1062715D02*
X1784006Y1062717D01*
G01X1784035Y1060946D02*
X1783051Y1060945D01*
G01Y1057715D02*
X1784006Y1057717D01*
G01X1784035Y1055946D02*
X1783051Y1055945D01*
G01Y1052715D02*
X1784006Y1052717D01*
G01X1784035Y1050946D02*
X1783051Y1050945D01*
G01Y1047715D02*
X1784006Y1047717D01*
G01X1807914Y1183355D02*
G03X1814838Y1170224I37662J11468D01*
G01X1807914Y1183355D02*
G03X1787953I-9980J-3040D01*
G01X1781028Y1170224D02*
G03X1787953Y1183355I-30737J24602D01*
G01X1807913D02*
G03X1787953I-9980J-3040D01*
G01X1807913D02*
G03X1814839Y1170224I37661J11473D01*
G01X1781028D02*
G03X1787953Y1183355I-30737J24602D01*
G01X1761417Y1497059D02*
G03Y1494280I0J-1389D01*
G01Y1498764D02*
G03Y1492575I0J-3094D01*
G01X1760157Y1499606D02*
G03Y1491732I1260J-3937D01*
G01X1757283Y1499606D02*
G03Y1491732I4134J-3937D01*
G01X1748819Y1523622D02*
X1782677D01*
G01Y1521654D02*
X1779134D01*
G01X1761417Y1520210D02*
X1744882D01*
G01X1782677Y1492913D02*
Y1526772D01*
G01X1780984Y1519685D02*
Y1521604D01*
G01X1779134Y1526772D02*
Y1521654D01*
G01X1772047Y1510954D02*
Y1471260D01*
G01X1768504Y1516929D02*
Y1485827D01*
G01X1767283Y1523622D02*
Y1471260D01*
G01X1764567Y1485827D02*
Y1512992D01*
G01X1763780Y1523622D02*
Y1471260D01*
G01X1763484Y1443209D02*
Y1471260D01*
G01Y1505512D02*
Y1485827D01*
G01X1761417Y1498764D02*
Y1497059D01*
G01Y1510954D02*
Y1526772D01*
G01Y1491732D02*
Y1499606D01*
G01Y1494279D02*
Y1492574D01*
G01X1759350Y1471260D02*
Y1443209D01*
G01Y1505512D02*
Y1485827D01*
G01X1758268D02*
Y1512992D01*
G01X1754331Y1485827D02*
Y1512992D01*
G01X1751969Y1485827D02*
Y1512992D01*
G01X1748819Y1523622D02*
Y1509843D01*
G01X1748031Y1485827D02*
Y1512992D01*
G01X1746949Y1443209D02*
Y1471260D01*
G01Y1505512D02*
Y1485827D01*
G01X1744882Y1526772D02*
Y1505210D01*
G01X1742815Y1471260D02*
Y1443209D01*
G01Y1505512D02*
Y1485827D01*
G01X1741732D02*
Y1512992D01*
G01X1740945Y1505210D02*
Y1523622D01*
G01X1737795Y1485827D02*
Y1512992D01*
G01X1735433Y1485827D02*
Y1512992D01*
G01X1731496Y1485827D02*
Y1512992D01*
G01X1730413Y1443209D02*
Y1471260D01*
G01Y1505512D02*
Y1485827D01*
G01X1730315Y1523622D02*
Y1505210D01*
G01X1726378D02*
Y1523622D01*
G01X1726280Y1471260D02*
Y1443209D01*
G01Y1505512D02*
Y1485827D01*
G01X1725197D02*
Y1512992D01*
G01X1748819Y1510954D02*
X1772047D01*
G01X1730315D02*
X1740945D01*
G01X1759350Y1505512D02*
X1763484D01*
G01X1742815D02*
X1746949D01*
G01X1726280D02*
X1730413D01*
G01X1740945Y1505210D02*
X1744882D01*
G01X1726378D02*
X1730315D01*
G01X1761417Y1499606D02*
X1757283D01*
G01X1772047Y1492913D02*
X1782677D01*
G01X1757283Y1491732D02*
X1761417D01*
G01X1751969Y1485827D02*
X1737795D01*
G01X1768504D02*
X1754331D01*
G01X1730413Y1469783D02*
X1726280D01*
G01X1746949D02*
X1742815D01*
G01X1763484D02*
X1759350D01*
G01X1730413Y1468996D02*
X1726280D01*
G01X1746949D02*
X1742815D01*
G01X1763484D02*
X1759350D01*
G01X1730413Y1464862D02*
X1726280D01*
G01X1746949D02*
X1742815D01*
G01X1763484D02*
X1759350D01*
G01X1730413Y1448130D02*
X1726280D01*
G01X1746949D02*
X1742815D01*
G01X1763484D02*
X1759350D01*
G01X1730413Y1447343D02*
X1726280D01*
G01X1746949D02*
X1742815D01*
G01X1763484D02*
X1759350D01*
G01X1730413Y1443209D02*
X1726280D01*
G01X1746949D02*
X1742815D01*
G01X1763484D02*
X1759350D01*
G01X1782677Y1523622D02*
X1772047Y1510954D01*
G01X1779134Y1526772D02*
X1768504Y1516929D01*
G01X1779134Y1521654D02*
X1768504Y1516929D01*
G01X1796282Y1808346D02*
Y1789409D01*
G01X1893841Y84941D02*
X1893836Y84921D01*
G01X1893856Y84955D02*
X1893841Y84941D01*
G01X1893876Y84961D02*
X1893856Y84955D01*
G01X1893841Y88091D02*
X1893836Y88071D01*
G01X1893856Y88105D02*
X1893841Y88091D01*
G01X1893876Y88110D02*
X1893856Y88105D01*
G01X1894816Y83799D02*
X1894821Y83819D01*
G01X1894802Y83785D02*
X1894816Y83799D01*
G01X1894782Y83780D02*
X1894802Y83785D01*
G01X1894816Y86949D02*
X1894821Y86969D01*
G01X1894802Y86934D02*
X1894816Y86949D01*
G01X1894782Y86929D02*
X1894802Y86934D01*
G01X1893841Y91240D02*
X1893836Y91220D01*
G01X1893856Y91254D02*
X1893841Y91240D01*
G01X1893876Y91260D02*
X1893856Y91254D01*
G01X1894816Y90098D02*
X1894821Y90118D01*
G01X1894802Y90084D02*
X1894816Y90098D01*
G01X1894782Y90079D02*
X1894802Y90084D01*
G01X1894816Y93248D02*
X1894821Y93268D01*
G01X1894802Y93233D02*
X1894816Y93248D01*
G01X1894782Y93228D02*
X1894802Y93233D01*
G01X1894800Y83772D02*
X1894804Y83774D01*
G01X1894797Y83770D02*
X1894800Y83772D01*
G01X1894794Y83770D02*
X1894797D01*
G01X1894791Y83769D02*
X1894794Y83770D01*
G01X1894787Y83769D02*
X1894791D01*
G01X1894783Y83768D02*
X1894787Y83769D01*
G01X1893861Y84968D02*
X1893858Y84967D01*
G01X1893864Y84969D02*
X1893861Y84968D01*
G01X1893868Y84970D02*
X1893864Y84969D01*
G01X1893871Y84971D02*
X1893868Y84970D01*
G01X1893874Y84972D02*
X1893871Y84971D01*
G01X1893878Y84972D02*
X1893874D01*
G01X1894800Y86921D02*
X1894804Y86923D01*
G01X1894797Y86920D02*
X1894800Y86921D01*
G01X1894794Y86919D02*
X1894797Y86920D01*
G01X1894791Y86919D02*
X1894794D01*
G01X1894787Y86918D02*
X1894791Y86919D01*
G01X1894783Y86918D02*
X1894787D01*
G01X1893861Y88118D02*
X1893858Y88116D01*
G01X1893864Y88119D02*
X1893861Y88118D01*
G01X1893868Y88120D02*
X1893864Y88119D01*
G01X1893871Y88121D02*
X1893868Y88120D01*
G01X1893874Y88121D02*
X1893871D01*
G01X1893878D02*
X1893874D01*
G01X1894800Y90071D02*
X1894804Y90073D01*
G01X1894797Y90070D02*
X1894800Y90071D01*
G01X1894794Y90069D02*
X1894797Y90070D01*
G01X1894791Y90068D02*
X1894794Y90069D01*
G01X1894787Y90068D02*
X1894791D01*
G01X1894783Y90067D02*
X1894787Y90068D01*
G01X1893861Y91267D02*
X1893858Y91266D01*
G01X1893864Y91269D02*
X1893861Y91267D01*
G01X1893868Y91270D02*
X1893864Y91269D01*
G01X1893871Y91270D02*
X1893868D01*
G01X1893874Y91271D02*
X1893871Y91270D01*
G01X1893878Y91271D02*
X1893874D01*
G01X1894800Y93220D02*
X1894804Y93222D01*
G01X1894797Y93219D02*
X1894800Y93220D01*
G01X1894794Y93219D02*
X1894797D01*
G01X1894791Y93218D02*
X1894794Y93219D01*
G01X1894787Y93217D02*
X1894791Y93218D01*
G01X1894783Y93217D02*
X1894787D01*
G01X1894813Y84959D02*
X1894817Y84954D01*
G01X1894809Y84963D02*
X1894813Y84959D01*
G01X1894803Y84967D02*
X1894809Y84963D01*
G01X1894797Y84970D02*
X1894803Y84967D01*
G01X1894790Y84971D02*
X1894797Y84970D01*
G01X1894783Y84972D02*
X1894790Y84971D01*
G01X1894813Y88109D02*
X1894817Y88103D01*
G01X1894809Y88113D02*
X1894813Y88109D01*
G01X1894803Y88117D02*
X1894809Y88113D01*
G01X1894797Y88119D02*
X1894803Y88117D01*
G01X1894790Y88121D02*
X1894797Y88119D01*
G01X1894783Y88121D02*
X1894790D01*
G01X1894813Y91258D02*
X1894817Y91253D01*
G01X1894809Y91263D02*
X1894813Y91258D01*
G01X1894803Y91266D02*
X1894809Y91263D01*
G01X1894797Y91269D02*
X1894803Y91266D01*
G01X1894790Y91270D02*
X1894797Y91269D01*
G01X1894783Y91271D02*
X1894790Y91270D01*
G01X1893839Y83798D02*
Y83805D01*
G01X1893842Y83791D02*
X1893839Y83798D01*
G01X1893845Y83785D02*
X1893842Y83791D01*
G01X1893850Y83779D02*
X1893845Y83785D01*
G01X1893856Y83774D02*
X1893850Y83779D01*
G01X1893863Y83771D02*
X1893856Y83774D01*
G01X1893870Y83769D02*
X1893863Y83771D01*
G01X1893878Y83768D02*
X1893870Y83769D01*
G01X1893839Y86948D02*
Y86955D01*
G01X1893842Y86941D02*
X1893839Y86948D01*
G01X1893845Y86934D02*
X1893842Y86941D01*
G01X1893850Y86929D02*
X1893845Y86934D01*
G01X1893856Y86924D02*
X1893850Y86929D01*
G01X1893863Y86920D02*
X1893856Y86924D01*
G01X1893870Y86919D02*
X1893863Y86920D01*
G01X1893878Y86918D02*
X1893870Y86919D01*
G01X1893839Y90097D02*
Y90104D01*
G01X1893842Y90090D02*
X1893839Y90097D01*
G01X1893845Y90084D02*
X1893842Y90090D01*
G01X1893850Y90078D02*
X1893845Y90084D01*
G01X1893856Y90074D02*
X1893850Y90078D01*
G01X1893863Y90070D02*
X1893856Y90074D01*
G01X1893870Y90068D02*
X1893863Y90070D01*
G01X1893878Y90067D02*
X1893870Y90068D01*
G01X1893839Y93247D02*
Y93254D01*
G01X1893842Y93240D02*
X1893839Y93247D01*
G01X1893845Y93233D02*
X1893842Y93240D01*
G01X1893850Y93228D02*
X1893845Y93233D01*
G01X1893856Y93223D02*
X1893850Y93228D01*
G01X1893863Y93220D02*
X1893856Y93223D01*
G01X1893870Y93218D02*
X1893863Y93220D01*
G01X1893878Y93217D02*
X1893870Y93218D01*
G01X1894793Y84959D02*
X1894802Y84955D01*
G01X1894782Y84961D02*
X1894793Y84959D01*
G01Y88109D02*
X1894802Y88105D01*
G01X1894782Y88110D02*
X1894793Y88109D01*
G01Y91258D02*
X1894802Y91254D01*
G01X1894782Y91260D02*
X1894793Y91258D01*
G01X1893839Y86959D02*
Y86955D01*
G01X1893840Y86952D02*
X1893839Y86959D01*
G01X1893852Y86937D02*
X1893840Y86952D01*
G01X1893877Y86929D02*
X1893852Y86937D01*
G01X1893839Y90108D02*
Y90104D01*
G01X1893840Y90102D02*
X1893839Y90108D01*
G01X1893852Y90087D02*
X1893840Y90102D01*
G01X1893876Y90079D02*
X1893852Y90087D01*
G01X1893839Y83809D02*
Y83806D01*
G01X1893840Y83803D02*
X1893839Y83809D01*
G01X1893852Y83788D02*
X1893840Y83803D01*
G01X1893876Y83780D02*
X1893852Y83788D01*
G01X1908235Y51999D02*
X1908246Y51984D01*
G01X1908211Y52008D02*
X1908235Y51999D01*
G01Y56999D02*
X1908246Y56984D01*
G01X1908211Y57008D02*
X1908235Y56999D01*
G01Y61999D02*
X1908246Y61984D01*
G01X1908211Y62008D02*
X1908235Y61999D01*
G01Y66999D02*
X1908246Y66984D01*
G01X1908211Y67008D02*
X1908235Y66999D01*
G01Y71999D02*
X1908246Y71984D01*
G01X1908211Y72008D02*
X1908235Y71999D01*
G01Y76999D02*
X1908246Y76984D01*
G01X1908211Y77008D02*
X1908235Y76999D01*
G01Y81999D02*
X1908246Y81984D01*
G01X1908211Y82008D02*
X1908235Y81999D01*
G01X1893839Y93258D02*
Y93254D01*
G01X1893840Y93252D02*
X1893839Y93258D01*
G01X1893850Y93238D02*
X1893840Y93252D01*
G01X1893873Y93228D02*
X1893850Y93238D01*
G01X1894791Y91259D02*
X1894782Y91260D01*
G01X1894800Y91256D02*
X1894791Y91259D01*
G01X1894808Y91250D02*
X1894800Y91256D01*
G01X1894791Y84959D02*
X1894782Y84961D01*
G01X1894800Y84956D02*
X1894791Y84959D01*
G01X1894808Y84951D02*
X1894800Y84956D01*
G01X1894791Y88109D02*
X1894782Y88110D01*
G01X1894800Y88106D02*
X1894791Y88109D01*
G01X1894808Y88100D02*
X1894800Y88106D01*
G01X1893878Y83774D02*
Y83768D01*
G01X1893877Y83778D02*
X1893878Y83774D01*
G01X1893876Y83780D02*
X1893877Y83778D01*
G01X1893878Y86924D02*
Y86918D01*
G01X1893877Y86928D02*
X1893878Y86924D01*
G01X1893876Y86929D02*
X1893877Y86928D01*
G01X1893878Y90074D02*
Y90067D01*
G01X1893877Y90078D02*
X1893878Y90074D01*
G01X1893876Y90079D02*
X1893877Y90078D01*
G01X1893878Y93223D02*
Y93217D01*
G01X1893877Y93227D02*
X1893878Y93223D01*
G01X1893876Y93228D02*
X1893877Y93227D01*
G01X1908248Y51975D02*
Y51982D01*
G01X1908249Y51970D02*
X1908248Y51975D01*
G01X1908250Y51969D02*
X1908249Y51970D01*
G01X1908248Y56975D02*
Y56982D01*
G01X1908249Y56970D02*
X1908248Y56975D01*
G01X1908250Y56969D02*
X1908249Y56970D01*
G01X1908248Y61975D02*
Y61982D01*
G01X1908249Y61970D02*
X1908248Y61975D01*
G01X1908250Y61969D02*
X1908249Y61970D01*
G01X1908248Y66975D02*
Y66982D01*
G01X1908249Y66970D02*
X1908248Y66975D01*
G01X1908250Y66969D02*
X1908249Y66970D01*
G01X1908248Y71975D02*
Y71982D01*
G01X1908249Y71970D02*
X1908248Y71975D01*
G01X1908250Y71969D02*
X1908249Y71970D01*
G01X1908248Y76975D02*
Y76982D01*
G01X1908249Y76970D02*
X1908248Y76975D01*
G01X1908250Y76969D02*
X1908249Y76970D01*
G01X1908248Y81975D02*
Y81982D01*
G01X1908249Y81970D02*
X1908248Y81975D01*
G01X1908250Y81969D02*
X1908249Y81970D01*
G01X1893861Y86931D02*
X1893876Y86929D01*
G01X1893850Y86939D02*
X1893861Y86931D01*
G01X1893838Y86957D02*
X1893850Y86939D01*
G01X1893861Y90081D02*
X1893876Y90079D01*
G01X1893849Y90089D02*
X1893861Y90081D01*
G01X1893837Y90109D02*
X1893849Y90089D01*
G01X1894823Y83813D02*
Y83805D01*
G01X1894822Y83817D02*
X1894823Y83813D01*
G01X1894821Y83819D02*
X1894822Y83817D01*
G01X1894823Y86963D02*
Y86955D01*
G01X1894822Y86967D02*
X1894823Y86963D01*
G01X1894821Y86969D02*
X1894822Y86967D01*
G01X1894823Y90112D02*
Y90104D01*
G01X1894822Y90117D02*
X1894823Y90112D01*
G01X1894821Y90118D02*
X1894822Y90117D01*
G01X1894823Y93262D02*
Y93254D01*
G01X1894822Y93266D02*
X1894823Y93262D01*
G01X1894821Y93268D02*
X1894822Y93266D01*
G01X1893861Y83782D02*
X1893876Y83780D01*
G01X1893848Y83791D02*
X1893861Y83782D01*
G01X1893837Y83811D02*
X1893848Y83791D01*
G01X1894822Y84941D02*
X1894823Y84935D01*
G01X1894820Y84948D02*
X1894822Y84941D01*
G01X1894817Y84954D02*
X1894820Y84948D01*
G01X1894822Y88091D02*
X1894823Y88084D01*
G01X1894820Y88097D02*
X1894822Y88091D01*
G01X1894817Y88103D02*
X1894820Y88097D01*
G01X1894822Y91241D02*
X1894823Y91234D01*
G01X1894820Y91247D02*
X1894822Y91241D01*
G01X1894817Y91253D02*
X1894820Y91247D01*
G01X1894784Y83774D02*
Y83768D01*
G01X1894783Y83778D02*
X1894784Y83774D01*
G01X1894782Y83780D02*
X1894783Y83778D01*
G01X1894784Y86924D02*
Y86918D01*
G01X1894783Y86928D02*
X1894784Y86924D01*
G01X1894782Y86929D02*
X1894783Y86928D01*
G01X1894784Y90074D02*
Y90067D01*
G01X1894783Y90077D02*
X1894784Y90074D01*
G01X1894782Y90079D02*
X1894783Y90077D01*
G01X1894784Y93223D02*
Y93217D01*
G01X1894783Y93227D02*
X1894784Y93223D01*
G01X1894782Y93228D02*
X1894783Y93227D01*
G01X1907264Y52015D02*
Y52024D01*
G01X1907265Y52009D02*
X1907264Y52015D01*
G01X1907265Y52008D02*
Y52009D01*
G01X1907264Y57015D02*
Y57024D01*
G01X1907265Y57009D02*
X1907264Y57015D01*
G01X1907265Y57008D02*
Y57009D01*
G01X1907264Y62015D02*
Y62024D01*
G01X1907265Y62009D02*
X1907264Y62015D01*
G01X1907265Y62008D02*
Y62009D01*
G01X1907264Y67015D02*
Y67024D01*
G01X1907265Y67009D02*
X1907264Y67015D01*
G01X1907265Y67008D02*
Y67009D01*
G01X1907264Y72015D02*
Y72024D01*
G01X1907265Y72009D02*
X1907264Y72015D01*
G01X1907265Y72008D02*
Y72009D01*
G01X1907264Y77015D02*
Y77024D01*
G01X1907265Y77009D02*
X1907264Y77015D01*
G01X1907265Y77008D02*
Y77009D01*
G01X1907264Y82015D02*
Y82024D01*
G01X1907265Y82009D02*
X1907264Y82015D01*
G01X1907265Y82008D02*
Y82009D01*
G01X1908240Y52152D02*
X1908248Y52125D01*
G01X1908230Y52178D02*
X1908240Y52152D01*
G01X1908219Y52205D02*
X1908230Y52178D01*
G01X1908240Y57152D02*
X1908248Y57125D01*
G01X1908230Y57178D02*
X1908240Y57152D01*
G01X1908219Y57205D02*
X1908230Y57178D01*
G01X1908240Y62152D02*
X1908248Y62125D01*
G01X1908230Y62178D02*
X1908240Y62152D01*
G01X1908219Y62205D02*
X1908230Y62178D01*
G01X1908240Y67152D02*
X1908248Y67125D01*
G01X1908230Y67178D02*
X1908240Y67152D01*
G01X1908219Y67205D02*
X1908230Y67178D01*
G01X1908240Y72152D02*
X1908248Y72125D01*
G01X1908230Y72178D02*
X1908240Y72152D01*
G01X1908219Y72205D02*
X1908230Y72178D01*
G01X1908240Y77152D02*
X1908248Y77125D01*
G01X1908230Y77178D02*
X1908240Y77152D01*
G01X1908219Y77205D02*
X1908230Y77178D01*
G01X1908240Y82152D02*
X1908248Y82125D01*
G01X1908230Y82178D02*
X1908240Y82152D01*
G01X1908219Y82205D02*
X1908230Y82178D01*
G01X1893856Y93233D02*
X1893876Y93228D01*
G01X1893843Y93246D02*
X1893856Y93233D01*
G01X1893836Y93263D02*
X1893843Y93246D01*
G01X1908231Y52003D02*
X1908211Y52008D01*
G01X1908245Y51988D02*
X1908231Y52003D01*
G01X1908250Y51969D02*
X1908245Y51988D01*
G01X1908231Y57003D02*
X1908211Y57008D01*
G01X1908245Y56988D02*
X1908231Y57003D01*
G01X1908250Y56969D02*
X1908245Y56988D01*
G01X1908231Y62003D02*
X1908211Y62008D01*
G01X1908245Y61988D02*
X1908231Y62003D01*
G01X1908250Y61969D02*
X1908245Y61988D01*
G01X1908231Y67003D02*
X1908211Y67008D01*
G01X1908245Y66988D02*
X1908231Y67003D01*
G01X1908250Y66969D02*
X1908245Y66988D01*
G01X1908231Y72003D02*
X1908211Y72008D01*
G01X1908245Y71988D02*
X1908231Y72003D01*
G01X1908250Y71969D02*
X1908245Y71988D01*
G01X1908231Y77003D02*
X1908211Y77008D01*
G01X1908245Y76988D02*
X1908231Y77003D01*
G01X1908250Y76969D02*
X1908245Y76988D01*
G01X1908231Y82003D02*
X1908211Y82008D01*
G01X1908245Y81988D02*
X1908231Y82003D01*
G01X1908250Y81969D02*
X1908245Y81988D01*
G01X1894815Y91242D02*
X1894808Y91250D01*
G01X1894820Y91231D02*
X1894815Y91242D01*
G01X1894822Y91220D02*
X1894820Y91231D01*
G01X1894815Y84943D02*
X1894808Y84951D01*
G01X1894820Y84932D02*
X1894815Y84943D01*
G01X1894822Y84921D02*
X1894820Y84932D01*
G01X1894815Y88092D02*
X1894808Y88100D01*
G01X1894820Y88082D02*
X1894815Y88092D01*
G01X1894822Y88071D02*
X1894820Y88082D01*
G01X1908215Y52106D02*
X1908219Y52205D01*
G01X1908209Y52034D02*
X1908215Y52106D01*
G01X1908211Y52008D02*
X1908209Y52034D01*
G01X1908215Y57106D02*
X1908219Y57205D01*
G01X1908209Y57034D02*
X1908215Y57106D01*
G01X1908211Y57008D02*
X1908209Y57034D01*
G01X1908215Y62106D02*
X1908219Y62205D01*
G01X1908209Y62034D02*
X1908215Y62106D01*
G01X1908211Y62008D02*
X1908209Y62034D01*
G01X1908215Y67106D02*
X1908219Y67205D01*
G01X1908209Y67034D02*
X1908215Y67106D01*
G01X1908211Y67008D02*
X1908209Y67034D01*
G01X1908215Y72106D02*
X1908219Y72205D01*
G01X1908209Y72034D02*
X1908215Y72106D01*
G01X1908211Y72008D02*
X1908209Y72034D01*
G01X1908215Y77106D02*
X1908219Y77205D01*
G01X1908209Y77034D02*
X1908215Y77106D01*
G01X1908211Y77008D02*
X1908209Y77034D01*
G01X1908215Y82106D02*
X1908219Y82205D01*
G01X1908209Y82034D02*
X1908215Y82106D01*
G01X1908211Y82008D02*
X1908209Y82034D01*
G01X1893879Y91444D02*
X1893878Y91457D01*
G01X1893876Y91431D02*
X1893879Y91444D01*
G01X1893876Y91417D02*
Y91431D01*
G01X1893879Y88294D02*
X1893878Y88307D01*
G01X1893876Y88281D02*
X1893879Y88294D01*
G01X1893876Y88268D02*
Y88281D01*
G01X1893879Y85145D02*
X1893878Y85157D01*
G01X1893876Y85132D02*
X1893879Y85145D01*
G01X1893876Y85118D02*
Y85132D01*
G01X1907265Y80628D02*
Y80630D01*
G01X1907264Y80622D02*
X1907265Y80628D01*
G01X1907264Y80614D02*
Y80622D01*
G01X1907265Y75628D02*
Y75630D01*
G01X1907264Y75622D02*
X1907265Y75628D01*
G01X1907264Y75614D02*
Y75622D01*
G01X1907265Y70628D02*
Y70630D01*
G01X1907264Y70622D02*
X1907265Y70628D01*
G01X1907264Y70614D02*
Y70622D01*
G01X1907265Y65628D02*
Y65630D01*
G01X1907264Y65622D02*
X1907265Y65628D01*
G01X1907264Y65614D02*
Y65622D01*
G01X1907265Y60628D02*
Y60630D01*
G01X1907264Y60622D02*
X1907265Y60628D01*
G01X1907264Y60614D02*
Y60622D01*
G01X1907265Y55628D02*
Y55630D01*
G01X1907264Y55622D02*
X1907265Y55628D01*
G01X1907264Y55614D02*
Y55622D01*
G01X1907265Y50628D02*
Y50630D01*
G01X1907264Y50622D02*
X1907265Y50628D01*
G01X1907264Y50614D02*
Y50622D01*
G01X1893876Y93057D02*
X1893874Y93070D01*
G01X1893879Y93044D02*
X1893876Y93057D01*
G01X1893878Y93031D02*
X1893879Y93044D01*
G01X1893876Y89907D02*
X1893874Y89921D01*
G01X1893879Y89894D02*
X1893876Y89907D01*
G01X1893878Y89882D02*
X1893879Y89894D01*
G01X1893876Y86757D02*
X1893874Y86771D01*
G01X1893879Y86745D02*
X1893876Y86757D01*
G01X1893878Y86732D02*
X1893879Y86745D01*
G01X1893876Y83608D02*
X1893874Y83622D01*
G01X1893879Y83595D02*
X1893876Y83608D01*
G01X1893878Y83583D02*
X1893879Y83595D01*
G01X1894786Y91431D02*
X1894787Y91417D01*
G01X1894783Y91444D02*
X1894786Y91431D01*
G01X1894783Y91457D02*
Y91444D01*
G01X1894786Y88281D02*
X1894787Y88268D01*
G01X1894783Y88294D02*
X1894786Y88281D01*
G01X1894783Y88307D02*
Y88294D01*
G01X1894786Y85132D02*
X1894787Y85118D01*
G01X1894783Y85145D02*
X1894786Y85132D01*
G01X1894783Y85157D02*
Y85145D01*
G01X1893838Y90112D02*
X1893839Y90105D01*
G01X1893837Y90117D02*
X1893838Y90112D01*
G01X1893837Y90109D02*
Y90117D01*
G01X1894783Y93044D02*
Y93031D01*
G01X1894785Y93057D02*
X1894783Y93044D01*
G01X1894787Y93070D02*
X1894785Y93057D01*
G01X1894783Y89894D02*
Y89882D01*
G01X1894785Y89907D02*
X1894783Y89894D01*
G01X1894787Y89921D02*
X1894785Y89907D01*
G01X1894783Y86745D02*
Y86732D01*
G01X1894785Y86757D02*
X1894783Y86745D01*
G01X1894787Y86771D02*
X1894785Y86757D01*
G01X1894783Y83595D02*
Y83583D01*
G01X1894785Y83608D02*
X1894783Y83595D01*
G01X1894787Y83622D02*
X1894785Y83608D01*
G01X1893838Y83813D02*
X1893839Y83806D01*
G01X1893837Y83817D02*
X1893838Y83813D01*
G01X1893837Y83811D02*
Y83817D01*
G01X1893852Y91251D02*
X1893876Y91260D01*
G01X1893841Y91237D02*
X1893852Y91251D01*
G01X1893839Y91230D02*
X1893841Y91237D01*
G01X1893852Y88102D02*
X1893876Y88110D01*
G01X1893841Y88087D02*
X1893852Y88102D01*
G01X1893839Y88080D02*
X1893841Y88087D01*
G01X1893852Y84952D02*
X1893876Y84961D01*
G01X1893841Y84937D02*
X1893852Y84952D01*
G01X1893839Y84931D02*
X1893841Y84937D01*
G01X1893839Y91240D02*
Y91234D01*
G01X1893841Y91246D02*
X1893839Y91240D01*
G01X1893844Y91252D02*
X1893841Y91246D01*
G01X1893848Y91257D02*
X1893844Y91252D01*
G01X1893852Y91262D02*
X1893848Y91257D01*
G01X1893858Y91266D02*
X1893852Y91262D01*
G01X1894794Y93230D02*
X1894782Y93228D01*
G01X1894804Y93235D02*
X1894794Y93230D01*
G01Y90081D02*
X1894782Y90079D01*
G01X1894804Y90085D02*
X1894794Y90081D01*
G01Y86931D02*
X1894782Y86929D01*
G01X1894804Y86936D02*
X1894794Y86931D01*
G01Y83781D02*
X1894782Y83780D01*
G01X1894804Y83786D02*
X1894794Y83781D01*
G01X1894823Y91227D02*
Y91234D01*
G01X1894822Y91222D02*
X1894823Y91227D01*
G01X1894822Y91220D02*
Y91222D01*
G01X1894823Y88077D02*
Y88084D01*
G01X1894822Y88072D02*
X1894823Y88077D01*
G01X1894822Y88071D02*
Y88072D01*
G01X1894823Y84928D02*
Y84935D01*
G01X1894822Y84923D02*
X1894823Y84928D01*
G01X1894822Y84921D02*
Y84923D01*
G01X1893838Y93262D02*
X1893839Y93254D01*
G01X1893837Y93266D02*
X1893838Y93262D01*
G01X1893836Y93263D02*
X1893837Y93266D01*
G01X1893838Y86963D02*
X1893839Y86955D01*
G01X1893837Y86967D02*
X1893838Y86963D01*
G01X1893836Y86965D02*
X1893837Y86967D01*
G01X1894783Y91265D02*
Y91271D01*
G01Y91261D02*
Y91265D01*
G01X1894782Y91260D02*
X1894783Y91261D01*
G01Y88115D02*
Y88121D01*
G01Y88111D02*
Y88115D01*
G01X1894782Y88110D02*
X1894783Y88111D01*
G01Y84966D02*
Y84972D01*
G01Y84962D02*
Y84966D01*
G01X1894782Y84961D02*
X1894783Y84962D01*
G01X1908248Y80622D02*
Y80613D01*
G01X1908249Y80628D02*
X1908248Y80622D01*
G01X1908251Y80630D02*
X1908249Y80628D01*
G01X1908248Y75622D02*
Y75613D01*
G01X1908249Y75628D02*
X1908248Y75622D01*
G01X1908251Y75630D02*
X1908249Y75628D01*
G01X1908248Y70622D02*
Y70613D01*
G01X1908249Y70628D02*
X1908248Y70622D01*
G01X1908251Y70630D02*
X1908249Y70628D01*
G01X1908248Y65622D02*
Y65613D01*
G01X1908249Y65628D02*
X1908248Y65622D01*
G01X1908251Y65630D02*
X1908249Y65628D01*
G01X1908248Y60622D02*
Y60613D01*
G01X1908249Y60628D02*
X1908248Y60622D01*
G01X1908251Y60630D02*
X1908249Y60628D01*
G01X1908248Y55622D02*
Y55613D01*
G01X1908249Y55628D02*
X1908248Y55622D01*
G01X1908251Y55630D02*
X1908249Y55628D01*
G01X1908248Y50622D02*
Y50613D01*
G01X1908249Y50628D02*
X1908248Y50622D01*
G01X1908251Y50630D02*
X1908249Y50628D01*
G01X1893838Y91226D02*
X1893839Y91234D01*
G01X1893837Y91222D02*
X1893838Y91226D01*
G01X1893836Y91220D02*
X1893837Y91222D01*
G01X1893838Y88077D02*
X1893839Y88084D01*
G01X1893837Y88072D02*
X1893838Y88077D01*
G01X1893836Y88071D02*
X1893837Y88072D01*
G01X1893838Y84927D02*
X1893839Y84935D01*
G01X1893837Y84923D02*
X1893838Y84927D01*
G01X1893836Y84921D02*
X1893837Y84923D01*
G01X1894820Y93242D02*
X1894823Y93254D01*
G01X1894814Y93230D02*
X1894820Y93242D01*
G01X1894804Y93222D02*
X1894814Y93230D01*
G01X1894820Y90092D02*
X1894823Y90104D01*
G01X1894814Y90081D02*
X1894820Y90092D01*
G01X1894804Y90073D02*
X1894814Y90081D01*
G01X1894820Y86943D02*
X1894823Y86955D01*
G01X1894814Y86931D02*
X1894820Y86943D01*
G01X1894804Y86923D02*
X1894814Y86931D01*
G01X1894820Y83793D02*
X1894823Y83805D01*
G01X1894814Y83781D02*
X1894820Y83793D01*
G01X1894804Y83774D02*
X1894814Y83781D01*
G01X1893877Y91265D02*
Y91271D01*
G01Y91261D02*
Y91265D01*
G01X1893876Y91260D02*
X1893877Y91261D01*
G01Y88115D02*
Y88121D01*
G01Y88111D02*
Y88115D01*
G01X1893876Y88110D02*
X1893877Y88111D01*
G01Y84965D02*
Y84972D01*
G01Y84962D02*
Y84965D01*
G01X1893876Y84961D02*
X1893877Y84962D01*
G01X1893839Y88091D02*
Y88084D01*
G01X1893841Y88097D02*
X1893839Y88091D01*
G01X1893844Y88103D02*
X1893841Y88097D01*
G01X1893848Y88108D02*
X1893844Y88103D01*
G01X1893852Y88113D02*
X1893848Y88108D01*
G01X1893858Y88116D02*
X1893852Y88113D01*
G01X1893839Y84941D02*
Y84935D01*
G01X1893841Y84947D02*
X1893839Y84941D01*
G01X1893844Y84953D02*
X1893841Y84947D01*
G01X1893848Y84958D02*
X1893844Y84953D01*
G01X1893852Y84963D02*
X1893848Y84958D01*
G01X1893858Y84967D02*
X1893852Y84963D01*
G01X1833563Y55118D02*
G03X1847539I6988J0D01*
G01D02*
G03X1833563I-6988J0D01*
G01X1898819Y25138D02*
G03X1899409Y24547I591J0D01*
G01X1906102D02*
G03X1906693Y25138I0J591D01*
G01X1903937Y26319D02*
G03Y28287I0J984D01*
G01X1901575D02*
G03Y26319I0J-984D01*
G01X1903858Y39508D02*
G03I-1102J0D01*
G01X1905315Y34232D02*
G03X1906496Y35413I0J1181D01*
G01X1899016D02*
G03X1900197Y34232I1181J0D01*
G01X1904331Y39508D02*
G03I-1575J0D01*
G01X1891929Y25728D02*
G03X1893898Y23760I1968J0D01*
G01X1911614D02*
G03X1913583Y25728I0J1969D01*
G01X1847539Y55118D02*
G03I-6988J0D01*
G01X1898228Y47500D02*
X1897047Y46319D01*
G01X1895276Y44823D02*
X1891929Y41476D01*
G01X1905241Y42579D02*
X1903937Y40610D01*
G01X1899265Y34688D02*
X1901575Y38917D01*
G01X1894822Y84923D02*
X1894823Y84935D01*
G01X1894822Y88073D02*
X1894823Y88084D01*
G01X1894822Y91222D02*
X1894823Y91234D01*
G01X1908248Y51982D02*
Y51991D01*
G01Y56982D02*
Y56991D01*
G01Y61982D02*
Y61991D01*
G01Y66982D02*
Y66991D01*
G01Y71982D02*
Y71991D01*
G01Y76982D02*
Y76991D01*
G01Y81982D02*
Y81991D01*
G01X1910236Y182815D02*
Y44823D01*
G01X1909646Y185059D02*
Y42579D01*
G01X1909429Y52008D02*
Y50630D01*
G01Y57008D02*
Y55630D01*
G01Y62008D02*
Y60630D01*
G01Y67008D02*
Y65630D01*
G01Y72008D02*
Y70630D01*
G01Y77008D02*
Y75630D01*
G01Y82008D02*
Y80630D01*
G01X1908858Y104862D02*
Y82776D01*
G01X1908248Y56982D02*
Y57125D01*
G01Y51982D02*
Y52125D01*
G01Y66982D02*
Y67125D01*
G01Y61982D02*
Y62125D01*
G01Y76982D02*
Y77125D01*
G01Y71982D02*
Y72125D01*
G01Y81982D02*
Y82125D01*
G01Y80138D02*
Y82500D01*
G01Y75138D02*
Y77500D01*
G01Y70138D02*
Y72500D01*
G01Y65138D02*
Y67500D01*
G01Y60138D02*
Y62500D01*
G01Y55138D02*
Y57500D01*
G01Y50138D02*
Y52500D01*
G01X1907677Y103681D02*
Y83957D01*
G01X1907264Y52500D02*
Y50138D01*
G01Y57500D02*
Y55138D01*
G01Y62500D02*
Y60138D01*
G01Y67500D02*
Y65138D01*
G01Y72500D02*
Y70138D01*
G01Y77500D02*
Y75138D01*
G01Y82500D02*
Y80138D01*
G01X1906693Y31240D02*
Y25138D01*
G01X1906496Y43957D02*
Y35413D01*
G01X1904921Y82776D02*
Y46319D01*
G01X1903937Y40610D02*
Y38917D01*
G01X1903740Y83957D02*
Y47500D01*
G01X1901575Y38917D02*
Y40610D01*
G01X1899016Y35413D02*
Y43957D01*
G01X1898819Y31240D02*
Y25138D01*
G01X1898228Y47500D02*
Y180138D01*
G01X1897047Y46319D02*
Y181319D01*
G01X1895276Y81614D02*
Y42579D01*
G01X1894823Y93070D02*
Y94567D01*
G01Y89921D02*
Y91417D01*
G01Y86771D02*
Y88268D01*
G01Y83622D02*
Y85118D01*
G01X1894783Y86918D02*
Y86771D01*
G01Y83768D02*
Y83621D01*
G01Y85119D02*
Y84972D01*
G01Y90067D02*
Y89920D01*
G01Y91418D02*
Y91271D01*
G01Y88268D02*
Y88121D01*
G01Y93217D02*
Y93070D01*
G01X1893878D02*
Y93217D01*
G01Y89920D02*
Y90067D01*
G01Y91271D02*
Y91418D01*
G01Y88121D02*
Y88268D01*
G01Y86771D02*
Y86918D01*
G01Y83621D02*
Y83768D01*
G01Y84972D02*
Y85119D01*
G01X1893839Y85118D02*
Y83622D01*
G01Y91417D02*
Y89921D01*
G01Y88268D02*
Y86772D01*
G01Y94567D02*
Y93071D01*
G01X1892657Y88110D02*
Y86929D01*
G01Y84961D02*
Y83780D01*
G01Y91260D02*
Y90079D01*
G01Y94409D02*
Y93228D01*
G01X1892323Y106024D02*
Y81614D01*
G01X1891929D02*
Y106024D01*
G01Y41476D02*
Y25728D01*
G01X1888898Y93228D02*
Y94409D01*
G01Y90079D02*
Y91260D01*
G01Y86929D02*
Y88110D01*
G01Y83780D02*
Y84961D01*
G01X1894823Y93254D02*
X1894822Y93265D01*
G01X1894823Y90105D02*
X1894822Y90115D01*
G01X1894823Y86955D02*
X1894822Y86966D01*
G01X1894823Y83806D02*
X1894822Y83816D01*
G01X1903937Y38917D02*
X1906247Y34688D01*
G01X1901575Y40610D02*
X1900271Y42579D01*
G01X1907677Y83957D02*
X1908858Y82776D01*
G01X1903740Y83957D02*
X1904921Y82776D01*
G01X1913583Y41476D02*
X1910236Y44823D01*
G01X1903740Y47500D02*
X1904921Y46319D01*
G01X1893836Y93263D02*
X1893725Y93268D01*
G01X1893836Y86965D02*
X1893725Y86969D01*
G01X1893091Y93268D02*
X1892657D01*
G01X1894821D02*
X1888898D01*
G01X1894782Y93228D02*
X1888898D01*
G01X1893839Y93071D02*
X1894823D01*
G01X1893878Y93031D02*
X1894783D01*
G01Y91457D02*
X1893878D01*
G01X1894823Y91417D02*
X1893839D01*
G01X1894782Y91260D02*
X1888898D01*
G01Y91220D02*
X1894822D01*
G01X1894821Y90118D02*
X1888898D01*
G01X1894782Y90079D02*
X1888898D01*
G01X1893839Y89921D02*
X1894823D01*
G01X1893878Y89882D02*
X1894783D01*
G01Y88307D02*
X1893878D01*
G01X1894823Y88268D02*
X1893839D01*
G01X1894782Y88110D02*
X1888898D01*
G01Y88071D02*
X1894822D01*
G01X1893091Y86969D02*
X1892657D01*
G01X1894821D02*
X1888898D01*
G01X1894782Y86929D02*
X1888898D01*
G01X1893839Y86772D02*
X1894823D01*
G01X1893878Y86732D02*
X1894783D01*
G01Y85157D02*
X1893878D01*
G01X1894823Y85118D02*
X1893839D01*
G01X1894782Y84961D02*
X1888898D01*
G01Y84921D02*
X1894822D01*
G01X1907677Y83957D02*
X1903740D01*
G01X1894821Y83819D02*
X1888898D01*
G01X1894782Y83780D02*
X1888898D01*
G01X1893839Y83622D02*
X1894823D01*
G01X1893878Y83583D02*
X1894783D01*
G01X1908858Y82776D02*
X1904921D01*
G01X1908248Y82500D02*
X1907264D01*
G01X1907265Y82008D02*
X1912598D01*
G01Y81969D02*
X1908250D01*
G01X1895276Y81614D02*
X1891929D01*
G01X1912598Y80630D02*
X1907265D01*
G01X1907264Y80138D02*
X1908248D01*
G01Y77500D02*
X1907264D01*
G01X1907265Y77008D02*
X1912598D01*
G01Y76969D02*
X1908250D01*
G01X1912598Y75630D02*
X1907265D01*
G01X1907264Y75138D02*
X1908248D01*
G01Y72500D02*
X1907264D01*
G01X1907265Y72008D02*
X1912598D01*
G01Y71969D02*
X1908250D01*
G01X1912598Y70630D02*
X1907265D01*
G01X1907264Y70138D02*
X1908248D01*
G01Y67500D02*
X1907264D01*
G01X1907265Y67008D02*
X1912598D01*
G01Y66969D02*
X1908250D01*
G01X1912598Y65630D02*
X1907265D01*
G01X1907264Y65138D02*
X1908248D01*
G01Y62500D02*
X1907264D01*
G01X1907265Y62008D02*
X1912598D01*
G01Y61969D02*
X1908250D01*
G01X1912598Y60630D02*
X1907265D01*
G01X1907264Y60138D02*
X1908248D01*
G01Y57500D02*
X1907264D01*
G01X1907265Y57008D02*
X1912598D01*
G01Y56969D02*
X1908250D01*
G01X1912598Y55630D02*
X1907265D01*
G01X1907264Y55138D02*
X1908248D01*
G01Y52500D02*
X1907264D01*
G01X1907265Y52008D02*
X1912598D01*
G01Y51969D02*
X1908250D01*
G01X1912598Y50630D02*
X1907265D01*
G01X1907264Y50138D02*
X1908248D01*
G01X1903740Y47500D02*
X1898228D01*
G01X1904921Y46319D02*
X1897047D01*
G01X1910236Y44823D02*
X1895276D01*
G01X1906496Y43957D02*
X1909646D01*
G01X1899016D02*
X1895276D01*
G01Y42579D02*
X1909646D01*
G01X1903937Y40610D02*
X1901575D01*
G01X1903937Y38917D02*
X1901575D01*
G01X1907264Y82204D02*
X1908219Y82205D01*
G01X1908248Y80434D02*
X1907264Y80433D01*
G01Y77204D02*
X1908219Y77205D01*
G01X1908248Y75434D02*
X1907264Y75433D01*
G01Y72204D02*
X1908219Y72205D01*
G01X1908248Y70434D02*
X1907264Y70433D01*
G01Y67204D02*
X1908219Y67205D01*
G01X1908248Y65434D02*
X1907264Y65433D01*
G01Y62204D02*
X1908219Y62205D01*
G01X1908248Y60434D02*
X1907264Y60433D01*
G01Y57204D02*
X1908219Y57205D01*
G01X1908248Y55434D02*
X1907264Y55433D01*
G01Y52204D02*
X1908219Y52205D01*
G01X1908248Y50434D02*
X1907264Y50433D01*
G01X1905315Y34232D02*
X1900197D01*
G01X1913583Y34193D02*
X1891929D01*
G01X1906693Y31240D02*
X1898819D01*
G01Y29665D02*
X1906693D01*
G01X1903937Y28287D02*
X1901575D01*
G01Y26319D02*
X1903937D01*
G01X1906102Y24547D02*
X1899409D01*
G01X1911614Y23760D02*
X1893898D01*
G01X1893841Y94390D02*
X1893836Y94370D01*
G01X1893856Y94404D02*
X1893841Y94390D01*
G01X1893876Y94409D02*
X1893856Y94404D01*
G01X1893841Y97539D02*
X1893836Y97520D01*
G01X1893856Y97554D02*
X1893841Y97539D01*
G01X1893876Y97559D02*
X1893856Y97554D01*
G01X1893841Y100689D02*
X1893836Y100669D01*
G01X1893856Y100703D02*
X1893841Y100689D01*
G01X1893876Y100709D02*
X1893856Y100703D01*
G01X1893841Y103839D02*
X1893836Y103819D01*
G01X1893856Y103853D02*
X1893841Y103839D01*
G01X1893876Y103858D02*
X1893856Y103853D01*
G01X1894816Y96398D02*
X1894821Y96417D01*
G01X1894802Y96383D02*
X1894816Y96398D01*
G01X1894782Y96378D02*
X1894802Y96383D01*
G01X1894816Y99547D02*
X1894821Y99567D01*
G01X1894802Y99533D02*
X1894816Y99547D01*
G01X1894782Y99528D02*
X1894802Y99533D01*
G01X1894816Y102697D02*
X1894821Y102717D01*
G01X1894802Y102682D02*
X1894816Y102697D01*
G01X1894782Y102677D02*
X1894802Y102682D01*
G01X1894822Y99546D02*
X1894823Y99553D01*
G01X1894820Y99539D02*
X1894822Y99546D01*
G01X1894816Y99533D02*
X1894820Y99539D01*
G01X1894811Y99527D02*
X1894816Y99533D01*
G01X1894805Y99522D02*
X1894811Y99527D01*
G01X1894798Y99519D02*
X1894805Y99522D01*
G01X1894791Y99517D02*
X1894798Y99519D01*
G01X1894783Y99516D02*
X1894791Y99517D01*
G01X1893861Y94417D02*
X1893858Y94415D01*
G01X1893864Y94418D02*
X1893861Y94417D01*
G01X1893868Y94419D02*
X1893864Y94418D01*
G01X1893871Y94420D02*
X1893868Y94419D01*
G01X1893874Y94420D02*
X1893871D01*
G01X1893878D02*
X1893874D01*
G01X1894800Y96370D02*
X1894804Y96372D01*
G01X1894797Y96369D02*
X1894800Y96370D01*
G01X1894794Y96368D02*
X1894797Y96369D01*
G01X1894791Y96367D02*
X1894794Y96368D01*
G01X1894787Y96367D02*
X1894791D01*
G01X1894783D02*
X1894787D01*
G01X1893861Y97567D02*
X1893858Y97565D01*
G01X1893864Y97568D02*
X1893861Y97567D01*
G01X1893868Y97569D02*
X1893864Y97568D01*
G01X1893871Y97570D02*
X1893868Y97569D01*
G01X1893874Y97570D02*
X1893871D01*
G01X1893878D02*
X1893874D01*
G01X1893861Y100716D02*
X1893858Y100715D01*
G01X1893864Y100717D02*
X1893861Y100716D01*
G01X1893868Y100719D02*
X1893864Y100717D01*
G01X1893871Y100719D02*
X1893868D01*
G01X1893874Y100720D02*
X1893871Y100719D01*
G01X1893878Y100720D02*
X1893874D01*
G01X1894800Y102669D02*
X1894804Y102671D01*
G01X1894797Y102668D02*
X1894800Y102669D01*
G01X1894794Y102667D02*
X1894797Y102668D01*
G01X1894791Y102667D02*
X1894794D01*
G01X1894787Y102666D02*
X1894791Y102667D01*
G01X1894783Y102666D02*
X1894787D01*
G01X1893861Y103866D02*
X1893858Y103864D01*
G01X1893864Y103867D02*
X1893861Y103866D01*
G01X1893868Y103868D02*
X1893864Y103867D01*
G01X1893871Y103869D02*
X1893868Y103868D01*
G01X1893874Y103869D02*
X1893871D01*
G01X1893878D02*
X1893874D01*
G01X1894813Y94408D02*
X1894817Y94402D01*
G01X1894809Y94412D02*
X1894813Y94408D01*
G01X1894803Y94416D02*
X1894809Y94412D01*
G01X1894797Y94419D02*
X1894803Y94416D01*
G01X1894790Y94420D02*
X1894797Y94419D01*
G01X1894783Y94420D02*
X1894790D01*
G01X1894813Y97557D02*
X1894817Y97552D01*
G01X1894809Y97562D02*
X1894813Y97557D01*
G01X1894803Y97565D02*
X1894809Y97562D01*
G01X1894797Y97568D02*
X1894803Y97565D01*
G01X1894790Y97570D02*
X1894797Y97568D01*
G01X1894783Y97570D02*
X1894790D01*
G01X1894813Y100707D02*
X1894817Y100702D01*
G01X1894809Y100711D02*
X1894813Y100707D01*
G01X1894803Y100715D02*
X1894809Y100711D01*
G01X1894797Y100718D02*
X1894803Y100715D01*
G01X1894790Y100719D02*
X1894797Y100718D01*
G01X1894783Y100720D02*
X1894790Y100719D01*
G01X1894813Y103857D02*
X1894817Y103851D01*
G01X1894809Y103861D02*
X1894813Y103857D01*
G01X1894803Y103865D02*
X1894809Y103861D01*
G01X1894797Y103867D02*
X1894803Y103865D01*
G01X1894790Y103869D02*
X1894797Y103867D01*
G01X1894783Y103869D02*
X1894790D01*
G01X1893839Y96396D02*
Y96404D01*
G01X1893842Y96389D02*
X1893839Y96396D01*
G01X1893845Y96383D02*
X1893842Y96389D01*
G01X1893850Y96378D02*
X1893845Y96383D01*
G01X1893856Y96373D02*
X1893850Y96378D01*
G01X1893863Y96369D02*
X1893856Y96373D01*
G01X1893870Y96367D02*
X1893863Y96369D01*
G01X1893878Y96367D02*
X1893870D01*
G01X1893839Y99546D02*
Y99553D01*
G01X1893842Y99539D02*
X1893839Y99546D01*
G01X1893845Y99533D02*
X1893842Y99539D01*
G01X1893850Y99527D02*
X1893845Y99533D01*
G01X1893856Y99522D02*
X1893850Y99527D01*
G01X1893863Y99519D02*
X1893856Y99522D01*
G01X1893870Y99517D02*
X1893863Y99519D01*
G01X1893878Y99516D02*
X1893870Y99517D01*
G01X1893839Y102696D02*
Y102703D01*
G01X1893842Y102689D02*
X1893839Y102696D01*
G01X1893845Y102682D02*
X1893842Y102689D01*
G01X1893850Y102677D02*
X1893845Y102682D01*
G01X1893856Y102672D02*
X1893850Y102677D01*
G01X1893863Y102669D02*
X1893856Y102672D01*
G01X1893870Y102667D02*
X1893863Y102669D01*
G01X1893878Y102666D02*
X1893870Y102667D01*
G01X1894793Y94408D02*
X1894802Y94404D01*
G01X1894782Y94409D02*
X1894793Y94408D01*
G01Y97557D02*
X1894802Y97554D01*
G01X1894782Y97559D02*
X1894793Y97557D01*
G01Y100707D02*
X1894802Y100703D01*
G01X1894782Y100709D02*
X1894793Y100707D01*
G01Y103857D02*
X1894802Y103853D01*
G01X1894782Y103858D02*
X1894793Y103857D01*
G01X1893839Y96407D02*
Y96404D01*
G01X1893840Y96401D02*
X1893839Y96407D01*
G01X1893852Y96386D02*
X1893840Y96401D01*
G01X1893876Y96378D02*
X1893852Y96386D01*
G01X1893839Y99557D02*
Y99553D01*
G01X1893840Y99551D02*
X1893839Y99557D01*
G01X1893852Y99536D02*
X1893840Y99551D01*
G01X1893876Y99528D02*
X1893852Y99536D01*
G01X1893839Y102707D02*
Y102703D01*
G01X1893840Y102701D02*
X1893839Y102707D01*
G01X1893852Y102685D02*
X1893840Y102701D01*
G01X1893876Y102677D02*
X1893852Y102685D01*
G01X1908235Y106999D02*
X1908246Y106984D01*
G01X1908211Y107008D02*
X1908235Y106999D01*
G01Y111999D02*
X1908246Y111984D01*
G01X1908211Y112008D02*
X1908235Y111999D01*
G01Y116999D02*
X1908246Y116984D01*
G01X1908211Y117008D02*
X1908235Y116999D01*
G01Y121999D02*
X1908246Y121984D01*
G01X1908211Y122008D02*
X1908235Y121999D01*
G01Y126999D02*
X1908246Y126984D01*
G01X1908211Y127008D02*
X1908235Y126999D01*
G01Y131999D02*
X1908246Y131984D01*
G01X1908211Y132008D02*
X1908235Y131999D01*
G01Y136999D02*
X1908246Y136984D01*
G01X1908211Y137008D02*
X1908235Y136999D01*
G01Y141999D02*
X1908246Y141984D01*
G01X1908211Y142008D02*
X1908235Y141999D01*
G01Y146999D02*
X1908246Y146984D01*
G01X1908211Y147008D02*
X1908235Y146999D01*
G01X1908246Y151984D02*
X1908248Y151978D01*
G01X1908235Y151999D02*
X1908246Y151984D01*
G01X1908211Y152008D02*
X1908235Y151999D01*
G01Y156999D02*
X1908246Y156984D01*
G01X1908211Y157008D02*
X1908235Y156999D01*
G01Y161999D02*
X1908246Y161984D01*
G01X1908211Y162008D02*
X1908235Y161999D01*
G01Y166999D02*
X1908246Y166984D01*
G01X1908211Y167008D02*
X1908235Y166999D01*
G01Y171999D02*
X1908246Y171984D01*
G01X1908211Y172008D02*
X1908235Y171999D01*
G01Y176999D02*
X1908246Y176984D01*
G01X1908211Y177008D02*
X1908235Y176999D01*
G01X1894791Y94408D02*
X1894782Y94409D01*
G01X1894800Y94405D02*
X1894791Y94408D01*
G01X1894808Y94400D02*
X1894800Y94405D01*
G01X1894791Y97558D02*
X1894782Y97559D01*
G01X1894800Y97555D02*
X1894791Y97558D01*
G01X1894808Y97549D02*
X1894800Y97555D01*
G01X1894791Y100707D02*
X1894782Y100709D01*
G01X1894800Y100704D02*
X1894791Y100707D01*
G01X1894808Y100699D02*
X1894800Y100704D01*
G01X1894791Y103857D02*
X1894782Y103858D01*
G01X1894800Y103854D02*
X1894791Y103857D01*
G01X1894808Y103848D02*
X1894800Y103854D01*
G01X1893878Y96373D02*
Y96367D01*
G01X1893877Y96377D02*
X1893878Y96373D01*
G01X1893876Y96378D02*
X1893877Y96377D01*
G01X1893878Y99522D02*
Y99516D01*
G01X1893877Y99526D02*
X1893878Y99522D01*
G01X1893876Y99528D02*
X1893877Y99526D01*
G01X1893878Y102672D02*
Y102666D01*
G01X1893877Y102676D02*
X1893878Y102672D01*
G01X1893876Y102677D02*
X1893877Y102676D01*
G01X1908248Y106975D02*
Y106982D01*
G01X1908249Y106970D02*
X1908248Y106975D01*
G01X1908250Y106969D02*
X1908249Y106970D01*
G01X1908248Y111975D02*
Y111982D01*
G01X1908249Y111970D02*
X1908248Y111975D01*
G01X1908250Y111969D02*
X1908249Y111970D01*
G01X1908248Y116975D02*
Y116982D01*
G01X1908249Y116970D02*
X1908248Y116975D01*
G01X1908250Y116969D02*
X1908249Y116970D01*
G01X1908248Y121975D02*
Y121982D01*
G01X1908249Y121970D02*
X1908248Y121975D01*
G01X1908250Y121969D02*
X1908249Y121970D01*
G01X1908248Y126975D02*
Y126982D01*
G01X1908249Y126970D02*
X1908248Y126975D01*
G01X1908250Y126969D02*
X1908249Y126970D01*
G01X1908248Y131975D02*
Y131982D01*
G01X1908249Y131970D02*
X1908248Y131975D01*
G01X1908250Y131969D02*
X1908249Y131970D01*
G01X1908248Y136975D02*
Y136982D01*
G01X1908249Y136970D02*
X1908248Y136975D01*
G01X1908250Y136969D02*
X1908249Y136970D01*
G01X1908248Y141975D02*
Y141982D01*
G01X1908249Y141970D02*
X1908248Y141975D01*
G01X1908250Y141969D02*
X1908249Y141970D01*
G01X1908248Y146975D02*
Y146982D01*
G01X1908249Y146970D02*
X1908248Y146975D01*
G01X1908250Y146969D02*
X1908249Y146970D01*
G01X1908248Y151975D02*
Y151982D01*
G01X1908249Y151970D02*
X1908248Y151975D01*
G01X1908250Y151969D02*
X1908249Y151970D01*
G01X1908248Y156975D02*
Y156982D01*
G01X1908249Y156970D02*
X1908248Y156975D01*
G01X1908250Y156969D02*
X1908249Y156970D01*
G01X1908248Y161975D02*
Y161982D01*
G01X1908249Y161970D02*
X1908248Y161975D01*
G01X1908250Y161969D02*
X1908249Y161970D01*
G01X1908248Y166975D02*
Y166982D01*
G01X1908249Y166970D02*
X1908248Y166975D01*
G01X1908250Y166969D02*
X1908249Y166970D01*
G01X1908248Y171975D02*
Y171982D01*
G01X1908249Y171970D02*
X1908248Y171975D01*
G01X1908250Y171969D02*
X1908249Y171970D01*
G01X1908248Y176975D02*
Y176982D01*
G01X1908249Y176970D02*
X1908248Y176975D01*
G01X1908250Y176969D02*
X1908249Y176970D01*
G01X1893861Y96380D02*
X1893876Y96378D01*
G01X1893850Y96388D02*
X1893861Y96380D01*
G01X1893838Y96406D02*
X1893850Y96388D01*
G01X1893861Y99530D02*
X1893876Y99528D01*
G01X1893849Y99538D02*
X1893861Y99530D01*
G01X1893837Y99558D02*
X1893849Y99538D01*
G01X1894823Y96411D02*
Y96404D01*
G01X1894822Y96416D02*
X1894823Y96411D01*
G01X1894821Y96417D02*
X1894822Y96416D01*
G01X1894823Y99561D02*
Y99553D01*
G01X1894822Y99565D02*
X1894823Y99561D01*
G01X1894821Y99567D02*
X1894822Y99565D01*
G01X1894823Y102711D02*
Y102703D01*
G01X1894822Y102715D02*
X1894823Y102711D01*
G01X1894821Y102717D02*
X1894822Y102715D01*
G01X1893861Y102680D02*
X1893876Y102677D01*
G01X1893848Y102688D02*
X1893861Y102680D01*
G01X1893837Y102708D02*
X1893848Y102688D01*
G01X1894822Y94390D02*
X1894823Y94383D01*
G01X1894820Y94396D02*
X1894822Y94390D01*
G01X1894817Y94402D02*
X1894820Y94396D01*
G01X1894822Y97540D02*
X1894823Y97533D01*
G01X1894820Y97546D02*
X1894822Y97540D01*
G01X1894817Y97552D02*
X1894820Y97546D01*
G01X1894822Y100689D02*
X1894823Y100683D01*
G01X1894820Y100696D02*
X1894822Y100689D01*
G01X1894817Y100702D02*
X1894820Y100696D01*
G01X1894822Y103839D02*
X1894823Y103832D01*
G01X1894820Y103845D02*
X1894822Y103839D01*
G01X1894817Y103851D02*
X1894820Y103845D01*
G01X1894784Y96373D02*
Y96367D01*
G01X1894783Y96376D02*
X1894784Y96373D01*
G01X1894782Y96378D02*
X1894783Y96376D01*
G01X1894784Y102672D02*
Y102666D01*
G01X1894783Y102676D02*
X1894784Y102672D01*
G01X1894782Y102677D02*
X1894783Y102676D01*
G01X1907264Y107015D02*
Y107024D01*
G01X1907265Y107009D02*
X1907264Y107015D01*
G01X1907265Y107008D02*
Y107009D01*
G01X1907264Y112015D02*
Y112024D01*
G01X1907265Y112009D02*
X1907264Y112015D01*
G01X1907265Y112008D02*
Y112009D01*
G01X1907264Y117015D02*
Y117024D01*
G01X1907265Y117009D02*
X1907264Y117015D01*
G01X1907265Y117008D02*
Y117009D01*
G01X1907264Y122015D02*
Y122024D01*
G01X1907265Y122009D02*
X1907264Y122015D01*
G01X1907265Y122008D02*
Y122009D01*
G01X1907264Y127015D02*
Y127024D01*
G01X1907265Y127009D02*
X1907264Y127015D01*
G01X1907265Y127008D02*
Y127009D01*
G01X1907264Y132015D02*
Y132024D01*
G01X1907265Y132009D02*
X1907264Y132015D01*
G01X1907265Y132008D02*
Y132009D01*
G01X1907264Y137015D02*
Y137024D01*
G01X1907265Y137009D02*
X1907264Y137015D01*
G01X1907265Y137008D02*
Y137009D01*
G01X1907264Y142015D02*
Y142024D01*
G01X1907265Y142009D02*
X1907264Y142015D01*
G01X1907265Y142008D02*
Y142009D01*
G01X1907264Y147015D02*
Y147024D01*
G01X1907265Y147009D02*
X1907264Y147015D01*
G01X1907265Y147008D02*
Y147009D01*
G01X1907264Y152015D02*
Y152024D01*
G01X1907265Y152009D02*
X1907264Y152015D01*
G01X1907265Y152008D02*
Y152009D01*
G01X1907264Y157015D02*
Y157024D01*
G01X1907265Y157009D02*
X1907264Y157015D01*
G01X1907265Y157008D02*
Y157009D01*
G01X1907264Y162015D02*
Y162024D01*
G01X1907265Y162009D02*
X1907264Y162015D01*
G01X1907265Y162008D02*
Y162009D01*
G01X1907264Y167015D02*
Y167024D01*
G01X1907265Y167009D02*
X1907264Y167015D01*
G01X1907265Y167008D02*
Y167009D01*
G01X1907264Y172015D02*
Y172024D01*
G01X1907265Y172009D02*
X1907264Y172015D01*
G01X1907265Y172008D02*
Y172009D01*
G01X1907264Y177015D02*
Y177024D01*
G01X1907265Y177009D02*
X1907264Y177015D01*
G01X1907265Y177008D02*
Y177009D01*
G01X1908240Y107152D02*
X1908248Y107125D01*
G01X1908230Y107178D02*
X1908240Y107152D01*
G01X1908219Y107205D02*
X1908230Y107178D01*
G01X1908240Y112152D02*
X1908248Y112125D01*
G01X1908230Y112178D02*
X1908240Y112152D01*
G01X1908219Y112205D02*
X1908230Y112178D01*
G01X1908240Y117152D02*
X1908248Y117125D01*
G01X1908230Y117178D02*
X1908240Y117152D01*
G01X1908219Y117205D02*
X1908230Y117178D01*
G01X1908240Y122152D02*
X1908248Y122125D01*
G01X1908230Y122178D02*
X1908240Y122152D01*
G01X1908219Y122205D02*
X1908230Y122178D01*
G01X1908240Y127152D02*
X1908248Y127125D01*
G01X1908230Y127178D02*
X1908240Y127152D01*
G01X1908219Y127205D02*
X1908230Y127178D01*
G01X1908240Y132152D02*
X1908248Y132125D01*
G01X1908230Y132178D02*
X1908240Y132152D01*
G01X1908219Y132205D02*
X1908230Y132178D01*
G01X1908240Y137152D02*
X1908248Y137125D01*
G01X1908230Y137178D02*
X1908240Y137152D01*
G01X1908219Y137205D02*
X1908230Y137178D01*
G01X1908240Y142152D02*
X1908248Y142125D01*
G01X1908230Y142178D02*
X1908240Y142152D01*
G01X1908219Y142205D02*
X1908230Y142178D01*
G01X1908240Y147152D02*
X1908248Y147125D01*
G01X1908230Y147178D02*
X1908240Y147152D01*
G01X1908219Y147205D02*
X1908230Y147178D01*
G01X1908240Y152152D02*
X1908248Y152125D01*
G01X1908230Y152178D02*
X1908240Y152152D01*
G01X1908219Y152205D02*
X1908230Y152178D01*
G01X1908240Y157152D02*
X1908248Y157125D01*
G01X1908230Y157178D02*
X1908240Y157152D01*
G01X1908219Y157205D02*
X1908230Y157178D01*
G01X1908240Y162152D02*
X1908248Y162125D01*
G01X1908230Y162178D02*
X1908240Y162152D01*
G01X1908219Y162205D02*
X1908230Y162178D01*
G01X1908240Y167152D02*
X1908248Y167125D01*
G01X1908230Y167178D02*
X1908240Y167152D01*
G01X1908219Y167205D02*
X1908230Y167178D01*
G01X1908240Y172152D02*
X1908248Y172125D01*
G01X1908230Y172178D02*
X1908240Y172152D01*
G01X1908219Y172205D02*
X1908230Y172178D01*
G01X1908240Y177152D02*
X1908248Y177125D01*
G01X1908230Y177178D02*
X1908240Y177152D01*
G01X1908219Y177205D02*
X1908230Y177178D01*
G01X1908231Y107003D02*
X1908211Y107008D01*
G01X1908245Y106988D02*
X1908231Y107003D01*
G01X1908250Y106969D02*
X1908245Y106988D01*
G01X1908231Y112003D02*
X1908211Y112008D01*
G01X1908245Y111988D02*
X1908231Y112003D01*
G01X1908250Y111969D02*
X1908245Y111988D01*
G01X1908231Y117003D02*
X1908211Y117008D01*
G01X1908245Y116988D02*
X1908231Y117003D01*
G01X1908250Y116969D02*
X1908245Y116988D01*
G01X1908231Y122003D02*
X1908211Y122008D01*
G01X1908245Y121988D02*
X1908231Y122003D01*
G01X1908250Y121969D02*
X1908245Y121988D01*
G01X1908231Y127003D02*
X1908211Y127008D01*
G01X1908245Y126988D02*
X1908231Y127003D01*
G01X1908250Y126969D02*
X1908245Y126988D01*
G01X1908231Y132003D02*
X1908211Y132008D01*
G01X1908245Y131988D02*
X1908231Y132003D01*
G01X1908250Y131969D02*
X1908245Y131988D01*
G01X1908231Y137003D02*
X1908211Y137008D01*
G01X1908245Y136988D02*
X1908231Y137003D01*
G01X1908250Y136969D02*
X1908245Y136988D01*
G01X1908231Y142003D02*
X1908211Y142008D01*
G01X1908245Y141988D02*
X1908231Y142003D01*
G01X1908250Y141969D02*
X1908245Y141988D01*
G01X1908231Y147003D02*
X1908211Y147008D01*
G01X1908245Y146988D02*
X1908231Y147003D01*
G01X1908250Y146969D02*
X1908245Y146988D01*
G01X1908231Y152003D02*
X1908211Y152008D01*
G01X1908245Y151988D02*
X1908231Y152003D01*
G01X1908250Y151969D02*
X1908245Y151988D01*
G01X1908231Y157003D02*
X1908211Y157008D01*
G01X1908245Y156988D02*
X1908231Y157003D01*
G01X1908250Y156969D02*
X1908245Y156988D01*
G01X1908231Y162003D02*
X1908211Y162008D01*
G01X1908245Y161988D02*
X1908231Y162003D01*
G01X1908250Y161969D02*
X1908245Y161988D01*
G01X1908231Y167003D02*
X1908211Y167008D01*
G01X1908245Y166988D02*
X1908231Y167003D01*
G01X1908250Y166969D02*
X1908245Y166988D01*
G01X1908231Y172003D02*
X1908211Y172008D01*
G01X1908245Y171988D02*
X1908231Y172003D01*
G01X1908250Y171969D02*
X1908245Y171988D01*
G01X1908231Y177003D02*
X1908211Y177008D01*
G01X1908245Y176988D02*
X1908231Y177003D01*
G01X1908250Y176969D02*
X1908245Y176988D01*
G01X1894815Y94391D02*
X1894808Y94400D01*
G01X1894820Y94381D02*
X1894815Y94391D01*
G01X1894822Y94370D02*
X1894820Y94381D01*
G01X1894815Y97541D02*
X1894808Y97549D01*
G01X1894820Y97531D02*
X1894815Y97541D01*
G01X1894822Y97520D02*
X1894820Y97531D01*
G01X1894815Y100691D02*
X1894808Y100699D01*
G01X1894820Y100680D02*
X1894815Y100691D01*
G01X1894822Y100669D02*
X1894820Y100680D01*
G01X1894815Y103840D02*
X1894808Y103848D01*
G01X1894820Y103830D02*
X1894815Y103840D01*
G01X1894822Y103819D02*
X1894820Y103830D01*
G01X1908215Y107106D02*
X1908219Y107205D01*
G01X1908209Y107034D02*
X1908215Y107106D01*
G01X1908211Y107008D02*
X1908209Y107034D01*
G01X1908215Y112106D02*
X1908219Y112205D01*
G01X1908209Y112034D02*
X1908215Y112106D01*
G01X1908211Y112008D02*
X1908209Y112034D01*
G01X1908215Y117106D02*
X1908219Y117205D01*
G01X1908209Y117034D02*
X1908215Y117106D01*
G01X1908211Y117008D02*
X1908209Y117034D01*
G01X1908215Y122106D02*
X1908219Y122205D01*
G01X1908209Y122034D02*
X1908215Y122106D01*
G01X1908211Y122008D02*
X1908209Y122034D01*
G01X1908215Y127106D02*
X1908219Y127205D01*
G01X1908209Y127034D02*
X1908215Y127106D01*
G01X1908211Y127008D02*
X1908209Y127034D01*
G01X1908215Y132106D02*
X1908219Y132205D01*
G01X1908209Y132034D02*
X1908215Y132106D01*
G01X1908211Y132008D02*
X1908209Y132034D01*
G01X1908215Y137106D02*
X1908219Y137205D01*
G01X1908209Y137034D02*
X1908215Y137106D01*
G01X1908211Y137008D02*
X1908209Y137034D01*
G01X1908215Y142106D02*
X1908219Y142205D01*
G01X1908209Y142034D02*
X1908215Y142106D01*
G01X1908211Y142008D02*
X1908209Y142034D01*
G01X1908215Y147106D02*
X1908219Y147205D01*
G01X1908209Y147034D02*
X1908215Y147106D01*
G01X1908211Y147008D02*
X1908209Y147034D01*
G01X1908215Y152106D02*
X1908219Y152205D01*
G01X1908209Y152034D02*
X1908215Y152106D01*
G01X1908211Y152008D02*
X1908209Y152034D01*
G01X1908215Y157106D02*
X1908219Y157205D01*
G01X1908209Y157034D02*
X1908215Y157106D01*
G01X1908211Y157008D02*
X1908209Y157034D01*
G01X1908215Y162106D02*
X1908219Y162205D01*
G01X1908209Y162034D02*
X1908215Y162106D01*
G01X1908211Y162008D02*
X1908209Y162034D01*
G01X1908215Y167106D02*
X1908219Y167205D01*
G01X1908209Y167034D02*
X1908215Y167106D01*
G01X1908211Y167008D02*
X1908209Y167034D01*
G01X1908215Y172106D02*
X1908219Y172205D01*
G01X1908209Y172034D02*
X1908215Y172106D01*
G01X1908211Y172008D02*
X1908209Y172034D01*
G01X1908215Y177106D02*
X1908219Y177205D01*
G01X1908209Y177034D02*
X1908215Y177106D01*
G01X1908211Y177008D02*
X1908209Y177034D01*
G01X1893838Y96411D02*
X1893839Y96404D01*
G01X1893837Y96416D02*
X1893838Y96411D01*
G01Y96406D02*
X1893837Y96416D01*
G01X1893879Y104043D02*
X1893878Y104055D01*
G01X1893876Y104030D02*
X1893879Y104043D01*
G01X1893876Y104016D02*
Y104030D01*
G01X1893879Y100893D02*
X1893878Y100906D01*
G01X1893876Y100880D02*
X1893879Y100893D01*
G01X1893876Y100866D02*
Y100880D01*
G01X1893879Y97743D02*
X1893878Y97756D01*
G01X1893876Y97730D02*
X1893879Y97743D01*
G01X1893876Y97717D02*
Y97730D01*
G01X1893879Y94594D02*
X1893878Y94606D01*
G01X1893876Y94581D02*
X1893879Y94594D01*
G01X1893876Y94567D02*
Y94581D01*
G01X1907265Y175628D02*
Y175630D01*
G01X1907264Y175622D02*
X1907265Y175628D01*
G01X1907264Y175614D02*
Y175622D01*
G01X1907265Y170628D02*
Y170630D01*
G01X1907264Y170622D02*
X1907265Y170628D01*
G01X1907264Y170614D02*
Y170622D01*
G01X1907265Y165628D02*
Y165630D01*
G01X1907264Y165622D02*
X1907265Y165628D01*
G01X1907264Y165614D02*
Y165622D01*
G01X1907265Y160628D02*
Y160630D01*
G01X1907264Y160622D02*
X1907265Y160628D01*
G01X1907264Y160614D02*
Y160622D01*
G01X1907265Y155628D02*
Y155630D01*
G01X1907264Y155622D02*
X1907265Y155628D01*
G01X1907264Y155614D02*
Y155622D01*
G01X1907265Y150628D02*
Y150630D01*
G01X1907264Y150622D02*
X1907265Y150628D01*
G01X1907264Y150614D02*
Y150622D01*
G01X1907265Y145628D02*
Y145630D01*
G01X1907264Y145622D02*
X1907265Y145628D01*
G01X1907264Y145614D02*
Y145622D01*
G01X1907265Y140628D02*
Y140630D01*
G01X1907264Y140622D02*
X1907265Y140628D01*
G01X1907264Y140614D02*
Y140622D01*
G01X1907265Y135628D02*
Y135630D01*
G01X1907264Y135622D02*
X1907265Y135628D01*
G01X1907264Y135614D02*
Y135622D01*
G01X1907265Y130628D02*
Y130630D01*
G01X1907264Y130622D02*
X1907265Y130628D01*
G01X1907264Y130614D02*
Y130622D01*
G01X1907265Y125628D02*
Y125630D01*
G01X1907264Y125622D02*
X1907265Y125628D01*
G01X1907264Y125614D02*
Y125622D01*
G01X1907265Y120628D02*
Y120630D01*
G01X1907264Y120622D02*
X1907265Y120628D01*
G01X1907264Y120614D02*
Y120622D01*
G01X1907265Y115628D02*
Y115630D01*
G01X1907264Y115622D02*
X1907265Y115628D01*
G01X1907264Y115614D02*
Y115622D01*
G01X1907265Y110628D02*
Y110630D01*
G01X1907264Y110622D02*
X1907265Y110628D01*
G01X1907264Y110614D02*
Y110622D01*
G01X1907265Y105628D02*
Y105630D01*
G01X1907264Y105622D02*
X1907265Y105628D01*
G01X1907264Y105614D02*
Y105622D01*
G01X1893838Y102711D02*
X1893839Y102703D01*
G01X1893837Y102715D02*
X1893838Y102711D01*
G01X1893837Y102707D02*
Y102715D01*
G01X1893876Y102506D02*
X1893874Y102519D01*
G01X1893879Y102493D02*
X1893876Y102506D01*
G01X1893878Y102480D02*
X1893879Y102493D01*
G01X1893876Y99356D02*
X1893874Y99370D01*
G01X1893879Y99343D02*
X1893876Y99356D01*
G01X1893878Y99331D02*
X1893879Y99343D01*
G01X1893876Y96206D02*
X1893874Y96220D01*
G01X1893879Y96194D02*
X1893876Y96206D01*
G01X1893878Y96181D02*
X1893879Y96194D01*
G01X1894786Y104030D02*
X1894787Y104016D01*
G01X1894783Y104043D02*
X1894786Y104030D01*
G01X1894783Y104055D02*
Y104043D01*
G01X1894786Y100880D02*
X1894787Y100866D01*
G01X1894783Y100893D02*
X1894786Y100880D01*
G01X1894783Y100906D02*
Y100893D01*
G01X1894786Y97730D02*
X1894787Y97717D01*
G01X1894783Y97743D02*
X1894786Y97730D01*
G01X1894783Y97756D02*
Y97743D01*
G01X1894786Y94581D02*
X1894787Y94567D01*
G01X1894783Y94594D02*
X1894786Y94581D01*
G01X1894783Y94606D02*
Y94594D01*
G01X1893838Y99561D02*
X1893839Y99554D01*
G01X1893837Y99565D02*
X1893838Y99561D01*
G01X1893837Y99558D02*
Y99565D01*
G01X1894783Y102493D02*
Y102480D01*
G01X1894785Y102506D02*
X1894783Y102493D01*
G01X1894787Y102519D02*
X1894785Y102506D01*
G01X1894783Y99343D02*
Y99331D01*
G01X1894785Y99356D02*
X1894783Y99343D01*
G01X1894787Y99370D02*
X1894785Y99356D01*
G01X1894783Y96194D02*
Y96181D01*
G01X1894785Y96206D02*
X1894783Y96194D01*
G01X1894787Y96220D02*
X1894785Y96206D01*
G01X1893852Y103850D02*
X1893876Y103858D01*
G01X1893841Y103835D02*
X1893852Y103850D01*
G01X1893839Y103828D02*
X1893841Y103835D01*
G01X1893852Y100700D02*
X1893876Y100709D01*
G01X1893841Y100685D02*
X1893852Y100700D01*
G01X1893839Y100679D02*
X1893841Y100685D01*
G01X1893852Y97550D02*
X1893876Y97559D01*
G01X1893841Y97536D02*
X1893852Y97550D01*
G01X1893839Y97529D02*
X1893841Y97536D01*
G01X1893852Y94401D02*
X1893876Y94409D01*
G01X1893841Y94386D02*
X1893852Y94401D01*
G01X1893839Y94380D02*
X1893841Y94386D01*
G01X1893877Y103863D02*
Y103869D01*
G01Y103859D02*
Y103863D01*
G01X1893876Y103858D02*
X1893877Y103859D01*
G01Y100713D02*
Y100720D01*
G01Y100710D02*
Y100713D01*
G01X1893876Y100709D02*
X1893877Y100710D01*
G01Y97564D02*
Y97570D01*
G01Y97560D02*
Y97564D01*
G01X1893876Y97559D02*
X1893877Y97560D01*
G01X1893839Y103839D02*
Y103832D01*
G01X1893841Y103845D02*
X1893839Y103839D01*
G01X1893844Y103851D02*
X1893841Y103845D01*
G01X1893848Y103856D02*
X1893844Y103851D01*
G01X1893852Y103861D02*
X1893848Y103856D01*
G01X1893858Y103864D02*
X1893852Y103861D01*
G01X1893839Y100689D02*
Y100683D01*
G01X1893841Y100695D02*
X1893839Y100689D01*
G01X1893844Y100701D02*
X1893841Y100695D01*
G01X1893848Y100706D02*
X1893844Y100701D01*
G01X1893852Y100711D02*
X1893848Y100706D01*
G01X1893858Y100715D02*
X1893852Y100711D01*
G01X1893839Y97539D02*
Y97533D01*
G01X1893841Y97546D02*
X1893839Y97539D01*
G01X1893844Y97552D02*
X1893841Y97546D01*
G01X1893848Y97557D02*
X1893844Y97552D01*
G01X1893852Y97561D02*
X1893848Y97557D01*
G01X1893858Y97565D02*
X1893852Y97561D01*
G01X1893839Y94390D02*
Y94383D01*
G01X1893841Y94396D02*
X1893839Y94390D01*
G01X1893844Y94402D02*
X1893841Y94396D01*
G01X1893848Y94407D02*
X1893844Y94402D01*
G01X1893852Y94412D02*
X1893848Y94407D01*
G01X1893858Y94415D02*
X1893852Y94412D01*
G01X1894794Y102679D02*
X1894782Y102677D01*
G01X1894804Y102684D02*
X1894794Y102679D01*
G01Y99530D02*
X1894782Y99528D01*
G01X1894804Y99534D02*
X1894794Y99530D01*
G01Y96380D02*
X1894782Y96378D01*
G01X1894804Y96385D02*
X1894794Y96380D01*
G01X1894823Y103825D02*
Y103832D01*
G01X1894822Y103820D02*
X1894823Y103825D01*
G01X1894822Y103819D02*
Y103820D01*
G01X1894823Y100676D02*
Y100683D01*
G01X1894822Y100671D02*
X1894823Y100676D01*
G01X1894822Y100669D02*
Y100671D01*
G01X1894823Y97526D02*
Y97533D01*
G01X1894822Y97521D02*
X1894823Y97526D01*
G01X1894822Y97520D02*
Y97521D01*
G01X1894823Y94376D02*
Y94383D01*
G01X1894822Y94372D02*
X1894823Y94376D01*
G01X1894822Y94370D02*
Y94372D01*
G01X1894783Y103863D02*
Y103869D01*
G01Y103859D02*
Y103863D01*
G01X1894782Y103858D02*
X1894783Y103859D01*
G01Y100714D02*
Y100720D01*
G01Y100710D02*
Y100714D01*
G01X1894782Y100709D02*
X1894783Y100710D01*
G01Y97564D02*
Y97570D01*
G01Y97560D02*
Y97564D01*
G01X1894782Y97559D02*
X1894783Y97560D01*
G01Y94415D02*
Y94420D01*
G01Y94411D02*
Y94415D01*
G01X1894782Y94409D02*
X1894783Y94411D01*
G01X1908248Y175622D02*
Y175613D01*
G01X1908249Y175628D02*
X1908248Y175622D01*
G01X1908251Y175630D02*
X1908249Y175628D01*
G01X1908248Y170622D02*
Y170613D01*
G01X1908249Y170628D02*
X1908248Y170622D01*
G01X1908251Y170630D02*
X1908249Y170628D01*
G01X1908248Y165622D02*
Y165613D01*
G01X1908249Y165628D02*
X1908248Y165622D01*
G01X1908251Y165630D02*
X1908249Y165628D01*
G01X1908248Y160622D02*
Y160613D01*
G01X1908249Y160628D02*
X1908248Y160622D01*
G01X1908251Y160630D02*
X1908249Y160628D01*
G01X1908248Y155622D02*
Y155613D01*
G01X1908249Y155628D02*
X1908248Y155622D01*
G01X1908251Y155630D02*
X1908249Y155628D01*
G01X1908248Y150622D02*
Y150613D01*
G01X1908249Y150628D02*
X1908248Y150622D01*
G01X1908251Y150630D02*
X1908249Y150628D01*
G01X1908248Y145622D02*
Y145613D01*
G01X1908249Y145628D02*
X1908248Y145622D01*
G01X1908251Y145630D02*
X1908249Y145628D01*
G01X1908248Y140622D02*
Y140613D01*
G01X1908249Y140628D02*
X1908248Y140622D01*
G01X1908251Y140630D02*
X1908249Y140628D01*
G01X1908248Y135622D02*
Y135613D01*
G01X1908249Y135628D02*
X1908248Y135622D01*
G01X1908251Y135630D02*
X1908249Y135628D01*
G01X1908248Y130622D02*
Y130613D01*
G01X1908249Y130628D02*
X1908248Y130622D01*
G01X1908251Y130630D02*
X1908249Y130628D01*
G01X1908248Y125622D02*
Y125613D01*
G01X1908249Y125628D02*
X1908248Y125622D01*
G01X1908251Y125630D02*
X1908249Y125628D01*
G01X1908248Y120622D02*
Y120613D01*
G01X1908249Y120628D02*
X1908248Y120622D01*
G01X1908251Y120630D02*
X1908249Y120628D01*
G01X1908248Y115622D02*
Y115613D01*
G01X1908249Y115628D02*
X1908248Y115622D01*
G01X1908251Y115630D02*
X1908249Y115628D01*
G01X1908248Y110622D02*
Y110613D01*
G01X1908249Y110628D02*
X1908248Y110622D01*
G01X1908251Y110630D02*
X1908249Y110628D01*
G01X1908248Y105622D02*
Y105613D01*
G01X1908249Y105628D02*
X1908248Y105622D01*
G01X1908251Y105630D02*
X1908249Y105628D01*
G01X1893838Y103825D02*
X1893839Y103832D01*
G01X1893837Y103820D02*
X1893838Y103825D01*
G01X1893836Y103819D02*
X1893837Y103820D01*
G01X1893838Y100675D02*
X1893839Y100683D01*
G01X1893837Y100671D02*
X1893838Y100675D01*
G01X1893836Y100669D02*
X1893837Y100671D01*
G01X1893838Y97526D02*
X1893839Y97533D01*
G01X1893837Y97521D02*
X1893838Y97526D01*
G01X1893836Y97520D02*
X1893837Y97521D01*
G01X1893838Y94376D02*
X1893839Y94383D01*
G01X1893837Y94372D02*
X1893838Y94376D01*
G01X1893836Y94370D02*
X1893837Y94372D01*
G01X1894820Y102691D02*
X1894823Y102703D01*
G01X1894814Y102679D02*
X1894820Y102691D01*
G01X1894804Y102671D02*
X1894814Y102679D01*
G01X1894820Y96391D02*
X1894823Y96404D01*
G01X1894814Y96380D02*
X1894820Y96391D01*
G01X1894804Y96372D02*
X1894814Y96380D01*
G01X1893877Y94414D02*
Y94420D01*
G01Y94411D02*
Y94414D01*
G01X1893876Y94409D02*
X1893877Y94411D01*
G01X1835039Y122047D02*
G03X1846063I5512J0D01*
G01D02*
G03X1835039I-5512J0D01*
G01X1904646Y188130D02*
G03I-1890J0D01*
G01X1905118D02*
G03I-2362J0D01*
G01X1846063Y122047D02*
G03I-5512J0D01*
G01X1907677Y103681D02*
X1908858Y104862D01*
G01X1903740Y103681D02*
X1904921Y104862D01*
G01X1900271Y185059D02*
X1901575Y187028D01*
G01X1906247Y192950D02*
X1903937Y188720D01*
G01X1913583Y186161D02*
X1910236Y182815D01*
G01X1903740Y180138D02*
X1904921Y181319D01*
G01X1894822Y94372D02*
X1894823Y94383D01*
G01X1894822Y97522D02*
X1894823Y97533D01*
G01X1894822Y100671D02*
X1894823Y100683D01*
G01X1894822Y103821D02*
X1894823Y103832D01*
G01X1908248Y106982D02*
Y106991D01*
G01Y111982D02*
Y111991D01*
G01Y116982D02*
Y116991D01*
G01Y121982D02*
Y121991D01*
G01Y126982D02*
Y126991D01*
G01Y131982D02*
Y131991D01*
G01Y136982D02*
Y136991D01*
G01Y141982D02*
Y141991D01*
G01Y146982D02*
Y146991D01*
G01Y151982D02*
Y151991D01*
G01Y156982D02*
Y156991D01*
G01Y161982D02*
Y161991D01*
G01Y166982D02*
Y166991D01*
G01Y171982D02*
Y171991D01*
G01Y176982D02*
Y176991D01*
G01X1909429Y107008D02*
Y105630D01*
G01Y112008D02*
Y110630D01*
G01Y117008D02*
Y115630D01*
G01Y122008D02*
Y120630D01*
G01Y127008D02*
Y125630D01*
G01Y132008D02*
Y130630D01*
G01Y137008D02*
Y135630D01*
G01Y142008D02*
Y140630D01*
G01Y147008D02*
Y145630D01*
G01Y152008D02*
Y150630D01*
G01Y157008D02*
Y155630D01*
G01Y162008D02*
Y160630D01*
G01Y167008D02*
Y165630D01*
G01Y172008D02*
Y170630D01*
G01Y177008D02*
Y175630D01*
G01X1908248Y106982D02*
Y107125D01*
G01Y116982D02*
Y117125D01*
G01Y111982D02*
Y112125D01*
G01Y126982D02*
Y127125D01*
G01Y121982D02*
Y122125D01*
G01Y136982D02*
Y137125D01*
G01Y131982D02*
Y132125D01*
G01Y146982D02*
Y147125D01*
G01Y141982D02*
Y142125D01*
G01Y156982D02*
Y157125D01*
G01Y151982D02*
Y152125D01*
G01Y166982D02*
Y167125D01*
G01Y161982D02*
Y162125D01*
G01Y176982D02*
Y177125D01*
G01Y171982D02*
Y172125D01*
G01Y175138D02*
Y177500D01*
G01Y170138D02*
Y172500D01*
G01Y165138D02*
Y167500D01*
G01Y160138D02*
Y162500D01*
G01Y155138D02*
Y157500D01*
G01Y150138D02*
Y152500D01*
G01Y145138D02*
Y147500D01*
G01Y140138D02*
Y142500D01*
G01Y135138D02*
Y137500D01*
G01Y130138D02*
Y132500D01*
G01Y125138D02*
Y127500D01*
G01Y120138D02*
Y122500D01*
G01Y115138D02*
Y117500D01*
G01Y110138D02*
Y112500D01*
G01Y105138D02*
Y107500D01*
G01X1907264D02*
Y105138D01*
G01Y112500D02*
Y110138D01*
G01Y117500D02*
Y115138D01*
G01Y122500D02*
Y120138D01*
G01Y127500D02*
Y125138D01*
G01Y132500D02*
Y130138D01*
G01Y137500D02*
Y135138D01*
G01Y142500D02*
Y140138D01*
G01Y147500D02*
Y145138D01*
G01Y152500D02*
Y150138D01*
G01Y157500D02*
Y155138D01*
G01Y162500D02*
Y160138D01*
G01Y167500D02*
Y165138D01*
G01Y172500D02*
Y170138D01*
G01Y177500D02*
Y175138D01*
G01X1906496Y192224D02*
Y183681D01*
G01X1904921Y181319D02*
Y104862D01*
G01X1903937Y188720D02*
Y187028D01*
G01X1903740Y180138D02*
Y103681D01*
G01X1901575Y187028D02*
Y188720D01*
G01X1899016Y183681D02*
Y192224D01*
G01X1895276Y185059D02*
Y106024D01*
G01X1894823Y102519D02*
Y104016D01*
G01Y99370D02*
Y100866D01*
G01Y96220D02*
Y97717D01*
G01X1894783Y96367D02*
Y96220D01*
G01Y94567D02*
Y94420D01*
G01Y99516D02*
Y99369D01*
G01Y100867D02*
Y100720D01*
G01Y97717D02*
Y97570D01*
G01Y102666D02*
Y102519D01*
G01Y104016D02*
Y103869D01*
G01X1893878Y102519D02*
Y102666D01*
G01Y103869D02*
Y104016D01*
G01Y99369D02*
Y99516D01*
G01Y100720D02*
Y100867D01*
G01Y97570D02*
Y97717D01*
G01Y96220D02*
Y96367D01*
G01Y94420D02*
Y94567D01*
G01X1893839Y100866D02*
Y99370D01*
G01Y97717D02*
Y96220D01*
G01Y104016D02*
Y102520D01*
G01X1892657Y97559D02*
Y96378D01*
G01Y100709D02*
Y99528D01*
G01Y103858D02*
Y102677D01*
G01X1891929Y201909D02*
Y186161D01*
G01X1888898Y102677D02*
Y103858D01*
G01Y99528D02*
Y100709D01*
G01Y96378D02*
Y97559D01*
G01X1894823Y102703D02*
X1894822Y102714D01*
G01X1894823Y99554D02*
X1894822Y99564D01*
G01X1894823Y96404D02*
X1894822Y96415D01*
G01X1894782Y99528D02*
X1894785Y99516D01*
G01X1901575Y188720D02*
X1899265Y192950D01*
G01X1903937Y187028D02*
X1905241Y185059D01*
G01X1897047Y181319D02*
X1898228Y180138D01*
G01X1895276Y182815D02*
X1891929Y186161D01*
G01X1893725Y102717D02*
X1893837Y102708D01*
G01X1893836Y96414D02*
X1893725Y96417D01*
G01X1901575Y187028D02*
X1903937D01*
G01X1895276Y185059D02*
X1909646D01*
G01X1895276Y183681D02*
X1899016D01*
G01X1909646D02*
X1906496D01*
G01X1895276Y182815D02*
X1910236D01*
G01X1897047Y181319D02*
X1904921D01*
G01X1898228Y180138D02*
X1903740D01*
G01X1908248Y177500D02*
X1907264D01*
G01X1907265Y177008D02*
X1912598D01*
G01Y176969D02*
X1908250D01*
G01X1912598Y175630D02*
X1907265D01*
G01X1907264Y175138D02*
X1908248D01*
G01Y172500D02*
X1907264D01*
G01X1907265Y172008D02*
X1912598D01*
G01Y171969D02*
X1908250D01*
G01X1912598Y170630D02*
X1907265D01*
G01X1907264Y170138D02*
X1908248D01*
G01Y167500D02*
X1907264D01*
G01X1907265Y167008D02*
X1912598D01*
G01Y166969D02*
X1908250D01*
G01X1912598Y165630D02*
X1907265D01*
G01X1907264Y165138D02*
X1908248D01*
G01Y162500D02*
X1907264D01*
G01X1907265Y162008D02*
X1912598D01*
G01Y161969D02*
X1908250D01*
G01X1912598Y160630D02*
X1907265D01*
G01X1907264Y160138D02*
X1908248D01*
G01Y157500D02*
X1907264D01*
G01X1907265Y157008D02*
X1912598D01*
G01Y156969D02*
X1908250D01*
G01X1912598Y155630D02*
X1907265D01*
G01X1907264Y155138D02*
X1908248D01*
G01Y152500D02*
X1907264D01*
G01X1907265Y152008D02*
X1912598D01*
G01Y151969D02*
X1908250D01*
G01X1912598Y150630D02*
X1907265D01*
G01X1907264Y150138D02*
X1908248D01*
G01Y147500D02*
X1907264D01*
G01X1907265Y147008D02*
X1912598D01*
G01Y146969D02*
X1908250D01*
G01X1912598Y145630D02*
X1907265D01*
G01X1907264Y145138D02*
X1908248D01*
G01Y142500D02*
X1907264D01*
G01X1907265Y142008D02*
X1912598D01*
G01Y141969D02*
X1908250D01*
G01X1912598Y140630D02*
X1907265D01*
G01X1907264Y140138D02*
X1908248D01*
G01Y137500D02*
X1907264D01*
G01X1907265Y137008D02*
X1912598D01*
G01Y136969D02*
X1908250D01*
G01X1912598Y135630D02*
X1907265D01*
G01X1907264Y135138D02*
X1908248D01*
G01Y132500D02*
X1907264D01*
G01X1907265Y132008D02*
X1912598D01*
G01Y131969D02*
X1908250D01*
G01X1912598Y130630D02*
X1907265D01*
G01X1907264Y130138D02*
X1908248D01*
G01Y127500D02*
X1907264D01*
G01X1907265Y127008D02*
X1912598D01*
G01Y126969D02*
X1908250D01*
G01X1912598Y125630D02*
X1907265D01*
G01X1907264Y125138D02*
X1908248D01*
G01Y122500D02*
X1907264D01*
G01X1907265Y122008D02*
X1912598D01*
G01Y121969D02*
X1908250D01*
G01X1912598Y120630D02*
X1907265D01*
G01X1907264Y120138D02*
X1908248D01*
G01Y117500D02*
X1907264D01*
G01Y177204D02*
X1908219Y177205D01*
G01X1908248Y175434D02*
X1907264Y175433D01*
G01Y172204D02*
X1908219Y172205D01*
G01X1908248Y170434D02*
X1907264Y170433D01*
G01Y167204D02*
X1908219Y167205D01*
G01X1908248Y165434D02*
X1907264Y165433D01*
G01Y162204D02*
X1908219Y162205D01*
G01X1908248Y160434D02*
X1907264Y160433D01*
G01Y157204D02*
X1908219Y157205D01*
G01X1908248Y155434D02*
X1907264Y155433D01*
G01Y152204D02*
X1908219Y152205D01*
G01X1908248Y150434D02*
X1907264Y150433D01*
G01Y147204D02*
X1908219Y147205D01*
G01X1908248Y145434D02*
X1907264Y145433D01*
G01Y142204D02*
X1908219Y142205D01*
G01X1908248Y140434D02*
X1907264Y140433D01*
G01Y137204D02*
X1908219Y137205D01*
G01X1908248Y135434D02*
X1907264Y135433D01*
G01Y132204D02*
X1908219Y132205D01*
G01X1908248Y130434D02*
X1907264Y130433D01*
G01Y127204D02*
X1908219Y127205D01*
G01X1908248Y125434D02*
X1907264Y125433D01*
G01Y122204D02*
X1908219Y122205D01*
G01X1908248Y120434D02*
X1907264Y120433D01*
G01X1907265Y117008D02*
X1912598D01*
G01Y116969D02*
X1908250D01*
G01X1912598Y115630D02*
X1907265D01*
G01X1907264Y115138D02*
X1908248D01*
G01Y112500D02*
X1907264D01*
G01X1907265Y112008D02*
X1912598D01*
G01Y111969D02*
X1908250D01*
G01X1912598Y110630D02*
X1907265D01*
G01X1907264Y110138D02*
X1908248D01*
G01Y107500D02*
X1907264D01*
G01X1907265Y107008D02*
X1912598D01*
G01Y106969D02*
X1908250D01*
G01X1895276Y106024D02*
X1891929D01*
G01X1912598Y105630D02*
X1907265D01*
G01X1907264Y105138D02*
X1908248D01*
G01X1904921Y104862D02*
X1908858D01*
G01X1894783Y104055D02*
X1893878D01*
G01X1894823Y104016D02*
X1893839D01*
G01X1894782Y103858D02*
X1888898D01*
G01Y103819D02*
X1894822D01*
G01X1903740Y103681D02*
X1907677D01*
G01X1894821Y102717D02*
X1888898D01*
G01X1894782Y102677D02*
X1888898D01*
G01X1893839Y102520D02*
X1894823D01*
G01X1893878Y102480D02*
X1894783D01*
G01Y100906D02*
X1893878D01*
G01X1894823Y100866D02*
X1893839D01*
G01X1894782Y100709D02*
X1888898D01*
G01Y100669D02*
X1894822D01*
G01X1894821Y99567D02*
X1888898D01*
G01X1894782Y99528D02*
X1888898D01*
G01X1893839Y99370D02*
X1894823D01*
G01X1893878Y99331D02*
X1894783D01*
G01Y97756D02*
X1893878D01*
G01X1894823Y97717D02*
X1893839D01*
G01X1894782Y97559D02*
X1888898D01*
G01Y97520D02*
X1894822D01*
G01X1893091Y96417D02*
X1892657D01*
G01X1894821D02*
X1888898D01*
G01X1894782Y96378D02*
X1888898D01*
G01X1893839Y96220D02*
X1894823D01*
G01X1893878Y96181D02*
X1894783D01*
G01Y94606D02*
X1893878D01*
G01X1894823Y94567D02*
X1893839D01*
G01X1894782Y94409D02*
X1888898D01*
G01Y94370D02*
X1894822D01*
G01X1907264Y117204D02*
X1908219Y117205D01*
G01X1908248Y115434D02*
X1907264Y115433D01*
G01Y112204D02*
X1908219Y112205D01*
G01X1908248Y110434D02*
X1907264Y110433D01*
G01Y107204D02*
X1908219Y107205D01*
G01X1908248Y105434D02*
X1907264Y105433D01*
G01X1862795Y260630D02*
G03X1863976I590J0D01*
G01Y254331D02*
G03X1862795I-590J0D01*
G01X1860827D02*
G03X1859646I-590J0D01*
G01Y260630D02*
G03X1860827I591J0D01*
G01X1862795D02*
G03X1863976I590J0D01*
G01Y254331D02*
G03X1862795I-590J0D01*
G01X1860827D02*
G03X1859646I-590J0D01*
G01Y260630D02*
G03X1860827I591J0D01*
G01X1906693Y202500D02*
G03X1906102Y203091I-591J0D01*
G01X1899409D02*
G03X1898819Y202500I1J-591D01*
G01X1901575Y201319D02*
G03Y199350I0J-985D01*
G01X1903937D02*
G03Y201319I0J984D01*
G01X1900197Y193406D02*
G03X1899016Y192224I0J-1181D01*
G01X1906496D02*
G03X1905315Y193406I-1181J1D01*
G01X1913583Y201909D02*
G03X1911614Y203878I-1969J0D01*
G01X1893898D02*
G03X1891929Y201909I0J-1969D01*
G01X1906693Y196398D02*
Y202500D01*
G01X1898819Y196398D02*
Y202500D01*
G01X1864764Y254331D02*
Y260630D01*
G01Y254331D02*
Y260630D01*
G01X1858858Y254331D02*
Y260630D01*
G01D02*
Y254331D01*
G01X1859646Y260630D02*
X1858858D01*
G01X1859646D02*
X1858858D01*
G01X1862795D02*
X1860827D01*
G01X1864764D02*
X1863976D01*
G01X1862795D02*
X1860827D01*
G01X1864764D02*
X1863976D01*
G01X1864764Y259646D02*
X1858858D01*
G01Y259449D02*
X1864764D01*
G01X1858858Y255512D02*
X1864764D01*
G01Y255315D02*
X1858858D01*
G01X1863976Y254331D02*
X1864764D01*
G01X1860827D02*
X1862795D01*
G01X1863976D02*
X1864764D01*
G01X1860827D02*
X1862795D01*
G01X1858858D02*
X1859646D01*
G01X1858858D02*
X1859646D01*
G01X1911614Y203878D02*
X1893898D01*
G01X1906102Y203091D02*
X1899409D01*
G01X1903937Y201319D02*
X1901575D01*
G01Y199350D02*
X1903937D01*
G01X1906693Y197972D02*
X1898819D01*
G01Y196398D02*
X1906693D01*
G01X1913583Y193445D02*
X1891929D01*
G01X1900197Y193406D02*
X1905315D01*
G01X1901575Y188720D02*
X1903937D01*
G01X1893841Y537697D02*
X1893836Y537677D01*
G01X1893856Y537711D02*
X1893841Y537697D01*
G01X1893876Y537717D02*
X1893856Y537711D01*
G01X1893841Y540846D02*
X1893836Y540827D01*
G01X1893856Y540861D02*
X1893841Y540846D01*
G01X1893876Y540866D02*
X1893856Y540861D01*
G01X1893841Y543996D02*
X1893836Y543976D01*
G01X1893856Y544010D02*
X1893841Y543996D01*
G01X1893876Y544016D02*
X1893856Y544010D01*
G01X1893841Y547146D02*
X1893836Y547126D01*
G01X1893856Y547160D02*
X1893841Y547146D01*
G01X1893876Y547165D02*
X1893856Y547160D01*
G01X1893841Y550295D02*
X1893836Y550276D01*
G01X1893856Y550309D02*
X1893841Y550295D01*
G01X1893876Y550315D02*
X1893856Y550309D01*
G01X1893841Y553445D02*
X1893836Y553425D01*
G01X1893856Y553459D02*
X1893841Y553445D01*
G01X1893876Y553465D02*
X1893856Y553459D01*
G01X1893841Y556594D02*
X1893836Y556575D01*
G01X1893856Y556609D02*
X1893841Y556594D01*
G01X1893876Y556614D02*
X1893856Y556609D01*
G01X1894816Y536555D02*
X1894821Y536575D01*
G01X1894802Y536541D02*
X1894816Y536555D01*
G01X1894782Y536535D02*
X1894802Y536541D01*
G01X1894816Y539705D02*
X1894821Y539724D01*
G01X1894802Y539690D02*
X1894816Y539705D01*
G01X1894782Y539685D02*
X1894802Y539690D01*
G01X1894816Y542854D02*
X1894821Y542874D01*
G01X1894802Y542840D02*
X1894816Y542854D01*
G01X1894782Y542835D02*
X1894802Y542840D01*
G01X1894816Y546004D02*
X1894821Y546024D01*
G01X1894802Y545989D02*
X1894816Y546004D01*
G01X1894782Y545984D02*
X1894802Y545989D01*
G01X1894816Y549154D02*
X1894821Y549173D01*
G01X1894802Y549139D02*
X1894816Y549154D01*
G01X1894782Y549134D02*
X1894802Y549139D01*
G01X1894816Y552303D02*
X1894821Y552323D01*
G01X1894802Y552289D02*
X1894816Y552303D01*
G01X1894782Y552283D02*
X1894802Y552289D01*
G01X1894816Y555453D02*
X1894821Y555472D01*
G01X1894802Y555438D02*
X1894816Y555453D01*
G01X1894782Y555433D02*
X1894802Y555438D01*
G01X1894822Y552302D02*
X1894823Y552309D01*
G01X1894820Y552295D02*
X1894822Y552302D01*
G01X1894816Y552289D02*
X1894820Y552295D01*
G01X1894811Y552283D02*
X1894816Y552289D01*
G01X1894805Y552278D02*
X1894811Y552283D01*
G01X1894798Y552275D02*
X1894805Y552278D01*
G01X1894791Y552273D02*
X1894798Y552275D01*
G01X1894783Y552272D02*
X1894791Y552273D01*
G01X1894800Y536528D02*
X1894804Y536530D01*
G01X1894797Y536526D02*
X1894800Y536528D01*
G01X1894794Y536526D02*
X1894797D01*
G01X1894791Y536525D02*
X1894794Y536526D01*
G01X1894787Y536524D02*
X1894791Y536525D01*
G01X1894783Y536524D02*
X1894787D01*
G01X1893861Y537724D02*
X1893858Y537722D01*
G01X1893864Y537725D02*
X1893861Y537724D01*
G01X1893868Y537726D02*
X1893864Y537725D01*
G01X1893871Y537727D02*
X1893868Y537726D01*
G01X1893874Y537728D02*
X1893871Y537727D01*
G01X1893878Y537728D02*
X1893874D01*
G01X1894800Y539677D02*
X1894804Y539679D01*
G01X1894797Y539676D02*
X1894800Y539677D01*
G01X1894794Y539675D02*
X1894797Y539676D01*
G01X1894791Y539674D02*
X1894794Y539675D01*
G01X1894787Y539674D02*
X1894791D01*
G01X1894783D02*
X1894787D01*
G01X1893861Y540874D02*
X1893858Y540872D01*
G01X1893864Y540875D02*
X1893861Y540874D01*
G01X1893868Y540876D02*
X1893864Y540875D01*
G01X1893871Y540877D02*
X1893868Y540876D01*
G01X1893874Y540877D02*
X1893871D01*
G01X1893878D02*
X1893874D01*
G01X1894800Y542827D02*
X1894804Y542829D01*
G01X1894797Y542826D02*
X1894800Y542827D01*
G01X1894794Y542825D02*
X1894797Y542826D01*
G01X1894791Y542824D02*
X1894794Y542825D01*
G01X1894787Y542824D02*
X1894791D01*
G01X1894783Y542823D02*
X1894787Y542824D01*
G01X1893861Y544023D02*
X1893858Y544022D01*
G01X1893864Y544024D02*
X1893861Y544023D01*
G01X1893868Y544026D02*
X1893864Y544024D01*
G01X1893871Y544026D02*
X1893868D01*
G01X1893874Y544027D02*
X1893871Y544026D01*
G01X1893878Y544027D02*
X1893874D01*
G01X1894800Y545976D02*
X1894804Y545978D01*
G01X1894797Y545975D02*
X1894800Y545976D01*
G01X1894794Y545974D02*
X1894797Y545975D01*
G01X1894791Y545974D02*
X1894794D01*
G01X1894787Y545973D02*
X1894791Y545974D01*
G01X1894783Y545973D02*
X1894787D01*
G01X1893861Y547173D02*
X1893858Y547171D01*
G01X1893864Y547174D02*
X1893861Y547173D01*
G01X1893868Y547175D02*
X1893864Y547174D01*
G01X1893871Y547176D02*
X1893868Y547175D01*
G01X1893874Y547176D02*
X1893871D01*
G01X1893878D02*
X1893874D01*
G01X1894800Y549126D02*
X1894804Y549128D01*
G01X1894797Y549125D02*
X1894800Y549126D01*
G01X1894794Y549124D02*
X1894797Y549125D01*
G01X1894791Y549123D02*
X1894794Y549124D01*
G01X1894787Y549123D02*
X1894791D01*
G01X1894783Y549122D02*
X1894787Y549123D01*
G01X1893861Y550322D02*
X1893858Y550321D01*
G01X1893864Y550324D02*
X1893861Y550322D01*
G01X1893868Y550325D02*
X1893864Y550324D01*
G01X1893871Y550326D02*
X1893868Y550325D01*
G01X1893874Y550326D02*
X1893871D01*
G01X1893878D02*
X1893874D01*
G01X1893861Y553472D02*
X1893858Y553470D01*
G01X1893864Y553473D02*
X1893861Y553472D01*
G01X1893868Y553474D02*
X1893864Y553473D01*
G01X1893871Y553475D02*
X1893868Y553474D01*
G01X1893874Y553476D02*
X1893871Y553475D01*
G01X1893878Y553476D02*
X1893874D01*
G01X1894800Y555425D02*
X1894804Y555427D01*
G01X1894797Y555424D02*
X1894800Y555425D01*
G01X1894794Y555423D02*
X1894797Y555424D01*
G01X1894791Y555422D02*
X1894794Y555423D01*
G01X1894787Y555422D02*
X1894791D01*
G01X1894783D02*
X1894787D01*
G01X1893861Y556622D02*
X1893858Y556620D01*
G01X1893864Y556623D02*
X1893861Y556622D01*
G01X1893868Y556624D02*
X1893864Y556623D01*
G01X1893871Y556625D02*
X1893868Y556624D01*
G01X1893874Y556625D02*
X1893871D01*
G01X1893878D02*
X1893874D01*
G01X1894813Y537715D02*
X1894817Y537709D01*
G01X1894809Y537719D02*
X1894813Y537715D01*
G01X1894803Y537723D02*
X1894809Y537719D01*
G01X1894797Y537726D02*
X1894803Y537723D01*
G01X1894790Y537727D02*
X1894797Y537726D01*
G01X1894783Y537728D02*
X1894790Y537727D01*
G01X1894813Y540865D02*
X1894817Y540859D01*
G01X1894809Y540869D02*
X1894813Y540865D01*
G01X1894803Y540872D02*
X1894809Y540869D01*
G01X1894797Y540875D02*
X1894803Y540872D01*
G01X1894790Y540877D02*
X1894797Y540875D01*
G01X1894783Y540877D02*
X1894790D01*
G01X1894813Y544014D02*
X1894817Y544009D01*
G01X1894809Y544019D02*
X1894813Y544014D01*
G01X1894803Y544022D02*
X1894809Y544019D01*
G01X1894797Y544025D02*
X1894803Y544022D01*
G01X1894790Y544026D02*
X1894797Y544025D01*
G01X1894783Y544027D02*
X1894790Y544026D01*
G01X1894813Y547164D02*
X1894817Y547158D01*
G01X1894809Y547168D02*
X1894813Y547164D01*
G01X1894803Y547172D02*
X1894809Y547168D01*
G01X1894797Y547174D02*
X1894803Y547172D01*
G01X1894790Y547176D02*
X1894797Y547174D01*
G01X1894783Y547176D02*
X1894790D01*
G01X1894813Y550313D02*
X1894817Y550308D01*
G01X1894809Y550318D02*
X1894813Y550313D01*
G01X1894803Y550321D02*
X1894809Y550318D01*
G01X1894797Y550324D02*
X1894803Y550321D01*
G01X1894790Y550326D02*
X1894797Y550324D01*
G01X1894783Y550326D02*
X1894790D01*
G01X1894813Y553463D02*
X1894817Y553457D01*
G01X1894809Y553467D02*
X1894813Y553463D01*
G01X1894803Y553471D02*
X1894809Y553467D01*
G01X1894797Y553474D02*
X1894803Y553471D01*
G01X1894790Y553475D02*
X1894797Y553474D01*
G01X1894783Y553476D02*
X1894790Y553475D01*
G01X1894813Y556613D02*
X1894817Y556607D01*
G01X1894809Y556617D02*
X1894813Y556613D01*
G01X1894803Y556620D02*
X1894809Y556617D01*
G01X1894797Y556623D02*
X1894803Y556620D01*
G01X1894790Y556625D02*
X1894797Y556623D01*
G01X1894783Y556625D02*
X1894790D01*
G01X1893839Y536554D02*
Y536561D01*
G01X1893842Y536547D02*
X1893839Y536554D01*
G01X1893845Y536541D02*
X1893842Y536547D01*
G01X1893850Y536535D02*
X1893845Y536541D01*
G01X1893856Y536530D02*
X1893850Y536535D01*
G01X1893863Y536527D02*
X1893856Y536530D01*
G01X1893870Y536525D02*
X1893863Y536527D01*
G01X1893878Y536524D02*
X1893870Y536525D01*
G01X1893839Y539704D02*
Y539711D01*
G01X1893842Y539696D02*
X1893839Y539704D01*
G01X1893845Y539690D02*
X1893842Y539696D01*
G01X1893850Y539685D02*
X1893845Y539690D01*
G01X1893856Y539680D02*
X1893850Y539685D01*
G01X1893863Y539676D02*
X1893856Y539680D01*
G01X1893870Y539674D02*
X1893863Y539676D01*
G01X1893878Y539674D02*
X1893870D01*
G01X1893839Y542853D02*
Y542860D01*
G01X1893842Y542846D02*
X1893839Y542853D01*
G01X1893845Y542840D02*
X1893842Y542846D01*
G01X1893850Y542834D02*
X1893845Y542840D01*
G01X1893856Y542830D02*
X1893850Y542834D01*
G01X1893863Y542826D02*
X1893856Y542830D01*
G01X1893870Y542824D02*
X1893863Y542826D01*
G01X1893878Y542823D02*
X1893870Y542824D01*
G01X1893839Y546003D02*
Y546010D01*
G01X1893842Y545996D02*
X1893839Y546003D01*
G01X1893845Y545989D02*
X1893842Y545996D01*
G01X1893850Y545984D02*
X1893845Y545989D01*
G01X1893856Y545979D02*
X1893850Y545984D01*
G01X1893863Y545976D02*
X1893856Y545979D01*
G01X1893870Y545974D02*
X1893863Y545976D01*
G01X1893878Y545973D02*
X1893870Y545974D01*
G01X1893839Y549152D02*
Y549159D01*
G01X1893842Y549145D02*
X1893839Y549152D01*
G01X1893845Y549139D02*
X1893842Y549145D01*
G01X1893850Y549133D02*
X1893845Y549139D01*
G01X1893856Y549129D02*
X1893850Y549133D01*
G01X1893863Y549125D02*
X1893856Y549129D01*
G01X1893870Y549123D02*
X1893863Y549125D01*
G01X1893878Y549122D02*
X1893870Y549123D01*
G01X1893839Y552302D02*
Y552309D01*
G01X1893842Y552295D02*
X1893839Y552302D01*
G01X1893845Y552289D02*
X1893842Y552295D01*
G01X1893850Y552283D02*
X1893845Y552289D01*
G01X1893856Y552278D02*
X1893850Y552283D01*
G01X1893863Y552275D02*
X1893856Y552278D01*
G01X1893870Y552273D02*
X1893863Y552275D01*
G01X1893878Y552272D02*
X1893870Y552273D01*
G01X1893839Y555452D02*
Y555459D01*
G01X1893842Y555444D02*
X1893839Y555452D01*
G01X1893845Y555438D02*
X1893842Y555444D01*
G01X1893850Y555433D02*
X1893845Y555438D01*
G01X1893856Y555428D02*
X1893850Y555433D01*
G01X1893863Y555424D02*
X1893856Y555428D01*
G01X1893870Y555422D02*
X1893863Y555424D01*
G01X1893878Y555422D02*
X1893870D01*
G01X1894793Y537715D02*
X1894802Y537711D01*
G01X1894782Y537717D02*
X1894793Y537715D01*
G01Y540865D02*
X1894802Y540861D01*
G01X1894782Y540866D02*
X1894793Y540865D01*
G01Y544014D02*
X1894802Y544010D01*
G01X1894782Y544016D02*
X1894793Y544014D01*
G01Y547164D02*
X1894802Y547160D01*
G01X1894782Y547165D02*
X1894793Y547164D01*
G01Y550313D02*
X1894802Y550309D01*
G01X1894782Y550315D02*
X1894793Y550313D01*
G01Y553463D02*
X1894802Y553459D01*
G01X1894782Y553465D02*
X1894793Y553463D01*
G01Y556613D02*
X1894802Y556609D01*
G01X1894782Y556614D02*
X1894793Y556613D01*
G01X1893839Y539715D02*
Y539711D01*
G01X1893840Y539708D02*
X1893839Y539715D01*
G01X1893852Y539693D02*
X1893840Y539708D01*
G01X1893877Y539685D02*
X1893852Y539693D01*
G01X1893839Y542864D02*
Y542860D01*
G01X1893840Y542858D02*
X1893839Y542864D01*
G01X1893852Y542843D02*
X1893840Y542858D01*
G01X1893876Y542835D02*
X1893852Y542843D01*
G01X1893839Y549163D02*
Y549159D01*
G01X1893840Y549157D02*
X1893839Y549163D01*
G01X1893852Y549142D02*
X1893840Y549157D01*
G01X1893876Y549134D02*
X1893852Y549142D01*
G01X1893839Y536565D02*
Y536561D01*
G01X1893840Y536559D02*
X1893839Y536565D01*
G01X1893852Y536544D02*
X1893840Y536559D01*
G01X1893876Y536535D02*
X1893852Y536544D01*
G01X1908235Y504755D02*
X1908246Y504740D01*
G01X1908211Y504764D02*
X1908235Y504755D01*
G01Y509755D02*
X1908246Y509740D01*
G01X1908211Y509764D02*
X1908235Y509755D01*
G01Y514755D02*
X1908246Y514740D01*
G01X1908211Y514764D02*
X1908235Y514755D01*
G01Y519755D02*
X1908246Y519740D01*
G01X1908211Y519764D02*
X1908235Y519755D01*
G01Y524755D02*
X1908246Y524740D01*
G01X1908211Y524764D02*
X1908235Y524755D01*
G01Y529755D02*
X1908246Y529740D01*
G01X1908211Y529764D02*
X1908235Y529755D01*
G01X1893839Y552313D02*
Y552309D01*
G01X1893840Y552307D02*
X1893839Y552313D01*
G01X1893852Y552292D02*
X1893840Y552307D01*
G01X1893876Y552283D02*
X1893852Y552292D01*
G01X1893839Y555463D02*
Y555459D01*
G01X1893840Y555457D02*
X1893839Y555463D01*
G01X1893852Y555441D02*
X1893840Y555457D01*
G01X1893876Y555433D02*
X1893852Y555441D01*
G01X1908235Y534755D02*
X1908246Y534740D01*
G01X1908211Y534764D02*
X1908235Y534755D01*
G01Y559755D02*
X1908246Y559740D01*
G01X1908211Y559764D02*
X1908235Y559755D01*
G01Y564755D02*
X1908246Y564740D01*
G01X1908211Y564764D02*
X1908235Y564755D01*
G01Y569755D02*
X1908246Y569740D01*
G01X1908211Y569764D02*
X1908235Y569755D01*
G01X1893839Y546014D02*
Y546010D01*
G01X1893840Y546008D02*
X1893839Y546014D01*
G01X1893850Y545994D02*
X1893840Y546008D01*
G01X1893873Y545984D02*
X1893850Y545994D01*
G01X1894791Y544015D02*
X1894782Y544016D01*
G01X1894800Y544011D02*
X1894791Y544015D01*
G01X1894808Y544006D02*
X1894800Y544011D01*
G01X1894791Y537715D02*
X1894782Y537717D01*
G01X1894800Y537712D02*
X1894791Y537715D01*
G01X1894808Y537707D02*
X1894800Y537712D01*
G01X1894791Y540865D02*
X1894782Y540866D01*
G01X1894800Y540862D02*
X1894791Y540865D01*
G01X1894808Y540856D02*
X1894800Y540862D01*
G01X1894791Y547164D02*
X1894782Y547165D01*
G01X1894800Y547161D02*
X1894791Y547164D01*
G01X1894808Y547156D02*
X1894800Y547161D01*
G01X1894791Y550314D02*
X1894782Y550315D01*
G01X1894800Y550311D02*
X1894791Y550314D01*
G01X1894808Y550305D02*
X1894800Y550311D01*
G01X1894791Y553463D02*
X1894782Y553465D01*
G01X1894800Y553460D02*
X1894791Y553463D01*
G01X1894808Y553455D02*
X1894800Y553460D01*
G01X1894791Y556613D02*
X1894782Y556614D01*
G01X1894800Y556610D02*
X1894791Y556613D01*
G01X1894808Y556604D02*
X1894800Y556610D01*
G01X1893878Y536530D02*
Y536524D01*
G01X1893877Y536534D02*
X1893878Y536530D01*
G01X1893876Y536535D02*
X1893877Y536534D01*
G01X1893878Y539680D02*
Y539674D01*
G01X1893877Y539684D02*
X1893878Y539680D01*
G01X1893876Y539685D02*
X1893877Y539684D01*
G01X1893878Y542830D02*
Y542823D01*
G01X1893877Y542833D02*
X1893878Y542830D01*
G01X1893876Y542835D02*
X1893877Y542833D01*
G01X1893878Y545979D02*
Y545973D01*
G01X1893877Y545983D02*
X1893878Y545979D01*
G01X1893876Y545984D02*
X1893877Y545983D01*
G01X1893878Y549129D02*
Y549122D01*
G01X1893877Y549133D02*
X1893878Y549129D01*
G01X1893876Y549134D02*
X1893877Y549133D01*
G01X1893878Y552278D02*
Y552272D01*
G01X1893877Y552282D02*
X1893878Y552278D01*
G01X1893876Y552283D02*
X1893877Y552282D01*
G01X1893878Y555428D02*
Y555422D01*
G01X1893877Y555432D02*
X1893878Y555428D01*
G01X1893876Y555433D02*
X1893877Y555432D01*
G01X1894794Y555435D02*
X1894782Y555433D01*
G01X1894804Y555440D02*
X1894794Y555435D01*
G01Y552285D02*
X1894782Y552283D01*
G01X1894804Y552290D02*
X1894794Y552285D01*
G01Y549136D02*
X1894782Y549134D01*
G01X1894804Y549141D02*
X1894794Y549136D01*
G01Y545986D02*
X1894782Y545984D01*
G01X1894804Y545991D02*
X1894794Y545986D01*
G01Y542837D02*
X1894782Y542835D01*
G01X1894804Y542841D02*
X1894794Y542837D01*
G01Y539687D02*
X1894782Y539685D01*
G01X1894804Y539692D02*
X1894794Y539687D01*
G01Y536537D02*
X1894782Y536535D01*
G01X1894804Y536542D02*
X1894794Y536537D01*
G01X1908248Y504731D02*
Y504738D01*
G01X1908249Y504726D02*
X1908248Y504731D01*
G01X1908250Y504724D02*
X1908249Y504726D01*
G01X1908248Y509731D02*
Y509738D01*
G01X1908249Y509726D02*
X1908248Y509731D01*
G01X1908250Y509724D02*
X1908249Y509726D01*
G01X1908248Y514731D02*
Y514738D01*
G01X1908249Y514726D02*
X1908248Y514731D01*
G01X1908250Y514724D02*
X1908249Y514726D01*
G01X1908248Y519731D02*
Y519738D01*
G01X1908249Y519726D02*
X1908248Y519731D01*
G01X1908250Y519724D02*
X1908249Y519726D01*
G01X1908248Y524731D02*
Y524738D01*
G01X1908249Y524726D02*
X1908248Y524731D01*
G01X1908250Y524724D02*
X1908249Y524726D01*
G01X1908248Y529731D02*
Y529738D01*
G01X1908249Y529726D02*
X1908248Y529731D01*
G01X1908250Y529724D02*
X1908249Y529726D01*
G01X1908248Y534731D02*
Y534738D01*
G01X1908249Y534726D02*
X1908248Y534731D01*
G01X1908250Y534724D02*
X1908249Y534726D01*
G01X1908248Y559731D02*
Y559738D01*
G01X1908249Y559726D02*
X1908248Y559731D01*
G01X1908250Y559724D02*
X1908249Y559726D01*
G01X1908248Y564731D02*
Y564738D01*
G01X1908249Y564726D02*
X1908248Y564731D01*
G01X1908250Y564724D02*
X1908249Y564726D01*
G01X1908248Y569731D02*
Y569738D01*
G01X1908249Y569726D02*
X1908248Y569731D01*
G01X1908250Y569724D02*
X1908249Y569726D01*
G01X1893861Y539687D02*
X1893876Y539685D01*
G01X1893850Y539694D02*
X1893861Y539687D01*
G01X1893838Y539713D02*
X1893850Y539694D01*
G01X1893861Y549136D02*
X1893876Y549134D01*
G01X1893850Y549144D02*
X1893861Y549136D01*
G01X1893838Y549162D02*
X1893850Y549144D01*
G01X1894820Y555446D02*
X1894823Y555459D01*
G01X1894814Y555435D02*
X1894820Y555446D01*
G01X1894804Y555427D02*
X1894814Y555435D01*
G01X1894820Y549147D02*
X1894823Y549159D01*
G01X1894814Y549136D02*
X1894820Y549147D01*
G01X1894804Y549128D02*
X1894814Y549136D01*
G01X1893877Y556619D02*
Y556625D01*
G01Y556615D02*
Y556619D01*
G01X1893876Y556614D02*
X1893877Y556615D01*
G01Y553469D02*
Y553476D01*
G01Y553466D02*
Y553469D01*
G01X1893876Y553465D02*
X1893877Y553466D01*
G01Y550320D02*
Y550326D01*
G01Y550316D02*
Y550320D01*
G01X1893876Y550315D02*
X1893877Y550316D01*
G01Y547170D02*
Y547176D01*
G01Y547167D02*
Y547170D01*
G01X1893876Y547165D02*
X1893877Y547167D01*
G01Y544020D02*
Y544027D01*
G01Y544017D02*
Y544020D01*
G01X1893876Y544016D02*
X1893877Y544017D01*
G01Y540871D02*
Y540877D01*
G01Y540867D02*
Y540871D01*
G01X1893876Y540866D02*
X1893877Y540867D01*
G01Y537721D02*
Y537728D01*
G01Y537718D02*
Y537721D01*
G01X1893876Y537717D02*
X1893877Y537718D01*
G01X1893839Y556594D02*
Y556588D01*
G01X1893841Y556601D02*
X1893839Y556594D01*
G01X1893844Y556607D02*
X1893841Y556601D01*
G01X1893848Y556612D02*
X1893844Y556607D01*
G01X1893852Y556617D02*
X1893848Y556612D01*
G01X1893858Y556620D02*
X1893852Y556617D01*
G01X1893839Y553445D02*
Y553439D01*
G01X1893841Y553451D02*
X1893839Y553445D01*
G01X1893844Y553457D02*
X1893841Y553451D01*
G01X1893848Y553462D02*
X1893844Y553457D01*
G01X1893852Y553467D02*
X1893848Y553462D01*
G01X1893858Y553470D02*
X1893852Y553467D01*
G01X1893839Y550295D02*
Y550289D01*
G01X1893841Y550302D02*
X1893839Y550295D01*
G01X1893844Y550307D02*
X1893841Y550302D01*
G01X1893848Y550313D02*
X1893844Y550307D01*
G01X1893852Y550317D02*
X1893848Y550313D01*
G01X1893858Y550321D02*
X1893852Y550317D01*
G01X1893839Y547146D02*
Y547139D01*
G01X1893841Y547152D02*
X1893839Y547146D01*
G01X1893844Y547158D02*
X1893841Y547152D01*
G01X1893848Y547163D02*
X1893844Y547158D01*
G01X1893852Y547168D02*
X1893848Y547163D01*
G01X1893858Y547171D02*
X1893852Y547168D01*
G01X1893839Y543996D02*
Y543990D01*
G01X1893841Y544002D02*
X1893839Y543996D01*
G01X1893844Y544008D02*
X1893841Y544002D01*
G01X1893848Y544013D02*
X1893844Y544008D01*
G01X1893852Y544018D02*
X1893848Y544013D01*
G01X1893858Y544022D02*
X1893852Y544018D01*
G01X1893839Y540846D02*
Y540840D01*
G01X1893841Y540853D02*
X1893839Y540846D01*
G01X1893844Y540859D02*
X1893841Y540853D01*
G01X1893848Y540864D02*
X1893844Y540859D01*
G01X1893852Y540869D02*
X1893848Y540864D01*
G01X1893858Y540872D02*
X1893852Y540869D01*
G01X1893839Y537697D02*
Y537691D01*
G01X1893841Y537703D02*
X1893839Y537697D01*
G01X1893844Y537709D02*
X1893841Y537703D01*
G01X1893848Y537714D02*
X1893844Y537709D01*
G01X1893852Y537719D02*
X1893848Y537714D01*
G01X1893858Y537722D02*
X1893852Y537719D01*
G01X1893861Y542837D02*
X1893876Y542835D01*
G01X1893849Y542845D02*
X1893861Y542837D01*
G01X1893837Y542865D02*
X1893849Y542845D01*
G01X1893861Y552286D02*
X1893876Y552283D01*
G01X1893849Y552294D02*
X1893861Y552286D01*
G01X1893837Y552314D02*
X1893849Y552294D01*
G01X1894823Y536569D02*
Y536561D01*
G01X1894822Y536573D02*
X1894823Y536569D01*
G01X1894821Y536575D02*
X1894822Y536573D01*
G01X1894823Y539719D02*
Y539711D01*
G01X1894822Y539723D02*
X1894823Y539719D01*
G01X1894821Y539724D02*
X1894822Y539723D01*
G01X1894823Y542868D02*
Y542860D01*
G01X1894822Y542872D02*
X1894823Y542868D01*
G01X1894821Y542874D02*
X1894822Y542872D01*
G01X1894823Y546018D02*
Y546010D01*
G01X1894822Y546022D02*
X1894823Y546018D01*
G01X1894821Y546024D02*
X1894822Y546022D01*
G01X1894823Y549167D02*
Y549159D01*
G01X1894822Y549172D02*
X1894823Y549167D01*
G01X1894821Y549173D02*
X1894822Y549172D01*
G01X1894823Y552317D02*
Y552309D01*
G01X1894822Y552321D02*
X1894823Y552317D01*
G01X1894821Y552323D02*
X1894822Y552321D01*
G01X1894823Y555467D02*
Y555459D01*
G01X1894822Y555471D02*
X1894823Y555467D01*
G01X1894821Y555472D02*
X1894822Y555471D01*
G01X1893861Y555436D02*
X1893876Y555433D01*
G01X1893848Y555444D02*
X1893861Y555436D01*
G01X1893837Y555464D02*
X1893848Y555444D01*
G01X1893861Y536538D02*
X1893876Y536535D01*
G01X1893848Y536547D02*
X1893861Y536538D01*
G01X1893837Y536567D02*
X1893848Y536547D01*
G01X1894822Y537697D02*
X1894823Y537691D01*
G01X1894820Y537704D02*
X1894822Y537697D01*
G01X1894817Y537709D02*
X1894820Y537704D01*
G01X1894822Y540847D02*
X1894823Y540840D01*
G01X1894820Y540853D02*
X1894822Y540847D01*
G01X1894817Y540859D02*
X1894820Y540853D01*
G01X1894822Y543996D02*
X1894823Y543990D01*
G01X1894820Y544003D02*
X1894822Y543996D01*
G01X1894817Y544009D02*
X1894820Y544003D01*
G01X1894822Y547146D02*
X1894823Y547139D01*
G01X1894820Y547152D02*
X1894822Y547146D01*
G01X1894817Y547158D02*
X1894820Y547152D01*
G01X1894822Y550296D02*
X1894823Y550289D01*
G01X1894820Y550302D02*
X1894822Y550296D01*
G01X1894817Y550308D02*
X1894820Y550302D01*
G01X1894822Y553445D02*
X1894823Y553439D01*
G01X1894820Y553452D02*
X1894822Y553445D01*
G01X1894817Y553457D02*
X1894820Y553452D01*
G01X1894822Y556595D02*
X1894823Y556588D01*
G01X1894820Y556601D02*
X1894822Y556595D01*
G01X1894817Y556607D02*
X1894820Y556601D01*
G01X1894784Y536530D02*
Y536524D01*
G01X1894783Y536534D02*
X1894784Y536530D01*
G01X1894782Y536535D02*
X1894783Y536534D01*
G01X1894784Y539680D02*
Y539674D01*
G01X1894783Y539683D02*
X1894784Y539680D01*
G01X1894782Y539685D02*
X1894783Y539683D01*
G01X1894784Y542830D02*
Y542823D01*
G01X1894783Y542833D02*
X1894784Y542830D01*
G01X1894782Y542835D02*
X1894783Y542833D01*
G01X1894784Y545979D02*
Y545973D01*
G01X1894783Y545983D02*
X1894784Y545979D01*
G01X1894782Y545984D02*
X1894783Y545983D01*
G01X1894784Y549129D02*
Y549122D01*
G01X1894783Y549132D02*
X1894784Y549129D01*
G01X1894782Y549134D02*
X1894783Y549132D01*
G01X1893838Y556581D02*
X1893839Y556588D01*
G01X1893837Y556576D02*
X1893838Y556581D01*
G01X1893836Y556575D02*
X1893837Y556576D01*
G01X1893838Y553431D02*
X1893839Y553439D01*
G01X1893837Y553427D02*
X1893838Y553431D01*
G01X1893836Y553425D02*
X1893837Y553427D01*
G01X1893838Y550281D02*
X1893839Y550289D01*
G01X1893837Y550277D02*
X1893838Y550281D01*
G01X1893836Y550276D02*
X1893837Y550277D01*
G01X1893838Y547132D02*
X1893839Y547139D01*
G01X1893837Y547128D02*
X1893838Y547132D01*
G01X1893836Y547126D02*
X1893837Y547128D01*
G01X1893838Y543982D02*
X1893839Y543990D01*
G01X1893837Y543978D02*
X1893838Y543982D01*
G01X1893836Y543976D02*
X1893837Y543978D01*
G01X1894820Y545998D02*
X1894823Y546010D01*
G01X1894814Y545986D02*
X1894820Y545998D01*
G01X1894804Y545978D02*
X1894814Y545986D01*
G01X1894820Y542848D02*
X1894823Y542860D01*
G01X1894814Y542837D02*
X1894820Y542848D01*
G01X1894804Y542829D02*
X1894814Y542837D01*
G01X1894820Y539698D02*
X1894823Y539711D01*
G01X1894814Y539687D02*
X1894820Y539698D01*
G01X1894804Y539679D02*
X1894814Y539687D01*
G01X1894820Y536549D02*
X1894823Y536561D01*
G01X1894814Y536537D02*
X1894820Y536549D01*
G01X1894804Y536530D02*
X1894814Y536537D01*
G01X1894784Y555428D02*
Y555422D01*
G01X1894783Y555431D02*
X1894784Y555428D01*
G01X1894782Y555433D02*
X1894783Y555431D01*
G01X1907264Y504771D02*
Y504780D01*
G01X1907265Y504765D02*
X1907264Y504771D01*
G01X1907265Y504764D02*
Y504765D01*
G01X1907264Y509771D02*
Y509780D01*
G01X1907265Y509765D02*
X1907264Y509771D01*
G01X1907265Y509764D02*
Y509765D01*
G01X1907264Y514771D02*
Y514780D01*
G01X1907265Y514765D02*
X1907264Y514771D01*
G01X1907265Y514764D02*
Y514765D01*
G01X1907264Y519771D02*
Y519780D01*
G01X1907265Y519765D02*
X1907264Y519771D01*
G01X1907265Y519764D02*
Y519765D01*
G01X1907264Y524771D02*
Y524780D01*
G01X1907265Y524765D02*
X1907264Y524771D01*
G01X1907265Y524764D02*
Y524765D01*
G01X1907264Y529771D02*
Y529780D01*
G01X1907265Y529765D02*
X1907264Y529771D01*
G01X1907265Y529764D02*
Y529765D01*
G01X1907264Y534771D02*
Y534780D01*
G01X1907265Y534765D02*
X1907264Y534771D01*
G01X1907265Y534764D02*
Y534765D01*
G01X1907264Y559771D02*
Y559780D01*
G01X1907265Y559765D02*
X1907264Y559771D01*
G01X1907265Y559764D02*
Y559765D01*
G01X1907264Y564771D02*
Y564780D01*
G01X1907265Y564765D02*
X1907264Y564771D01*
G01X1907265Y564764D02*
Y564765D01*
G01X1907264Y569771D02*
Y569780D01*
G01X1907265Y569765D02*
X1907264Y569771D01*
G01X1907265Y569764D02*
Y569765D01*
G01X1908240Y504907D02*
X1908248Y504881D01*
G01X1908230Y504934D02*
X1908240Y504907D01*
G01X1908219Y504961D02*
X1908230Y504934D01*
G01X1908240Y509907D02*
X1908248Y509881D01*
G01X1908230Y509934D02*
X1908240Y509907D01*
G01X1908219Y509961D02*
X1908230Y509934D01*
G01X1908240Y514907D02*
X1908248Y514881D01*
G01X1908230Y514934D02*
X1908240Y514907D01*
G01X1908219Y514961D02*
X1908230Y514934D01*
G01X1908240Y519907D02*
X1908248Y519881D01*
G01X1908230Y519934D02*
X1908240Y519907D01*
G01X1908219Y519961D02*
X1908230Y519934D01*
G01X1908240Y524907D02*
X1908248Y524881D01*
G01X1908230Y524934D02*
X1908240Y524907D01*
G01X1908219Y524961D02*
X1908230Y524934D01*
G01X1908240Y529907D02*
X1908248Y529881D01*
G01X1908230Y529934D02*
X1908240Y529907D01*
G01X1908219Y529961D02*
X1908230Y529934D01*
G01X1908240Y534907D02*
X1908248Y534881D01*
G01X1908230Y534934D02*
X1908240Y534907D01*
G01X1908219Y534961D02*
X1908230Y534934D01*
G01X1908240Y559907D02*
X1908248Y559881D01*
G01X1908230Y559934D02*
X1908240Y559907D01*
G01X1908219Y559961D02*
X1908230Y559934D01*
G01X1908240Y564907D02*
X1908248Y564881D01*
G01X1908230Y564934D02*
X1908240Y564907D01*
G01X1908219Y564961D02*
X1908230Y564934D01*
G01X1908240Y569907D02*
X1908248Y569881D01*
G01X1908230Y569934D02*
X1908240Y569907D01*
G01X1908219Y569961D02*
X1908230Y569934D01*
G01X1893856Y545989D02*
X1893876Y545984D01*
G01X1893843Y546002D02*
X1893856Y545989D01*
G01X1893836Y546019D02*
X1893843Y546002D01*
G01X1894783Y556619D02*
Y556625D01*
G01Y556615D02*
Y556619D01*
G01X1894782Y556614D02*
X1894783Y556615D01*
G01Y553470D02*
Y553476D01*
G01Y553466D02*
Y553470D01*
G01X1894782Y553465D02*
X1894783Y553466D01*
G01Y550320D02*
Y550326D01*
G01Y550316D02*
Y550320D01*
G01X1894782Y550315D02*
X1894783Y550316D01*
G01Y547170D02*
Y547176D01*
G01Y547167D02*
Y547170D01*
G01X1894782Y547165D02*
X1894783Y547167D01*
G01Y544021D02*
Y544027D01*
G01Y544017D02*
Y544021D01*
G01X1894782Y544016D02*
X1894783Y544017D01*
G01Y540871D02*
Y540877D01*
G01Y540867D02*
Y540871D01*
G01X1894782Y540866D02*
X1894783Y540867D01*
G01Y537722D02*
Y537728D01*
G01Y537718D02*
Y537722D01*
G01X1894782Y537717D02*
X1894783Y537718D01*
G01X1908248Y568378D02*
Y568369D01*
G01X1908249Y568384D02*
X1908248Y568378D01*
G01X1908251Y568386D02*
X1908249Y568384D01*
G01X1908248Y563378D02*
Y563369D01*
G01X1908249Y563384D02*
X1908248Y563378D01*
G01X1908251Y563386D02*
X1908249Y563384D01*
G01X1908248Y558378D02*
Y558369D01*
G01X1908249Y558384D02*
X1908248Y558378D01*
G01X1908251Y558386D02*
X1908249Y558384D01*
G01X1908248Y533378D02*
Y533369D01*
G01X1908249Y533384D02*
X1908248Y533378D01*
G01X1908251Y533386D02*
X1908249Y533384D01*
G01X1908248Y528378D02*
Y528369D01*
G01X1908249Y528384D02*
X1908248Y528378D01*
G01X1908251Y528386D02*
X1908249Y528384D01*
G01X1908248Y523378D02*
Y523369D01*
G01X1908249Y523384D02*
X1908248Y523378D01*
G01X1908251Y523386D02*
X1908249Y523384D01*
G01X1908248Y518378D02*
Y518369D01*
G01X1908249Y518384D02*
X1908248Y518378D01*
G01X1908251Y518386D02*
X1908249Y518384D01*
G01X1908248Y513378D02*
Y513369D01*
G01X1908249Y513384D02*
X1908248Y513378D01*
G01X1908251Y513386D02*
X1908249Y513384D01*
G01X1908248Y508378D02*
Y508369D01*
G01X1908249Y508384D02*
X1908248Y508378D01*
G01X1908251Y508386D02*
X1908249Y508384D01*
G01X1908248Y503378D02*
Y503369D01*
G01X1908249Y503384D02*
X1908248Y503378D01*
G01X1908251Y503386D02*
X1908249Y503384D01*
G01X1893838Y540833D02*
X1893839Y540840D01*
G01X1893837Y540828D02*
X1893838Y540833D01*
G01X1893836Y540827D02*
X1893837Y540828D01*
G01X1893838Y537683D02*
X1893839Y537691D01*
G01X1893837Y537679D02*
X1893838Y537683D01*
G01X1893836Y537677D02*
X1893837Y537679D01*
G01X1908231Y504759D02*
X1908211Y504764D01*
G01X1908245Y504744D02*
X1908231Y504759D01*
G01X1908250Y504724D02*
X1908245Y504744D01*
G01X1908231Y509759D02*
X1908211Y509764D01*
G01X1908245Y509744D02*
X1908231Y509759D01*
G01X1908250Y509724D02*
X1908245Y509744D01*
G01X1908231Y514759D02*
X1908211Y514764D01*
G01X1908245Y514744D02*
X1908231Y514759D01*
G01X1908250Y514724D02*
X1908245Y514744D01*
G01X1908231Y519759D02*
X1908211Y519764D01*
G01X1908245Y519744D02*
X1908231Y519759D01*
G01X1908250Y519724D02*
X1908245Y519744D01*
G01X1908231Y524759D02*
X1908211Y524764D01*
G01X1908245Y524744D02*
X1908231Y524759D01*
G01X1908250Y524724D02*
X1908245Y524744D01*
G01X1908231Y529759D02*
X1908211Y529764D01*
G01X1908245Y529744D02*
X1908231Y529759D01*
G01X1908250Y529724D02*
X1908245Y529744D01*
G01X1908231Y534759D02*
X1908211Y534764D01*
G01X1908245Y534744D02*
X1908231Y534759D01*
G01X1908250Y534724D02*
X1908245Y534744D01*
G01X1908231Y559759D02*
X1908211Y559764D01*
G01X1908245Y559744D02*
X1908231Y559759D01*
G01X1908250Y559724D02*
X1908245Y559744D01*
G01X1908231Y564759D02*
X1908211Y564764D01*
G01X1908245Y564744D02*
X1908231Y564759D01*
G01X1908250Y564724D02*
X1908245Y564744D01*
G01X1908231Y569759D02*
X1908211Y569764D01*
G01X1908245Y569744D02*
X1908231Y569759D01*
G01X1908250Y569724D02*
X1908245Y569744D01*
G01X1894815Y543998D02*
X1894808Y544006D01*
G01X1894820Y543987D02*
X1894815Y543998D01*
G01X1894822Y543976D02*
X1894820Y543987D01*
G01X1894815Y537698D02*
X1894808Y537707D01*
G01X1894820Y537688D02*
X1894815Y537698D01*
G01X1894822Y537677D02*
X1894820Y537688D01*
G01X1894815Y540848D02*
X1894808Y540856D01*
G01X1894820Y540838D02*
X1894815Y540848D01*
G01X1894822Y540827D02*
X1894820Y540838D01*
G01X1894815Y547147D02*
X1894808Y547156D01*
G01X1894820Y547137D02*
X1894815Y547147D01*
G01X1894822Y547126D02*
X1894820Y547137D01*
G01X1894815Y550297D02*
X1894808Y550305D01*
G01X1894820Y550287D02*
X1894815Y550297D01*
G01X1894822Y550276D02*
X1894820Y550287D01*
G01X1894815Y553446D02*
X1894808Y553455D01*
G01X1894820Y553436D02*
X1894815Y553446D01*
G01X1894822Y553425D02*
X1894820Y553436D01*
G01X1894815Y556596D02*
X1894808Y556604D01*
G01X1894820Y556586D02*
X1894815Y556596D01*
G01X1894822Y556575D02*
X1894820Y556586D01*
G01X1908215Y504862D02*
X1908219Y504961D01*
G01X1908209Y504790D02*
X1908215Y504862D01*
G01X1908211Y504764D02*
X1908209Y504790D01*
G01X1908215Y509862D02*
X1908219Y509961D01*
G01X1908209Y509790D02*
X1908215Y509862D01*
G01X1908211Y509764D02*
X1908209Y509790D01*
G01X1908215Y514862D02*
X1908219Y514961D01*
G01X1908209Y514790D02*
X1908215Y514862D01*
G01X1908211Y514764D02*
X1908209Y514790D01*
G01X1908215Y519862D02*
X1908219Y519961D01*
G01X1908209Y519790D02*
X1908215Y519862D01*
G01X1908211Y519764D02*
X1908209Y519790D01*
G01X1908215Y524862D02*
X1908219Y524961D01*
G01X1908209Y524790D02*
X1908215Y524862D01*
G01X1908211Y524764D02*
X1908209Y524790D01*
G01X1908215Y529862D02*
X1908219Y529961D01*
G01X1908209Y529790D02*
X1908215Y529862D01*
G01X1908211Y529764D02*
X1908209Y529790D01*
G01X1908215Y534862D02*
X1908219Y534961D01*
G01X1908209Y534790D02*
X1908215Y534862D01*
G01X1908211Y534764D02*
X1908209Y534790D01*
G01X1908215Y559862D02*
X1908219Y559961D01*
G01X1908209Y559790D02*
X1908215Y559862D01*
G01X1908211Y559764D02*
X1908209Y559790D01*
G01X1908215Y564862D02*
X1908219Y564961D01*
G01X1908209Y564790D02*
X1908215Y564862D01*
G01X1908211Y564764D02*
X1908209Y564790D01*
G01X1908215Y569862D02*
X1908219Y569961D01*
G01X1908209Y569790D02*
X1908215Y569862D01*
G01X1908211Y569764D02*
X1908209Y569790D01*
G01X1893838Y549167D02*
X1893839Y549160D01*
G01X1893837Y549172D02*
X1893838Y549167D01*
G01Y549162D02*
X1893837Y549172D01*
G01X1893879Y556798D02*
X1893878Y556811D01*
G01X1893876Y556785D02*
X1893879Y556798D01*
G01X1893876Y556772D02*
Y556785D01*
G01X1893879Y553649D02*
X1893878Y553661D01*
G01X1893876Y553636D02*
X1893879Y553649D01*
G01X1893876Y553622D02*
Y553636D01*
G01X1893879Y550499D02*
X1893878Y550512D01*
G01X1893876Y550486D02*
X1893879Y550499D01*
G01X1893876Y550472D02*
Y550486D01*
G01X1893879Y547350D02*
X1893878Y547362D01*
G01X1893876Y547337D02*
X1893879Y547350D01*
G01X1893876Y547323D02*
Y547337D01*
G01X1893879Y544200D02*
X1893878Y544213D01*
G01X1893876Y544187D02*
X1893879Y544200D01*
G01X1893876Y544173D02*
Y544187D01*
G01X1893879Y541050D02*
X1893878Y541063D01*
G01X1893876Y541037D02*
X1893879Y541050D01*
G01X1893876Y541024D02*
Y541037D01*
G01X1893879Y537901D02*
X1893878Y537913D01*
G01X1893876Y537888D02*
X1893879Y537901D01*
G01X1893876Y537874D02*
Y537888D01*
G01X1907265Y568384D02*
Y568386D01*
G01X1907264Y568378D02*
X1907265Y568384D01*
G01X1907264Y568370D02*
Y568378D01*
G01X1907265Y563384D02*
Y563386D01*
G01X1907264Y563378D02*
X1907265Y563384D01*
G01X1907264Y563370D02*
Y563378D01*
G01X1907265Y558384D02*
Y558386D01*
G01X1907264Y558378D02*
X1907265Y558384D01*
G01X1907264Y558370D02*
Y558378D01*
G01X1907265Y533384D02*
Y533386D01*
G01X1907264Y533378D02*
X1907265Y533384D01*
G01X1907264Y533370D02*
Y533378D01*
G01X1907265Y528384D02*
Y528386D01*
G01X1907264Y528378D02*
X1907265Y528384D01*
G01X1907264Y528370D02*
Y528378D01*
G01X1907265Y523384D02*
Y523386D01*
G01X1907264Y523378D02*
X1907265Y523384D01*
G01X1907264Y523370D02*
Y523378D01*
G01X1907265Y518384D02*
Y518386D01*
G01X1907264Y518378D02*
X1907265Y518384D01*
G01X1907264Y518370D02*
Y518378D01*
G01X1907265Y513384D02*
Y513386D01*
G01X1907264Y513378D02*
X1907265Y513384D01*
G01X1907264Y513370D02*
Y513378D01*
G01X1907265Y508384D02*
Y508386D01*
G01X1907264Y508378D02*
X1907265Y508384D01*
G01X1907264Y508370D02*
Y508378D01*
G01X1907265Y503384D02*
Y503386D01*
G01X1907264Y503378D02*
X1907265Y503384D01*
G01X1907264Y503370D02*
Y503378D01*
G01X1893838Y555467D02*
X1893839Y555459D01*
G01X1893837Y555471D02*
X1893838Y555467D01*
G01X1893837Y555463D02*
Y555471D01*
G01X1893876Y555261D02*
X1893874Y555275D01*
G01X1893879Y555249D02*
X1893876Y555261D01*
G01X1893878Y555236D02*
X1893879Y555249D01*
G01X1893876Y552112D02*
X1893874Y552126D01*
G01X1893879Y552099D02*
X1893876Y552112D01*
G01X1893878Y552087D02*
X1893879Y552099D01*
G01X1893876Y548962D02*
X1893874Y548976D01*
G01X1893879Y548950D02*
X1893876Y548962D01*
G01X1893878Y548937D02*
X1893879Y548950D01*
G01X1893876Y545813D02*
X1893874Y545826D01*
G01X1893879Y545800D02*
X1893876Y545813D01*
G01X1893878Y545787D02*
X1893879Y545800D01*
G01X1893876Y542663D02*
X1893874Y542677D01*
G01X1893879Y542650D02*
X1893876Y542663D01*
G01X1893878Y542638D02*
X1893879Y542650D01*
G01X1893876Y539513D02*
X1893874Y539527D01*
G01X1893879Y539501D02*
X1893876Y539513D01*
G01X1893878Y539488D02*
X1893879Y539501D01*
G01X1893876Y536364D02*
X1893874Y536378D01*
G01X1893879Y536351D02*
X1893876Y536364D01*
G01X1893878Y536339D02*
X1893879Y536351D01*
G01X1894786Y556785D02*
X1894787Y556772D01*
G01X1894783Y556798D02*
X1894786Y556785D01*
G01X1894783Y556811D02*
Y556798D01*
G01X1894786Y553636D02*
X1894787Y553622D01*
G01X1894783Y553649D02*
X1894786Y553636D01*
G01X1894783Y553661D02*
Y553649D01*
G01X1894786Y550486D02*
X1894787Y550472D01*
G01X1894783Y550499D02*
X1894786Y550486D01*
G01X1894783Y550512D02*
Y550499D01*
G01X1894786Y547337D02*
X1894787Y547323D01*
G01X1894783Y547350D02*
X1894786Y547337D01*
G01X1894783Y547362D02*
Y547350D01*
G01X1894786Y544187D02*
X1894787Y544173D01*
G01X1894783Y544200D02*
X1894786Y544187D01*
G01X1894783Y544213D02*
Y544200D01*
G01X1894786Y541037D02*
X1894787Y541024D01*
G01X1894783Y541050D02*
X1894786Y541037D01*
G01X1894783Y541063D02*
Y541050D01*
G01X1894786Y537888D02*
X1894787Y537874D01*
G01X1894783Y537901D02*
X1894786Y537888D01*
G01X1894783Y537913D02*
Y537901D01*
G01X1893838Y542868D02*
X1893839Y542861D01*
G01X1893837Y542872D02*
X1893838Y542868D01*
G01X1893837Y542865D02*
Y542872D01*
G01X1893838Y552317D02*
X1893839Y552309D01*
G01X1893837Y552321D02*
X1893838Y552317D01*
G01X1893837Y552314D02*
Y552321D01*
G01X1894783Y555249D02*
Y555236D01*
G01X1894785Y555261D02*
X1894783Y555249D01*
G01X1894787Y555275D02*
X1894785Y555261D01*
G01X1894783Y552099D02*
Y552087D01*
G01X1894785Y552112D02*
X1894783Y552099D01*
G01X1894787Y552126D02*
X1894785Y552112D01*
G01X1894783Y548950D02*
Y548937D01*
G01X1894785Y548962D02*
X1894783Y548950D01*
G01X1894787Y548976D02*
X1894785Y548962D01*
G01X1894783Y545800D02*
Y545787D01*
G01X1894785Y545813D02*
X1894783Y545800D01*
G01X1894787Y545826D02*
X1894785Y545813D01*
G01X1894783Y542650D02*
Y542638D01*
G01X1894785Y542663D02*
X1894783Y542650D01*
G01X1894787Y542677D02*
X1894785Y542663D01*
G01X1894783Y539501D02*
Y539488D01*
G01X1894785Y539513D02*
X1894783Y539501D01*
G01X1894787Y539527D02*
X1894785Y539513D01*
G01X1894783Y536351D02*
Y536339D01*
G01X1894785Y536364D02*
X1894783Y536351D01*
G01X1894787Y536378D02*
X1894785Y536364D01*
G01X1893838Y536569D02*
X1893839Y536561D01*
G01X1893837Y536573D02*
X1893838Y536569D01*
G01X1893837Y536567D02*
Y536573D01*
G01X1893852Y556606D02*
X1893876Y556614D01*
G01X1893841Y556591D02*
X1893852Y556606D01*
G01X1893839Y556584D02*
X1893841Y556591D01*
G01X1893852Y553456D02*
X1893876Y553465D01*
G01X1893841Y553441D02*
X1893852Y553456D01*
G01X1893839Y553435D02*
X1893841Y553441D01*
G01X1893852Y550306D02*
X1893876Y550315D01*
G01X1893841Y550292D02*
X1893852Y550306D01*
G01X1893839Y550285D02*
X1893841Y550292D01*
G01X1893852Y547157D02*
X1893876Y547165D01*
G01X1893841Y547142D02*
X1893852Y547157D01*
G01X1893839Y547135D02*
X1893841Y547142D01*
G01X1893852Y544007D02*
X1893876Y544016D01*
G01X1893841Y543993D02*
X1893852Y544007D01*
G01X1893839Y543986D02*
X1893841Y543993D01*
G01X1893852Y540857D02*
X1893876Y540866D01*
G01X1893841Y540843D02*
X1893852Y540857D01*
G01X1893839Y540836D02*
X1893841Y540843D01*
G01X1893852Y537708D02*
X1893876Y537717D01*
G01X1893841Y537693D02*
X1893852Y537708D01*
G01X1893839Y537687D02*
X1893841Y537693D01*
G01X1894823Y556581D02*
Y556588D01*
G01X1894822Y556576D02*
X1894823Y556581D01*
G01X1894822Y556575D02*
Y556576D01*
G01X1894823Y553431D02*
Y553439D01*
G01X1894822Y553427D02*
X1894823Y553431D01*
G01X1894822Y553425D02*
Y553427D01*
G01X1894823Y550282D02*
Y550289D01*
G01X1894822Y550277D02*
X1894823Y550282D01*
G01X1894822Y550276D02*
Y550277D01*
G01X1894823Y547132D02*
Y547139D01*
G01X1894822Y547128D02*
X1894823Y547132D01*
G01X1894822Y547126D02*
Y547128D01*
G01X1894823Y543983D02*
Y543990D01*
G01X1894822Y543978D02*
X1894823Y543983D01*
G01X1894822Y543976D02*
Y543978D01*
G01X1894823Y540833D02*
Y540840D01*
G01X1894822Y540828D02*
X1894823Y540833D01*
G01X1894822Y540827D02*
Y540828D01*
G01X1894823Y537683D02*
Y537691D01*
G01X1894822Y537679D02*
X1894823Y537683D01*
G01X1894822Y537677D02*
Y537679D01*
G01X1893838Y546018D02*
X1893839Y546010D01*
G01X1893837Y546022D02*
X1893838Y546018D01*
G01X1893836Y546019D02*
X1893837Y546022D01*
G01X1893838Y539719D02*
X1893839Y539711D01*
G01X1893837Y539723D02*
X1893838Y539719D01*
G01X1893836Y539721D02*
X1893837Y539723D01*
G01X1903858Y492264D02*
G03I-1102J0D01*
G01X1905315Y486988D02*
G03X1906496Y488169I0J1181D01*
G01X1899016D02*
G03X1900197Y486988I1181J0D01*
G01X1904331Y492264D02*
G03I-1575J0D01*
G01X1898819Y477894D02*
G03X1899409Y477303I591J0D01*
G01X1906102D02*
G03X1906693Y477894I0J591D01*
G01X1903937Y479075D02*
G03Y481043I0J984D01*
G01X1901575D02*
G03Y479075I0J-984D01*
G01X1891929Y478484D02*
G03X1893898Y476516I1968J0D01*
G01X1911614D02*
G03X1913583Y478484I1J1968D01*
G01X1905241Y495335D02*
X1903937Y493366D01*
G01X1899265Y487444D02*
X1901575Y491673D01*
G01X1894822Y537679D02*
X1894823Y537691D01*
G01X1894822Y540829D02*
X1894823Y540840D01*
G01X1894822Y543978D02*
X1894823Y543990D01*
G01X1894822Y547128D02*
X1894823Y547139D01*
G01X1894822Y550278D02*
X1894823Y550289D01*
G01X1894822Y553427D02*
X1894823Y553439D01*
G01X1894822Y556577D02*
X1894823Y556588D01*
G01X1908248Y504738D02*
Y504746D01*
G01Y509738D02*
Y509746D01*
G01Y514738D02*
Y514746D01*
G01Y519738D02*
Y519746D01*
G01Y524738D02*
Y524746D01*
G01Y529738D02*
Y529746D01*
G01Y534738D02*
Y534746D01*
G01Y559738D02*
Y559746D01*
G01Y564738D02*
Y564746D01*
G01Y569738D02*
Y569746D01*
G01X1910236Y635571D02*
Y497579D01*
G01X1909646Y637815D02*
Y495335D01*
G01X1909429Y504764D02*
Y503386D01*
G01Y509764D02*
Y508386D01*
G01Y514764D02*
Y513386D01*
G01Y519764D02*
Y518386D01*
G01Y524764D02*
Y523386D01*
G01Y529764D02*
Y528386D01*
G01Y534764D02*
Y533386D01*
G01Y559764D02*
Y558386D01*
G01Y564764D02*
Y563386D01*
G01Y569764D02*
Y568386D01*
G01X1908858Y557618D02*
Y535531D01*
G01X1908248Y504738D02*
Y504881D01*
G01Y514738D02*
Y514881D01*
G01Y509738D02*
Y509881D01*
G01Y524738D02*
Y524881D01*
G01Y519738D02*
Y519881D01*
G01Y534738D02*
Y534881D01*
G01Y529738D02*
Y529881D01*
G01Y564738D02*
Y564881D01*
G01Y559738D02*
Y559881D01*
G01Y567894D02*
Y570256D01*
G01Y562894D02*
Y565256D01*
G01Y557894D02*
Y560256D01*
G01Y532894D02*
Y535256D01*
G01Y527894D02*
Y530256D01*
G01Y522894D02*
Y525256D01*
G01Y517894D02*
Y520256D01*
G01Y512894D02*
Y515256D01*
G01Y507894D02*
Y510256D01*
G01Y502894D02*
Y505256D01*
G01X1907677Y556437D02*
Y536713D01*
G01X1907264Y505256D02*
Y502894D01*
G01Y510256D02*
Y507894D01*
G01Y515256D02*
Y512894D01*
G01Y520256D02*
Y517894D01*
G01Y525256D02*
Y522894D01*
G01Y530256D02*
Y527894D01*
G01Y535256D02*
Y532894D01*
G01Y560256D02*
Y557894D01*
G01Y565256D02*
Y562894D01*
G01Y570256D02*
Y567894D01*
G01X1906693Y483996D02*
Y477894D01*
G01X1906496Y496713D02*
Y488169D01*
G01X1904921Y535531D02*
Y499075D01*
G01Y634075D02*
Y557618D01*
G01X1903937Y493366D02*
Y491673D01*
G01X1903740Y536713D02*
Y500256D01*
G01Y632894D02*
Y556437D01*
G01X1901575Y491673D02*
Y493366D01*
G01X1899016Y488169D02*
Y496713D01*
G01X1898819Y483996D02*
Y477894D01*
G01X1898228Y500256D02*
Y632894D01*
G01X1897047Y499075D02*
Y634075D01*
G01X1895276Y534370D02*
Y495335D01*
G01Y637815D02*
Y558780D01*
G01X1894823Y555275D02*
Y556772D01*
G01Y552126D02*
Y553622D01*
G01Y548976D02*
Y550472D01*
G01Y545826D02*
Y547323D01*
G01Y542677D02*
Y544173D01*
G01Y539527D02*
Y541024D01*
G01Y536378D02*
Y537874D01*
G01X1894783Y536524D02*
Y536377D01*
G01Y539674D02*
Y539527D01*
G01Y541024D02*
Y540877D01*
G01Y537874D02*
Y537728D01*
G01Y545973D02*
Y545826D01*
G01Y542823D02*
Y542676D01*
G01Y544174D02*
Y544027D01*
G01Y549122D02*
Y548976D01*
G01Y550473D02*
Y550326D01*
G01Y547323D02*
Y547176D01*
G01Y555422D02*
Y555275D01*
G01Y552272D02*
Y552125D01*
G01Y553622D02*
Y553476D01*
G01Y556772D02*
Y556625D01*
G01X1893878D02*
Y556772D01*
G01Y555275D02*
Y555422D01*
G01Y552125D02*
Y552272D01*
G01Y553476D02*
Y553622D01*
G01Y548976D02*
Y549122D01*
G01Y550326D02*
Y550473D01*
G01Y547176D02*
Y547323D01*
G01Y545826D02*
Y545973D01*
G01Y542676D02*
Y542823D01*
G01Y544027D02*
Y544174D01*
G01Y539527D02*
Y539674D01*
G01Y540877D02*
Y541024D01*
G01Y537728D02*
Y537874D01*
G01Y536377D02*
Y536524D01*
G01X1893839Y541024D02*
Y539528D01*
G01Y537874D02*
Y536378D01*
G01Y544173D02*
Y542677D01*
G01Y550472D02*
Y548976D01*
G01Y547323D02*
Y545827D01*
G01Y553622D02*
Y552126D01*
G01Y556772D02*
Y555276D01*
G01X1892657Y537717D02*
Y536535D01*
G01Y540866D02*
Y539685D01*
G01Y547165D02*
Y545984D01*
G01Y544016D02*
Y542835D01*
G01Y550315D02*
Y549134D01*
G01Y556614D02*
Y555433D01*
G01Y553465D02*
Y552283D01*
G01X1892323Y558780D02*
Y534370D01*
G01X1891929D02*
Y558780D01*
G01Y494232D02*
Y478484D01*
G01X1888898Y555433D02*
Y556614D01*
G01Y552283D02*
Y553465D01*
G01Y549134D02*
Y550315D01*
G01Y545984D02*
Y547165D01*
G01Y542835D02*
Y544016D01*
G01Y539685D02*
Y540866D01*
G01Y536535D02*
Y537717D01*
G01X1894823Y555459D02*
X1894822Y555470D01*
G01X1894823Y552309D02*
X1894822Y552320D01*
G01X1894823Y549160D02*
X1894822Y549170D01*
G01X1894823Y546010D02*
X1894822Y546021D01*
G01X1894823Y542861D02*
X1894822Y542871D01*
G01X1894823Y539711D02*
X1894822Y539722D01*
G01X1894823Y536561D02*
X1894822Y536572D01*
G01X1898228Y500256D02*
X1897047Y499075D01*
G01X1895276Y497579D02*
X1891929Y494232D01*
G01X1894782Y552283D02*
X1894785Y552272D01*
G01X1907677Y556437D02*
X1908858Y557618D01*
G01X1903740Y556437D02*
X1904921Y557618D01*
G01X1903937Y491673D02*
X1906247Y487444D01*
G01X1901575Y493366D02*
X1900271Y495335D01*
G01X1907677Y536713D02*
X1908858Y535531D01*
G01X1903740Y536713D02*
X1904921Y535531D01*
G01X1913583Y494232D02*
X1910236Y497579D01*
G01X1903740Y500256D02*
X1904921Y499075D01*
G01X1893725Y555472D02*
X1893837Y555464D01*
G01X1893836Y546019D02*
X1893725Y546024D01*
G01X1893836Y539721D02*
X1893725Y539724D01*
G01X1893836Y549170D02*
X1893725Y549173D01*
G01X1908248Y570256D02*
X1907264D01*
G01X1907265Y569764D02*
X1912598D01*
G01Y569724D02*
X1908250D01*
G01X1912598Y568386D02*
X1907265D01*
G01X1907264Y567894D02*
X1908248D01*
G01Y565256D02*
X1907264D01*
G01X1907265Y564764D02*
X1912598D01*
G01Y564724D02*
X1908250D01*
G01X1912598Y563386D02*
X1907265D01*
G01X1907264Y562894D02*
X1908248D01*
G01Y560256D02*
X1907264D01*
G01X1907265Y559764D02*
X1912598D01*
G01Y559724D02*
X1908250D01*
G01X1895276Y558780D02*
X1891929D01*
G01X1912598Y558386D02*
X1907265D01*
G01X1907264Y557894D02*
X1908248D01*
G01X1904921Y557618D02*
X1908858D01*
G01X1894783Y556811D02*
X1893878D01*
G01X1894823Y556772D02*
X1893839D01*
G01X1894782Y556614D02*
X1888898D01*
G01Y556575D02*
X1894822D01*
G01X1903740Y556437D02*
X1907677D01*
G01X1894821Y555472D02*
X1888898D01*
G01X1894782Y555433D02*
X1888898D01*
G01X1893839Y555276D02*
X1894823D01*
G01X1893878Y555236D02*
X1894783D01*
G01Y553661D02*
X1893878D01*
G01X1894823Y553622D02*
X1893839D01*
G01X1894782Y553465D02*
X1888898D01*
G01Y553425D02*
X1894822D01*
G01X1894821Y552323D02*
X1888898D01*
G01X1894782Y552283D02*
X1888898D01*
G01X1893839Y552126D02*
X1894823D01*
G01X1893878Y552087D02*
X1894783D01*
G01Y550512D02*
X1893878D01*
G01X1894823Y550472D02*
X1893839D01*
G01X1894782Y550315D02*
X1888898D01*
G01Y550276D02*
X1894822D01*
G01X1893091Y549173D02*
X1892657D01*
G01X1894821D02*
X1888898D01*
G01X1894782Y549134D02*
X1888898D01*
G01X1893839Y548976D02*
X1894823D01*
G01X1893878Y548937D02*
X1894783D01*
G01Y547362D02*
X1893878D01*
G01X1894823Y547323D02*
X1893839D01*
G01X1894782Y547165D02*
X1888898D01*
G01Y547126D02*
X1894822D01*
G01X1893091Y546024D02*
X1892657D01*
G01X1894821D02*
X1888898D01*
G01X1894782Y545984D02*
X1888898D01*
G01X1893839Y545827D02*
X1894823D01*
G01X1893878Y545787D02*
X1894783D01*
G01Y544213D02*
X1893878D01*
G01X1894823Y544173D02*
X1893839D01*
G01X1894782Y544016D02*
X1888898D01*
G01Y543976D02*
X1894822D01*
G01X1894821Y542874D02*
X1888898D01*
G01X1894782Y542835D02*
X1888898D01*
G01X1893839Y542677D02*
X1894823D01*
G01X1893878Y542638D02*
X1894783D01*
G01Y541063D02*
X1893878D01*
G01X1894823Y541024D02*
X1893839D01*
G01X1894782Y540866D02*
X1888898D01*
G01Y540827D02*
X1894822D01*
G01X1893091Y539724D02*
X1892657D01*
G01X1894821D02*
X1888898D01*
G01X1894782Y539685D02*
X1888898D01*
G01X1893839Y539528D02*
X1894823D01*
G01X1893878Y539488D02*
X1894783D01*
G01Y537913D02*
X1893878D01*
G01X1894823Y537874D02*
X1893839D01*
G01X1894782Y537717D02*
X1888898D01*
G01Y537677D02*
X1894822D01*
G01X1907677Y536713D02*
X1903740D01*
G01X1894821Y536575D02*
X1888898D01*
G01X1894782Y536535D02*
X1888898D01*
G01X1893839Y536378D02*
X1894823D01*
G01X1893878Y536339D02*
X1894783D01*
G01X1908858Y535531D02*
X1904921D01*
G01X1908248Y535256D02*
X1907264D01*
G01X1907265Y534764D02*
X1912598D01*
G01Y534724D02*
X1908250D01*
G01X1895276Y534370D02*
X1891929D01*
G01X1912598Y533386D02*
X1907265D01*
G01X1907264Y532894D02*
X1908248D01*
G01Y530256D02*
X1907264D01*
G01X1907265Y529764D02*
X1912598D01*
G01Y529724D02*
X1908250D01*
G01X1912598Y528386D02*
X1907265D01*
G01X1907264Y569959D02*
X1908219Y569961D01*
G01X1908248Y568190D02*
X1907264Y568189D01*
G01Y564959D02*
X1908219Y564961D01*
G01X1908248Y563190D02*
X1907264Y563189D01*
G01Y559959D02*
X1908219Y559961D01*
G01X1908248Y558190D02*
X1907264Y558189D01*
G01Y534959D02*
X1908219Y534961D01*
G01X1908248Y533190D02*
X1907264Y533189D01*
G01Y529959D02*
X1908219Y529961D01*
G01X1907264Y527894D02*
X1908248D01*
G01Y525256D02*
X1907264D01*
G01X1907265Y524764D02*
X1912598D01*
G01Y524724D02*
X1908250D01*
G01X1912598Y523386D02*
X1907265D01*
G01X1907264Y522894D02*
X1908248D01*
G01Y520256D02*
X1907264D01*
G01X1907265Y519764D02*
X1912598D01*
G01Y519724D02*
X1908250D01*
G01X1912598Y518386D02*
X1907265D01*
G01X1907264Y517894D02*
X1908248D01*
G01Y515256D02*
X1907264D01*
G01X1907265Y514764D02*
X1912598D01*
G01Y514724D02*
X1908250D01*
G01X1912598Y513386D02*
X1907265D01*
G01X1907264Y512894D02*
X1908248D01*
G01Y510256D02*
X1907264D01*
G01X1907265Y509764D02*
X1912598D01*
G01Y509724D02*
X1908250D01*
G01X1912598Y508386D02*
X1907265D01*
G01X1907264Y507894D02*
X1908248D01*
G01Y505256D02*
X1907264D01*
G01X1907265Y504764D02*
X1912598D01*
G01Y504724D02*
X1908250D01*
G01X1912598Y503386D02*
X1907265D01*
G01X1907264Y502894D02*
X1908248D01*
G01X1903740Y500256D02*
X1898228D01*
G01X1904921Y499075D02*
X1897047D01*
G01X1910236Y497579D02*
X1895276D01*
G01X1906496Y496713D02*
X1909646D01*
G01X1899016D02*
X1895276D01*
G01Y495335D02*
X1909646D01*
G01X1903937Y493366D02*
X1901575D01*
G01X1903937Y491673D02*
X1901575D01*
G01X1905315Y486988D02*
X1900197D01*
G01X1913583Y486949D02*
X1891929D01*
G01X1906693Y483996D02*
X1898819D01*
G01Y482421D02*
X1906693D01*
G01X1903937Y481043D02*
X1901575D01*
G01Y479075D02*
X1903937D01*
G01X1906102Y477303D02*
X1899409D01*
G01X1911614Y476516D02*
X1893898D01*
G01X1908248Y528190D02*
X1907264Y528189D01*
G01Y524959D02*
X1908219Y524961D01*
G01X1908248Y523190D02*
X1907264Y523189D01*
G01Y519959D02*
X1908219Y519961D01*
G01X1908248Y518190D02*
X1907264Y518189D01*
G01Y514959D02*
X1908219Y514961D01*
G01X1908248Y513190D02*
X1907264Y513189D01*
G01Y509959D02*
X1908219Y509961D01*
G01X1908248Y508190D02*
X1907264Y508189D01*
G01Y504959D02*
X1908219Y504961D01*
G01X1908248Y503190D02*
X1907264Y503189D01*
G01X1908235Y574755D02*
X1908246Y574740D01*
G01X1908211Y574764D02*
X1908235Y574755D01*
G01Y579755D02*
X1908246Y579740D01*
G01X1908211Y579764D02*
X1908235Y579755D01*
G01Y584755D02*
X1908246Y584740D01*
G01X1908211Y584764D02*
X1908235Y584755D01*
G01Y589755D02*
X1908246Y589740D01*
G01X1908211Y589764D02*
X1908235Y589755D01*
G01Y594755D02*
X1908246Y594740D01*
G01X1908211Y594764D02*
X1908235Y594755D01*
G01Y599755D02*
X1908246Y599740D01*
G01X1908211Y599764D02*
X1908235Y599755D01*
G01Y604755D02*
X1908246Y604740D01*
G01X1908211Y604764D02*
X1908235Y604755D01*
G01Y609755D02*
X1908246Y609740D01*
G01X1908211Y609764D02*
X1908235Y609755D01*
G01Y614755D02*
X1908246Y614740D01*
G01X1908211Y614764D02*
X1908235Y614755D01*
G01Y619755D02*
X1908246Y619740D01*
G01X1908211Y619764D02*
X1908235Y619755D01*
G01Y624755D02*
X1908246Y624740D01*
G01X1908211Y624764D02*
X1908235Y624755D01*
G01Y629755D02*
X1908246Y629740D01*
G01X1908211Y629764D02*
X1908235Y629755D01*
G01X1908248Y574731D02*
Y574738D01*
G01X1908249Y574726D02*
X1908248Y574731D01*
G01X1908250Y574724D02*
X1908249Y574726D01*
G01X1908248Y579731D02*
Y579738D01*
G01X1908249Y579726D02*
X1908248Y579731D01*
G01X1908250Y579724D02*
X1908249Y579726D01*
G01X1908248Y584731D02*
Y584738D01*
G01X1908249Y584726D02*
X1908248Y584731D01*
G01X1908250Y584724D02*
X1908249Y584726D01*
G01X1908248Y589731D02*
Y589738D01*
G01X1908249Y589726D02*
X1908248Y589731D01*
G01X1908250Y589724D02*
X1908249Y589726D01*
G01X1908248Y594731D02*
Y594738D01*
G01X1908249Y594726D02*
X1908248Y594731D01*
G01X1908250Y594724D02*
X1908249Y594726D01*
G01X1908248Y599731D02*
Y599738D01*
G01X1908249Y599726D02*
X1908248Y599731D01*
G01X1908250Y599724D02*
X1908249Y599726D01*
G01X1908248Y604731D02*
Y604738D01*
G01X1908249Y604726D02*
X1908248Y604731D01*
G01X1908250Y604724D02*
X1908249Y604726D01*
G01X1908248Y609731D02*
Y609738D01*
G01X1908249Y609726D02*
X1908248Y609731D01*
G01X1908250Y609724D02*
X1908249Y609726D01*
G01X1908248Y614731D02*
Y614738D01*
G01X1908249Y614726D02*
X1908248Y614731D01*
G01X1908250Y614724D02*
X1908249Y614726D01*
G01X1908248Y619731D02*
Y619738D01*
G01X1908249Y619726D02*
X1908248Y619731D01*
G01X1908250Y619724D02*
X1908249Y619726D01*
G01X1908248Y624731D02*
Y624738D01*
G01X1908249Y624726D02*
X1908248Y624731D01*
G01X1908250Y624724D02*
X1908249Y624726D01*
G01X1908248Y629731D02*
Y629738D01*
G01X1908249Y629726D02*
X1908248Y629731D01*
G01X1908250Y629724D02*
X1908249Y629726D01*
G01X1908248Y628378D02*
Y628369D01*
G01X1908249Y628384D02*
X1908248Y628378D01*
G01X1908251Y628386D02*
X1908249Y628384D01*
G01X1908248Y623378D02*
Y623369D01*
G01X1908249Y623384D02*
X1908248Y623378D01*
G01X1908251Y623386D02*
X1908249Y623384D01*
G01X1908248Y618378D02*
Y618369D01*
G01X1908249Y618384D02*
X1908248Y618378D01*
G01X1908251Y618386D02*
X1908249Y618384D01*
G01X1908248Y613378D02*
Y613369D01*
G01X1908249Y613384D02*
X1908248Y613378D01*
G01X1908251Y613386D02*
X1908249Y613384D01*
G01X1908248Y608378D02*
Y608369D01*
G01X1908249Y608384D02*
X1908248Y608378D01*
G01X1908251Y608386D02*
X1908249Y608384D01*
G01X1907264Y574771D02*
Y574780D01*
G01X1907265Y574765D02*
X1907264Y574771D01*
G01X1907265Y574764D02*
Y574765D01*
G01X1907264Y579771D02*
Y579780D01*
G01X1907265Y579765D02*
X1907264Y579771D01*
G01X1907265Y579764D02*
Y579765D01*
G01X1907264Y584771D02*
Y584780D01*
G01X1907265Y584765D02*
X1907264Y584771D01*
G01X1907265Y584764D02*
Y584765D01*
G01X1907264Y589771D02*
Y589780D01*
G01X1907265Y589765D02*
X1907264Y589771D01*
G01X1907265Y589764D02*
Y589765D01*
G01X1907264Y594771D02*
Y594780D01*
G01X1907265Y594765D02*
X1907264Y594771D01*
G01X1907265Y594764D02*
Y594765D01*
G01X1907264Y599771D02*
Y599780D01*
G01X1907265Y599765D02*
X1907264Y599771D01*
G01X1907265Y599764D02*
Y599765D01*
G01X1907264Y604771D02*
Y604780D01*
G01X1907265Y604765D02*
X1907264Y604771D01*
G01X1907265Y604764D02*
Y604765D01*
G01X1907264Y609771D02*
Y609780D01*
G01X1907265Y609765D02*
X1907264Y609771D01*
G01X1907265Y609764D02*
Y609765D01*
G01X1907264Y614771D02*
Y614780D01*
G01X1907265Y614765D02*
X1907264Y614771D01*
G01X1907265Y614764D02*
Y614765D01*
G01X1907264Y619771D02*
Y619780D01*
G01X1907265Y619765D02*
X1907264Y619771D01*
G01X1907265Y619764D02*
Y619765D01*
G01X1907264Y624771D02*
Y624780D01*
G01X1907265Y624765D02*
X1907264Y624771D01*
G01X1907265Y624764D02*
Y624765D01*
G01X1907264Y629771D02*
Y629780D01*
G01X1907265Y629765D02*
X1907264Y629771D01*
G01X1907265Y629764D02*
Y629765D01*
G01X1908240Y574907D02*
X1908248Y574881D01*
G01X1908230Y574934D02*
X1908240Y574907D01*
G01X1908219Y574961D02*
X1908230Y574934D01*
G01X1908240Y579907D02*
X1908248Y579881D01*
G01X1908230Y579934D02*
X1908240Y579907D01*
G01X1908219Y579961D02*
X1908230Y579934D01*
G01X1908240Y584907D02*
X1908248Y584881D01*
G01X1908230Y584934D02*
X1908240Y584907D01*
G01X1908219Y584961D02*
X1908230Y584934D01*
G01X1908240Y589907D02*
X1908248Y589881D01*
G01X1908230Y589934D02*
X1908240Y589907D01*
G01X1908219Y589961D02*
X1908230Y589934D01*
G01X1908240Y594907D02*
X1908248Y594881D01*
G01X1908230Y594934D02*
X1908240Y594907D01*
G01X1908219Y594961D02*
X1908230Y594934D01*
G01X1908240Y599907D02*
X1908248Y599881D01*
G01X1908230Y599934D02*
X1908240Y599907D01*
G01X1908219Y599961D02*
X1908230Y599934D01*
G01X1908240Y604907D02*
X1908248Y604881D01*
G01X1908230Y604934D02*
X1908240Y604907D01*
G01X1908219Y604961D02*
X1908230Y604934D01*
G01X1908240Y609907D02*
X1908248Y609881D01*
G01X1908230Y609934D02*
X1908240Y609907D01*
G01X1908219Y609961D02*
X1908230Y609934D01*
G01X1908240Y614907D02*
X1908248Y614881D01*
G01X1908230Y614934D02*
X1908240Y614907D01*
G01X1908219Y614961D02*
X1908230Y614934D01*
G01X1908240Y619907D02*
X1908248Y619881D01*
G01X1908230Y619934D02*
X1908240Y619907D01*
G01X1908219Y619961D02*
X1908230Y619934D01*
G01X1908240Y624907D02*
X1908248Y624881D01*
G01X1908230Y624934D02*
X1908240Y624907D01*
G01X1908219Y624961D02*
X1908230Y624934D01*
G01X1908240Y629907D02*
X1908248Y629881D01*
G01X1908230Y629934D02*
X1908240Y629907D01*
G01X1908219Y629961D02*
X1908230Y629934D01*
G01X1908248Y603378D02*
Y603369D01*
G01X1908249Y603384D02*
X1908248Y603378D01*
G01X1908251Y603386D02*
X1908249Y603384D01*
G01X1908248Y598378D02*
Y598369D01*
G01X1908249Y598384D02*
X1908248Y598378D01*
G01X1908251Y598386D02*
X1908249Y598384D01*
G01X1908248Y593378D02*
Y593369D01*
G01X1908249Y593384D02*
X1908248Y593378D01*
G01X1908251Y593386D02*
X1908249Y593384D01*
G01X1908248Y588378D02*
Y588369D01*
G01X1908249Y588384D02*
X1908248Y588378D01*
G01X1908251Y588386D02*
X1908249Y588384D01*
G01X1908248Y583378D02*
Y583369D01*
G01X1908249Y583384D02*
X1908248Y583378D01*
G01X1908251Y583386D02*
X1908249Y583384D01*
G01X1908248Y578378D02*
Y578369D01*
G01X1908249Y578384D02*
X1908248Y578378D01*
G01X1908251Y578386D02*
X1908249Y578384D01*
G01X1908248Y573378D02*
Y573369D01*
G01X1908249Y573384D02*
X1908248Y573378D01*
G01X1908251Y573386D02*
X1908249Y573384D01*
G01X1908231Y574759D02*
X1908211Y574764D01*
G01X1908245Y574744D02*
X1908231Y574759D01*
G01X1908250Y574724D02*
X1908245Y574744D01*
G01X1908231Y579759D02*
X1908211Y579764D01*
G01X1908245Y579744D02*
X1908231Y579759D01*
G01X1908250Y579724D02*
X1908245Y579744D01*
G01X1908231Y584759D02*
X1908211Y584764D01*
G01X1908245Y584744D02*
X1908231Y584759D01*
G01X1908250Y584724D02*
X1908245Y584744D01*
G01X1908231Y589759D02*
X1908211Y589764D01*
G01X1908245Y589744D02*
X1908231Y589759D01*
G01X1908250Y589724D02*
X1908245Y589744D01*
G01X1908231Y594759D02*
X1908211Y594764D01*
G01X1908245Y594744D02*
X1908231Y594759D01*
G01X1908250Y594724D02*
X1908245Y594744D01*
G01X1908231Y599759D02*
X1908211Y599764D01*
G01X1908245Y599744D02*
X1908231Y599759D01*
G01X1908250Y599724D02*
X1908245Y599744D01*
G01X1908231Y604759D02*
X1908211Y604764D01*
G01X1908245Y604744D02*
X1908231Y604759D01*
G01X1908250Y604724D02*
X1908245Y604744D01*
G01X1908231Y609759D02*
X1908211Y609764D01*
G01X1908245Y609744D02*
X1908231Y609759D01*
G01X1908250Y609724D02*
X1908245Y609744D01*
G01X1908231Y614759D02*
X1908211Y614764D01*
G01X1908245Y614744D02*
X1908231Y614759D01*
G01X1908250Y614724D02*
X1908245Y614744D01*
G01X1908231Y619759D02*
X1908211Y619764D01*
G01X1908245Y619744D02*
X1908231Y619759D01*
G01X1908250Y619724D02*
X1908245Y619744D01*
G01X1908231Y624759D02*
X1908211Y624764D01*
G01X1908245Y624744D02*
X1908231Y624759D01*
G01X1908250Y624724D02*
X1908245Y624744D01*
G01X1908231Y629759D02*
X1908211Y629764D01*
G01X1908245Y629744D02*
X1908231Y629759D01*
G01X1908250Y629724D02*
X1908245Y629744D01*
G01X1908215Y574862D02*
X1908219Y574961D01*
G01X1908209Y574790D02*
X1908215Y574862D01*
G01X1908211Y574764D02*
X1908209Y574790D01*
G01X1908215Y579862D02*
X1908219Y579961D01*
G01X1908209Y579790D02*
X1908215Y579862D01*
G01X1908211Y579764D02*
X1908209Y579790D01*
G01X1908215Y584862D02*
X1908219Y584961D01*
G01X1908209Y584790D02*
X1908215Y584862D01*
G01X1908211Y584764D02*
X1908209Y584790D01*
G01X1908215Y589862D02*
X1908219Y589961D01*
G01X1908209Y589790D02*
X1908215Y589862D01*
G01X1908211Y589764D02*
X1908209Y589790D01*
G01X1908215Y594862D02*
X1908219Y594961D01*
G01X1908209Y594790D02*
X1908215Y594862D01*
G01X1908211Y594764D02*
X1908209Y594790D01*
G01X1908215Y599862D02*
X1908219Y599961D01*
G01X1908209Y599790D02*
X1908215Y599862D01*
G01X1908211Y599764D02*
X1908209Y599790D01*
G01X1908215Y604862D02*
X1908219Y604961D01*
G01X1908209Y604790D02*
X1908215Y604862D01*
G01X1908211Y604764D02*
X1908209Y604790D01*
G01X1908215Y609862D02*
X1908219Y609961D01*
G01X1908209Y609790D02*
X1908215Y609862D01*
G01X1908211Y609764D02*
X1908209Y609790D01*
G01X1908215Y614862D02*
X1908219Y614961D01*
G01X1908209Y614790D02*
X1908215Y614862D01*
G01X1908211Y614764D02*
X1908209Y614790D01*
G01X1908215Y619862D02*
X1908219Y619961D01*
G01X1908209Y619790D02*
X1908215Y619862D01*
G01X1908211Y619764D02*
X1908209Y619790D01*
G01X1908215Y624862D02*
X1908219Y624961D01*
G01X1908209Y624790D02*
X1908215Y624862D01*
G01X1908211Y624764D02*
X1908209Y624790D01*
G01X1908215Y629862D02*
X1908219Y629961D01*
G01X1908209Y629790D02*
X1908215Y629862D01*
G01X1908211Y629764D02*
X1908209Y629790D01*
G01X1907265Y628384D02*
Y628386D01*
G01X1907264Y628378D02*
X1907265Y628384D01*
G01X1907264Y628370D02*
Y628378D01*
G01X1907265Y623384D02*
Y623386D01*
G01X1907264Y623378D02*
X1907265Y623384D01*
G01X1907264Y623370D02*
Y623378D01*
G01X1907265Y618384D02*
Y618386D01*
G01X1907264Y618378D02*
X1907265Y618384D01*
G01X1907264Y618370D02*
Y618378D01*
G01X1907265Y613384D02*
Y613386D01*
G01X1907264Y613378D02*
X1907265Y613384D01*
G01X1907264Y613370D02*
Y613378D01*
G01X1907265Y608384D02*
Y608386D01*
G01X1907264Y608378D02*
X1907265Y608384D01*
G01X1907264Y608370D02*
Y608378D01*
G01X1907265Y603384D02*
Y603386D01*
G01X1907264Y603378D02*
X1907265Y603384D01*
G01X1907264Y603370D02*
Y603378D01*
G01X1907265Y598384D02*
Y598386D01*
G01X1907264Y598378D02*
X1907265Y598384D01*
G01X1907264Y598370D02*
Y598378D01*
G01X1907265Y593384D02*
Y593386D01*
G01X1907264Y593378D02*
X1907265Y593384D01*
G01X1907264Y593370D02*
Y593378D01*
G01X1907265Y588384D02*
Y588386D01*
G01X1907264Y588378D02*
X1907265Y588384D01*
G01X1907264Y588370D02*
Y588378D01*
G01X1907265Y583384D02*
Y583386D01*
G01X1907264Y583378D02*
X1907265Y583384D01*
G01X1907264Y583370D02*
Y583378D01*
G01X1907265Y578384D02*
Y578386D01*
G01X1907264Y578378D02*
X1907265Y578384D01*
G01X1907264Y578370D02*
Y578378D01*
G01X1907265Y573384D02*
Y573386D01*
G01X1907264Y573378D02*
X1907265Y573384D01*
G01X1907264Y573370D02*
Y573378D01*
G01X1906693Y655256D02*
G03X1906102Y655846I-590J0D01*
G01X1899409D02*
G03X1898819Y655256I0J-590D01*
G01X1901575Y654075D02*
G03Y652106I0J-985D01*
G01X1903937D02*
G03Y654075I0J984D01*
G01X1900197Y646161D02*
G03X1899016Y644980I0J-1181D01*
G01X1906496D02*
G03X1905315Y646161I-1181J0D01*
G01X1904646Y640886D02*
G03I-1890J0D01*
G01X1913583Y654665D02*
G03X1911614Y656634I-1969J0D01*
G01X1893898D02*
G03X1891929Y654665I0J-1969D01*
G01X1905118Y640886D02*
G03I-2362J0D01*
G01X1908248Y574738D02*
Y574746D01*
G01Y579738D02*
Y579746D01*
G01Y584738D02*
Y584746D01*
G01Y589738D02*
Y589746D01*
G01Y594738D02*
Y594746D01*
G01Y599738D02*
Y599746D01*
G01Y604738D02*
Y604746D01*
G01Y609738D02*
Y609746D01*
G01Y614738D02*
Y614746D01*
G01Y619738D02*
Y619746D01*
G01Y624738D02*
Y624746D01*
G01Y629738D02*
Y629746D01*
G01X1909429Y574764D02*
Y573386D01*
G01Y579764D02*
Y578386D01*
G01Y584764D02*
Y583386D01*
G01Y589764D02*
Y588386D01*
G01Y594764D02*
Y593386D01*
G01Y599764D02*
Y598386D01*
G01Y604764D02*
Y603386D01*
G01Y609764D02*
Y608386D01*
G01Y614764D02*
Y613386D01*
G01Y619764D02*
Y618386D01*
G01Y624764D02*
Y623386D01*
G01Y629764D02*
Y628386D01*
G01X1908248Y627894D02*
Y630256D01*
G01Y622894D02*
Y625256D01*
G01Y617894D02*
Y620256D01*
G01Y612894D02*
Y615256D01*
G01Y607894D02*
Y610256D01*
G01Y602894D02*
Y605256D01*
G01Y597894D02*
Y600256D01*
G01Y592894D02*
Y595256D01*
G01Y587894D02*
Y590256D01*
G01Y582894D02*
Y585256D01*
G01Y577894D02*
Y580256D01*
G01Y572894D02*
Y575256D01*
G01X1907264D02*
Y572894D01*
G01Y580256D02*
Y577894D01*
G01Y585256D02*
Y582894D01*
G01Y590256D02*
Y587894D01*
G01Y595256D02*
Y592894D01*
G01Y600256D02*
Y597894D01*
G01Y605256D02*
Y602894D01*
G01Y610256D02*
Y607894D01*
G01Y615256D02*
Y612894D01*
G01Y620256D02*
Y617894D01*
G01Y625256D02*
Y622894D01*
G01Y630256D02*
Y627894D01*
G01X1906693Y649154D02*
Y655256D01*
G01X1906496Y644980D02*
Y636437D01*
G01X1903937Y641476D02*
Y639783D01*
G01X1901575D02*
Y641476D01*
G01X1899016Y636437D02*
Y644980D01*
G01X1898819Y649154D02*
Y655256D01*
G01X1891929Y654665D02*
Y638917D01*
G01X1900271Y637815D02*
X1901575Y639783D01*
G01X1906247Y645706D02*
X1903937Y641476D01*
G01X1901575D02*
X1899265Y645706D01*
G01X1913583Y638917D02*
X1910236Y635571D01*
G01X1903740Y632894D02*
X1904921Y634075D01*
G01X1903937Y639783D02*
X1905241Y637815D01*
G01X1897047Y634075D02*
X1898228Y632894D01*
G01X1895276Y635571D02*
X1891929Y638917D01*
G01X1911614Y656634D02*
X1893898D01*
G01X1906102Y655846D02*
X1899409D01*
G01X1903937Y654075D02*
X1901575D01*
G01Y652106D02*
X1903937D01*
G01X1906693Y650728D02*
X1898819D01*
G01Y649154D02*
X1906693D01*
G01X1913583Y646201D02*
X1891929D01*
G01X1900197Y646161D02*
X1905315D01*
G01X1901575Y641476D02*
X1903937D01*
G01X1901575Y639783D02*
X1903937D01*
G01X1895276Y637815D02*
X1909646D01*
G01X1895276Y636437D02*
X1899016D01*
G01X1909646D02*
X1906496D01*
G01X1895276Y635571D02*
X1910236D01*
G01X1897047Y634075D02*
X1904921D01*
G01X1898228Y632894D02*
X1903740D01*
G01X1908248Y630256D02*
X1907264D01*
G01X1907265Y629764D02*
X1912598D01*
G01Y629724D02*
X1908250D01*
G01X1912598Y628386D02*
X1907265D01*
G01X1907264Y627894D02*
X1908248D01*
G01Y625256D02*
X1907264D01*
G01X1907265Y624764D02*
X1912598D01*
G01Y624724D02*
X1908250D01*
G01X1912598Y623386D02*
X1907265D01*
G01X1907264Y622894D02*
X1908248D01*
G01Y620256D02*
X1907264D01*
G01X1907265Y619764D02*
X1912598D01*
G01Y619724D02*
X1908250D01*
G01X1912598Y618386D02*
X1907265D01*
G01X1907264Y617894D02*
X1908248D01*
G01Y615256D02*
X1907264D01*
G01X1907265Y614764D02*
X1912598D01*
G01Y614724D02*
X1908250D01*
G01X1912598Y613386D02*
X1907265D01*
G01X1907264Y612894D02*
X1908248D01*
G01Y610256D02*
X1907264D01*
G01Y629959D02*
X1908219Y629961D01*
G01X1908248Y628190D02*
X1907264Y628189D01*
G01Y624959D02*
X1908219Y624961D01*
G01X1908248Y623190D02*
X1907264Y623189D01*
G01Y619959D02*
X1908219Y619961D01*
G01X1908248Y618190D02*
X1907264Y618189D01*
G01Y614959D02*
X1908219Y614961D01*
G01X1908248Y613190D02*
X1907264Y613189D01*
G01X1907265Y609764D02*
X1912598D01*
G01Y609724D02*
X1908250D01*
G01X1912598Y608386D02*
X1907265D01*
G01X1907264Y607894D02*
X1908248D01*
G01Y605256D02*
X1907264D01*
G01X1907265Y604764D02*
X1912598D01*
G01Y604724D02*
X1908250D01*
G01X1912598Y603386D02*
X1907265D01*
G01X1907264Y602894D02*
X1908248D01*
G01Y600256D02*
X1907264D01*
G01X1907265Y599764D02*
X1912598D01*
G01Y599724D02*
X1908250D01*
G01X1912598Y598386D02*
X1907265D01*
G01X1907264Y597894D02*
X1908248D01*
G01Y595256D02*
X1907264D01*
G01X1907265Y594764D02*
X1912598D01*
G01Y594724D02*
X1908250D01*
G01X1912598Y593386D02*
X1907265D01*
G01X1907264Y592894D02*
X1908248D01*
G01Y590256D02*
X1907264D01*
G01X1907265Y589764D02*
X1912598D01*
G01Y589724D02*
X1908250D01*
G01X1912598Y588386D02*
X1907265D01*
G01X1907264Y587894D02*
X1908248D01*
G01Y585256D02*
X1907264D01*
G01X1907265Y584764D02*
X1912598D01*
G01Y584724D02*
X1908250D01*
G01X1912598Y583386D02*
X1907265D01*
G01X1907264Y582894D02*
X1908248D01*
G01Y580256D02*
X1907264D01*
G01X1907265Y579764D02*
X1912598D01*
G01Y579724D02*
X1908250D01*
G01X1912598Y578386D02*
X1907265D01*
G01X1907264Y577894D02*
X1908248D01*
G01Y575256D02*
X1907264D01*
G01X1907265Y574764D02*
X1912598D01*
G01Y574724D02*
X1908250D01*
G01X1912598Y573386D02*
X1907265D01*
G01X1907264Y572894D02*
X1908248D01*
G01X1907264Y609959D02*
X1908219Y609961D01*
G01X1908248Y608190D02*
X1907264Y608189D01*
G01Y604959D02*
X1908219Y604961D01*
G01X1908248Y603190D02*
X1907264Y603189D01*
G01Y599959D02*
X1908219Y599961D01*
G01X1908248Y598190D02*
X1907264Y598189D01*
G01Y594959D02*
X1908219Y594961D01*
G01X1908248Y593190D02*
X1907264Y593189D01*
G01Y589959D02*
X1908219Y589961D01*
G01X1908248Y588190D02*
X1907264Y588189D01*
G01Y584959D02*
X1908219Y584961D01*
G01X1908248Y583190D02*
X1907264Y583189D01*
G01Y579959D02*
X1908219Y579961D01*
G01X1908248Y578190D02*
X1907264Y578189D01*
G01Y574959D02*
X1908219Y574961D01*
G01X1908248Y573190D02*
X1907264Y573189D01*
G01X1862795Y713386D02*
G03X1863976I590J0D01*
G01Y707087D02*
G03X1862795I-590J0D01*
G01X1860827D02*
G03X1859646I-590J0D01*
G01Y713386D02*
G03X1860827I591J0D01*
G01X1862795D02*
G03X1863976I590J0D01*
G01Y707087D02*
G03X1862795I-590J0D01*
G01X1860827D02*
G03X1859646I-590J0D01*
G01Y713386D02*
G03X1860827I591J0D01*
G01X1864764Y707087D02*
Y713386D01*
G01Y707087D02*
Y713386D01*
G01X1858858Y707087D02*
Y713386D01*
G01D02*
Y707087D01*
G01X1859646Y713386D02*
X1858858D01*
G01X1859646D02*
X1858858D01*
G01X1862795D02*
X1860827D01*
G01X1864764D02*
X1863976D01*
G01X1862795D02*
X1860827D01*
G01X1864764D02*
X1863976D01*
G01X1864764Y712402D02*
X1858858D01*
G01Y712205D02*
X1864764D01*
G01X1858858Y708268D02*
X1864764D01*
G01Y708071D02*
X1858858D01*
G01X1863976Y707087D02*
X1864764D01*
G01X1860827D02*
X1862795D01*
G01X1863976D02*
X1864764D01*
G01X1860827D02*
X1862795D01*
G01X1858858D02*
X1859646D01*
G01X1858858D02*
X1859646D01*
G01X1903858Y945020D02*
G03I-1102J0D01*
G01X1905315Y939744D02*
G03X1906496Y940925I0J1181D01*
G01X1899016D02*
G03X1900197Y939744I1181J0D01*
G01X1904331Y945020D02*
G03I-1575J0D01*
G01X1898819Y930650D02*
G03X1899409Y930059I591J0D01*
G01X1906102D02*
G03X1906693Y930650I0J591D01*
G01X1903937Y931831D02*
G03Y933799I0J984D01*
G01X1901575D02*
G03Y931831I0J-984D01*
G01X1891929Y931240D02*
G03X1893898Y929272I1968J0D01*
G01X1911614D02*
G03X1913583Y931240I1J1968D01*
G01X1910236Y1088327D02*
Y950335D01*
G01X1909646Y1090571D02*
Y948091D01*
G01X1906693Y936752D02*
Y930650D01*
G01X1906496Y949469D02*
Y940925D01*
G01X1904921Y988287D02*
Y951831D01*
G01X1903937Y946122D02*
Y944429D01*
G01X1901575D02*
Y946122D01*
G01X1899016Y940925D02*
Y949469D01*
G01X1898819Y936752D02*
Y930650D01*
G01X1897047Y951831D02*
Y1086831D01*
G01X1895276Y987126D02*
Y948091D01*
G01X1891929Y946988D02*
Y931240D01*
G01X1903937Y944429D02*
X1906247Y940200D01*
G01X1901575Y946122D02*
X1900271Y948091D01*
G01X1910236Y950335D02*
X1913583Y946988D01*
G01X1903740Y953012D02*
X1904921Y951831D01*
G01X1905241Y948091D02*
X1903937Y946122D01*
G01X1899265Y940200D02*
X1901575Y944429D01*
G01X1898228Y953012D02*
X1897047Y951831D01*
G01X1895276Y950335D02*
X1891929Y946988D01*
G01X1904921Y951831D02*
X1897047D01*
G01X1910236Y950335D02*
X1895276D01*
G01X1906496Y949469D02*
X1909646D01*
G01X1899016D02*
X1895276D01*
G01Y948091D02*
X1909646D01*
G01X1903937Y946122D02*
X1901575D01*
G01X1903937Y944429D02*
X1901575D01*
G01X1905315Y939744D02*
X1900197D01*
G01X1913583Y939705D02*
X1891929D01*
G01X1906693Y936752D02*
X1898819D01*
G01Y935177D02*
X1906693D01*
G01X1903937Y933799D02*
X1901575D01*
G01Y931831D02*
X1903937D01*
G01X1906102Y930059D02*
X1899409D01*
G01X1911614Y929272D02*
X1893898D01*
G01X1893841Y990453D02*
X1893836Y990433D01*
G01X1893856Y990467D02*
X1893841Y990453D01*
G01X1893876Y990472D02*
X1893856Y990467D01*
G01X1893841Y993602D02*
X1893836Y993583D01*
G01X1893856Y993617D02*
X1893841Y993602D01*
G01X1893876Y993622D02*
X1893856Y993617D01*
G01X1893841Y996752D02*
X1893836Y996732D01*
G01X1893856Y996766D02*
X1893841Y996752D01*
G01X1893876Y996772D02*
X1893856Y996766D01*
G01X1893841Y999902D02*
X1893836Y999882D01*
G01X1893856Y999916D02*
X1893841Y999902D01*
G01X1893876Y999921D02*
X1893856Y999916D01*
G01X1893841Y1003051D02*
X1893836Y1003031D01*
G01X1893856Y1003065D02*
X1893841Y1003051D01*
G01X1893876Y1003071D02*
X1893856Y1003065D01*
G01X1893841Y1006201D02*
X1893836Y1006181D01*
G01X1893856Y1006215D02*
X1893841Y1006201D01*
G01X1893876Y1006220D02*
X1893856Y1006215D01*
G01X1893841Y1009350D02*
X1893836Y1009331D01*
G01X1893856Y1009365D02*
X1893841Y1009350D01*
G01X1893876Y1009370D02*
X1893856Y1009365D01*
G01X1894816Y989311D02*
X1894821Y989331D01*
G01X1894802Y989296D02*
X1894816Y989311D01*
G01X1894782Y989291D02*
X1894802Y989296D01*
G01X1894816Y992461D02*
X1894821Y992480D01*
G01X1894802Y992446D02*
X1894816Y992461D01*
G01X1894782Y992441D02*
X1894802Y992446D01*
G01X1894816Y995610D02*
X1894821Y995630D01*
G01X1894802Y995596D02*
X1894816Y995610D01*
G01X1894782Y995591D02*
X1894802Y995596D01*
G01X1894816Y998760D02*
X1894821Y998780D01*
G01X1894802Y998745D02*
X1894816Y998760D01*
G01X1894782Y998740D02*
X1894802Y998745D01*
G01X1894816Y1001909D02*
X1894821Y1001929D01*
G01X1894802Y1001895D02*
X1894816Y1001909D01*
G01X1894782Y1001890D02*
X1894802Y1001895D01*
G01X1894816Y1005059D02*
X1894821Y1005079D01*
G01X1894802Y1005044D02*
X1894816Y1005059D01*
G01X1894782Y1005039D02*
X1894802Y1005044D01*
G01X1894816Y1008209D02*
X1894821Y1008228D01*
G01X1894802Y1008194D02*
X1894816Y1008209D01*
G01X1894782Y1008189D02*
X1894802Y1008194D01*
G01X1894822Y1005058D02*
X1894823Y1005065D01*
G01X1894820Y1005051D02*
X1894822Y1005058D01*
G01X1894816Y1005044D02*
X1894820Y1005051D01*
G01X1894811Y1005039D02*
X1894816Y1005044D01*
G01X1894805Y1005034D02*
X1894811Y1005039D01*
G01X1894798Y1005031D02*
X1894805Y1005034D01*
G01X1894791Y1005029D02*
X1894798Y1005031D01*
G01X1894783Y1005028D02*
X1894791Y1005029D01*
G01X1894794Y1008191D02*
X1894782Y1008189D01*
G01X1894804Y1008196D02*
X1894794Y1008191D01*
G01Y1005041D02*
X1894782Y1005039D01*
G01X1894804Y1005046D02*
X1894794Y1005041D01*
G01Y1001892D02*
X1894782Y1001890D01*
G01X1894804Y1001896D02*
X1894794Y1001892D01*
G01Y998742D02*
X1894782Y998740D01*
G01X1894804Y998747D02*
X1894794Y998742D01*
G01Y995593D02*
X1894782Y995591D01*
G01X1894804Y995597D02*
X1894794Y995593D01*
G01Y992443D02*
X1894782Y992441D01*
G01X1894804Y992448D02*
X1894794Y992443D01*
G01Y989293D02*
X1894782Y989291D01*
G01X1894804Y989298D02*
X1894794Y989293D01*
G01X1894800Y989283D02*
X1894804Y989285D01*
G01X1894797Y989282D02*
X1894800Y989283D01*
G01X1894794Y989281D02*
X1894797Y989282D01*
G01X1894791Y989281D02*
X1894794D01*
G01X1894787Y989280D02*
X1894791Y989281D01*
G01X1894783Y989280D02*
X1894787D01*
G01X1893861Y990480D02*
X1893858Y990478D01*
G01X1893864Y990481D02*
X1893861Y990480D01*
G01X1893868Y990482D02*
X1893864Y990481D01*
G01X1893871Y990483D02*
X1893868Y990482D01*
G01X1893874Y990483D02*
X1893871D01*
G01X1893878D02*
X1893874D01*
G01X1894800Y992433D02*
X1894804Y992435D01*
G01X1894797Y992432D02*
X1894800Y992433D01*
G01X1894794Y992431D02*
X1894797Y992432D01*
G01X1894791Y992430D02*
X1894794Y992431D01*
G01X1894787Y992430D02*
X1894791D01*
G01X1894783D02*
X1894787D01*
G01X1893861Y993630D02*
X1893858Y993628D01*
G01X1893864Y993631D02*
X1893861Y993630D01*
G01X1893868Y993632D02*
X1893864Y993631D01*
G01X1893871Y993633D02*
X1893868Y993632D01*
G01X1893874Y993633D02*
X1893871D01*
G01X1893878D02*
X1893874D01*
G01X1894800Y995583D02*
X1894804Y995585D01*
G01X1894797Y995581D02*
X1894800Y995583D01*
G01X1894794Y995581D02*
X1894797D01*
G01X1894791Y995580D02*
X1894794Y995581D01*
G01X1894787Y995580D02*
X1894791D01*
G01X1894783Y995579D02*
X1894787Y995580D01*
G01X1893861Y996779D02*
X1893858Y996778D01*
G01X1893864Y996780D02*
X1893861Y996779D01*
G01X1893868Y996781D02*
X1893864Y996780D01*
G01X1893871Y996782D02*
X1893868Y996781D01*
G01X1893874Y996783D02*
X1893871Y996782D01*
G01X1893878Y996783D02*
X1893874D01*
G01X1894800Y998732D02*
X1894804Y998734D01*
G01X1894797Y998731D02*
X1894800Y998732D01*
G01X1894794Y998730D02*
X1894797Y998731D01*
G01X1894791Y998730D02*
X1894794D01*
G01X1894787Y998729D02*
X1894791Y998730D01*
G01X1894783Y998729D02*
X1894787D01*
G01X1893861Y999929D02*
X1893858Y999927D01*
G01X1893864Y999930D02*
X1893861Y999929D01*
G01X1893868Y999931D02*
X1893864Y999930D01*
G01X1893871Y999932D02*
X1893868Y999931D01*
G01X1893874Y999932D02*
X1893871D01*
G01X1893878D02*
X1893874D01*
G01X1894800Y1001882D02*
X1894804Y1001884D01*
G01X1894797Y1001881D02*
X1894800Y1001882D01*
G01X1894794Y1001880D02*
X1894797Y1001881D01*
G01X1894791Y1001879D02*
X1894794Y1001880D01*
G01X1894787Y1001879D02*
X1894791D01*
G01X1894783Y1001878D02*
X1894787Y1001879D01*
G01X1893861Y1003078D02*
X1893858Y1003077D01*
G01X1893864Y1003080D02*
X1893861Y1003078D01*
G01X1893868Y1003081D02*
X1893864Y1003080D01*
G01X1893871Y1003081D02*
X1893868D01*
G01X1893874Y1003082D02*
X1893871Y1003081D01*
G01X1893878Y1003082D02*
X1893874D01*
G01X1893861Y1006228D02*
X1893858Y1006226D01*
G01X1893864Y1006229D02*
X1893861Y1006228D01*
G01X1893868Y1006230D02*
X1893864Y1006229D01*
G01X1893871Y1006231D02*
X1893868Y1006230D01*
G01X1893874Y1006231D02*
X1893871D01*
G01X1893878D02*
X1893874D01*
G01X1894800Y1008181D02*
X1894804Y1008183D01*
G01X1894797Y1008180D02*
X1894800Y1008181D01*
G01X1894794Y1008179D02*
X1894797Y1008180D01*
G01X1894791Y1008178D02*
X1894794Y1008179D01*
G01X1894787Y1008178D02*
X1894791D01*
G01X1894783D02*
X1894787D01*
G01X1893861Y1009378D02*
X1893858Y1009376D01*
G01X1893864Y1009379D02*
X1893861Y1009378D01*
G01X1893868Y1009380D02*
X1893864Y1009379D01*
G01X1893871Y1009381D02*
X1893868Y1009380D01*
G01X1893874Y1009381D02*
X1893871D01*
G01X1893878D02*
X1893874D01*
G01X1893877Y1009375D02*
Y1009381D01*
G01Y1009371D02*
Y1009375D01*
G01X1893876Y1009370D02*
X1893877Y1009371D01*
G01Y1006225D02*
Y1006231D01*
G01Y1006222D02*
Y1006225D01*
G01X1893876Y1006220D02*
X1893877Y1006222D01*
G01Y1003076D02*
Y1003082D01*
G01Y1003072D02*
Y1003076D01*
G01X1893876Y1003071D02*
X1893877Y1003072D01*
G01X1893839Y1009350D02*
Y1009344D01*
G01X1893841Y1009357D02*
X1893839Y1009350D01*
G01X1893844Y1009363D02*
X1893841Y1009357D01*
G01X1893848Y1009368D02*
X1893844Y1009363D01*
G01X1893852Y1009372D02*
X1893848Y1009368D01*
G01X1893858Y1009376D02*
X1893852Y1009372D01*
G01X1893839Y1006201D02*
Y1006194D01*
G01X1893841Y1006207D02*
X1893839Y1006201D01*
G01X1893844Y1006213D02*
X1893841Y1006207D01*
G01X1893848Y1006218D02*
X1893844Y1006213D01*
G01X1893852Y1006223D02*
X1893848Y1006218D01*
G01X1893858Y1006226D02*
X1893852Y1006223D01*
G01X1893839Y1003051D02*
Y1003045D01*
G01X1893841Y1003057D02*
X1893839Y1003051D01*
G01X1893844Y1003063D02*
X1893841Y1003057D01*
G01X1893848Y1003069D02*
X1893844Y1003063D01*
G01X1893852Y1003073D02*
X1893848Y1003069D01*
G01X1893858Y1003077D02*
X1893852Y1003073D01*
G01X1893839Y999902D02*
Y999895D01*
G01X1893841Y999908D02*
X1893839Y999902D01*
G01X1893844Y999914D02*
X1893841Y999908D01*
G01X1893848Y999919D02*
X1893844Y999914D01*
G01X1893852Y999924D02*
X1893848Y999919D01*
G01X1893858Y999927D02*
X1893852Y999924D01*
G01X1893839Y996752D02*
Y996746D01*
G01X1893841Y996758D02*
X1893839Y996752D01*
G01X1893844Y996764D02*
X1893841Y996758D01*
G01X1893848Y996769D02*
X1893844Y996764D01*
G01X1893852Y996774D02*
X1893848Y996769D01*
G01X1893858Y996778D02*
X1893852Y996774D01*
G01X1893839Y993602D02*
Y993596D01*
G01X1893841Y993609D02*
X1893839Y993602D01*
G01X1893844Y993615D02*
X1893841Y993609D01*
G01X1893848Y993620D02*
X1893844Y993615D01*
G01X1893852Y993624D02*
X1893848Y993620D01*
G01X1893858Y993628D02*
X1893852Y993624D01*
G01X1893839Y990453D02*
Y990446D01*
G01X1893841Y990459D02*
X1893839Y990453D01*
G01X1893844Y990465D02*
X1893841Y990459D01*
G01X1893848Y990470D02*
X1893844Y990465D01*
G01X1893852Y990475D02*
X1893848Y990470D01*
G01X1893858Y990478D02*
X1893852Y990475D01*
G01X1894813Y990471D02*
X1894817Y990465D01*
G01X1894809Y990475D02*
X1894813Y990471D01*
G01X1894803Y990479D02*
X1894809Y990475D01*
G01X1894797Y990481D02*
X1894803Y990479D01*
G01X1894790Y990483D02*
X1894797Y990481D01*
G01X1894783Y990483D02*
X1894790D01*
G01X1894813Y993620D02*
X1894817Y993615D01*
G01X1894809Y993625D02*
X1894813Y993620D01*
G01X1894803Y993628D02*
X1894809Y993625D01*
G01X1894797Y993631D02*
X1894803Y993628D01*
G01X1894790Y993633D02*
X1894797Y993631D01*
G01X1894783Y993633D02*
X1894790D01*
G01X1894813Y996770D02*
X1894817Y996765D01*
G01X1894809Y996774D02*
X1894813Y996770D01*
G01X1894803Y996778D02*
X1894809Y996774D01*
G01X1894797Y996781D02*
X1894803Y996778D01*
G01X1894790Y996782D02*
X1894797Y996781D01*
G01X1894783Y996783D02*
X1894790Y996782D01*
G01X1894813Y999920D02*
X1894817Y999914D01*
G01X1894809Y999924D02*
X1894813Y999920D01*
G01X1894803Y999928D02*
X1894809Y999924D01*
G01X1894797Y999930D02*
X1894803Y999928D01*
G01X1894790Y999932D02*
X1894797Y999930D01*
G01X1894783Y999932D02*
X1894790D01*
G01X1894813Y1003069D02*
X1894817Y1003064D01*
G01X1894809Y1003074D02*
X1894813Y1003069D01*
G01X1894803Y1003077D02*
X1894809Y1003074D01*
G01X1894797Y1003080D02*
X1894803Y1003077D01*
G01X1894790Y1003081D02*
X1894797Y1003080D01*
G01X1894783Y1003082D02*
X1894790Y1003081D01*
G01X1894813Y1006219D02*
X1894817Y1006213D01*
G01X1894809Y1006223D02*
X1894813Y1006219D01*
G01X1894803Y1006227D02*
X1894809Y1006223D01*
G01X1894797Y1006230D02*
X1894803Y1006227D01*
G01X1894790Y1006231D02*
X1894797Y1006230D01*
G01X1894783Y1006231D02*
X1894790D01*
G01X1894813Y1009369D02*
X1894817Y1009363D01*
G01X1894809Y1009373D02*
X1894813Y1009369D01*
G01X1894803Y1009376D02*
X1894809Y1009373D01*
G01X1894797Y1009379D02*
X1894803Y1009376D01*
G01X1894790Y1009381D02*
X1894797Y1009379D01*
G01X1894783Y1009381D02*
X1894790D01*
G01X1893839Y989310D02*
Y989317D01*
G01X1893842Y989303D02*
X1893839Y989310D01*
G01X1893845Y989296D02*
X1893842Y989303D01*
G01X1893850Y989291D02*
X1893845Y989296D01*
G01X1893856Y989286D02*
X1893850Y989291D01*
G01X1893863Y989283D02*
X1893856Y989286D01*
G01X1893870Y989281D02*
X1893863Y989283D01*
G01X1893878Y989280D02*
X1893870Y989281D01*
G01X1893839Y992459D02*
Y992467D01*
G01X1893842Y992452D02*
X1893839Y992459D01*
G01X1893845Y992446D02*
X1893842Y992452D01*
G01X1893850Y992441D02*
X1893845Y992446D01*
G01X1893856Y992436D02*
X1893850Y992441D01*
G01X1893863Y992432D02*
X1893856Y992436D01*
G01X1893870Y992430D02*
X1893863Y992432D01*
G01X1893878Y992430D02*
X1893870D01*
G01X1893839Y995609D02*
Y995616D01*
G01X1893842Y995602D02*
X1893839Y995609D01*
G01X1893845Y995596D02*
X1893842Y995602D01*
G01X1893850Y995590D02*
X1893845Y995596D01*
G01X1893856Y995585D02*
X1893850Y995590D01*
G01X1893863Y995582D02*
X1893856Y995585D01*
G01X1893870Y995580D02*
X1893863Y995582D01*
G01X1893878Y995579D02*
X1893870Y995580D01*
G01X1893839Y998759D02*
Y998766D01*
G01X1893842Y998752D02*
X1893839Y998759D01*
G01X1893845Y998745D02*
X1893842Y998752D01*
G01X1893850Y998740D02*
X1893845Y998745D01*
G01X1893856Y998735D02*
X1893850Y998740D01*
G01X1893863Y998731D02*
X1893856Y998735D01*
G01X1893870Y998730D02*
X1893863Y998731D01*
G01X1893878Y998729D02*
X1893870Y998730D01*
G01X1893839Y1001908D02*
Y1001915D01*
G01X1893842Y1001901D02*
X1893839Y1001908D01*
G01X1893845Y1001895D02*
X1893842Y1001901D01*
G01X1893850Y1001889D02*
X1893845Y1001895D01*
G01X1893856Y1001885D02*
X1893850Y1001889D01*
G01X1893863Y1001881D02*
X1893856Y1001885D01*
G01X1893870Y1001879D02*
X1893863Y1001881D01*
G01X1893878Y1001878D02*
X1893870Y1001879D01*
G01X1893839Y1005058D02*
Y1005065D01*
G01X1893842Y1005051D02*
X1893839Y1005058D01*
G01X1893845Y1005044D02*
X1893842Y1005051D01*
G01X1893850Y1005039D02*
X1893845Y1005044D01*
G01X1893856Y1005034D02*
X1893850Y1005039D01*
G01X1893863Y1005031D02*
X1893856Y1005034D01*
G01X1893870Y1005029D02*
X1893863Y1005031D01*
G01X1893878Y1005028D02*
X1893870Y1005029D01*
G01X1893839Y1008207D02*
Y1008215D01*
G01X1893842Y1008200D02*
X1893839Y1008207D01*
G01X1893845Y1008194D02*
X1893842Y1008200D01*
G01X1893850Y1008189D02*
X1893845Y1008194D01*
G01X1893856Y1008184D02*
X1893850Y1008189D01*
G01X1893863Y1008180D02*
X1893856Y1008184D01*
G01X1893870Y1008178D02*
X1893863Y1008180D01*
G01X1893878Y1008178D02*
X1893870D01*
G01X1894820Y1008202D02*
X1894823Y1008215D01*
G01X1894814Y1008191D02*
X1894820Y1008202D01*
G01X1894804Y1008183D02*
X1894814Y1008191D01*
G01X1894820Y1001903D02*
X1894823Y1001915D01*
G01X1894814Y1001892D02*
X1894820Y1001903D01*
G01X1894804Y1001884D02*
X1894814Y1001892D01*
G01X1894820Y998754D02*
X1894823Y998766D01*
G01X1894814Y998742D02*
X1894820Y998754D01*
G01X1894804Y998734D02*
X1894814Y998742D01*
G01X1894820Y995604D02*
X1894823Y995616D01*
G01X1894814Y995593D02*
X1894820Y995604D01*
G01X1894804Y995585D02*
X1894814Y995593D01*
G01X1894820Y992454D02*
X1894823Y992467D01*
G01X1894814Y992443D02*
X1894820Y992454D01*
G01X1894804Y992435D02*
X1894814Y992443D01*
G01X1894820Y989305D02*
X1894823Y989317D01*
G01X1894814Y989293D02*
X1894820Y989305D01*
G01X1894804Y989285D02*
X1894814Y989293D01*
G01X1893877Y999926D02*
Y999932D01*
G01Y999922D02*
Y999926D01*
G01X1893876Y999921D02*
X1893877Y999922D01*
G01Y996776D02*
Y996783D01*
G01Y996773D02*
Y996776D01*
G01X1893876Y996772D02*
X1893877Y996773D01*
G01Y993627D02*
Y993633D01*
G01Y993623D02*
Y993627D01*
G01X1893876Y993622D02*
X1893877Y993623D01*
G01Y990477D02*
Y990483D01*
G01Y990474D02*
Y990477D01*
G01X1893876Y990472D02*
X1893877Y990474D01*
G01X1894793Y990471D02*
X1894802Y990467D01*
G01X1894782Y990472D02*
X1894793Y990471D01*
G01Y993620D02*
X1894802Y993617D01*
G01X1894782Y993622D02*
X1894793Y993620D01*
G01Y996770D02*
X1894802Y996766D01*
G01X1894782Y996772D02*
X1894793Y996770D01*
G01Y999920D02*
X1894802Y999916D01*
G01X1894782Y999921D02*
X1894793Y999920D01*
G01Y1003069D02*
X1894802Y1003065D01*
G01X1894782Y1003071D02*
X1894793Y1003069D01*
G01Y1006219D02*
X1894802Y1006215D01*
G01X1894782Y1006220D02*
X1894793Y1006219D01*
G01Y1009369D02*
X1894802Y1009365D01*
G01X1894782Y1009370D02*
X1894793Y1009369D01*
G01X1893839Y992470D02*
Y992467D01*
G01X1893840Y992464D02*
X1893839Y992470D01*
G01X1893852Y992449D02*
X1893840Y992464D01*
G01X1893877Y992441D02*
X1893852Y992449D01*
G01X1908235Y957511D02*
X1908246Y957496D01*
G01X1908211Y957520D02*
X1908235Y957511D01*
G01Y962511D02*
X1908246Y962496D01*
G01X1908211Y962520D02*
X1908235Y962511D01*
G01X1908248Y1046134D02*
Y1046125D01*
G01X1908249Y1046140D02*
X1908248Y1046134D01*
G01X1908251Y1046142D02*
X1908249Y1046140D01*
G01X1908248Y1041134D02*
Y1041125D01*
G01X1908249Y1041140D02*
X1908248Y1041134D01*
G01X1908251Y1041142D02*
X1908249Y1041140D01*
G01X1908248Y1036134D02*
Y1036125D01*
G01X1908249Y1036140D02*
X1908248Y1036134D01*
G01X1908251Y1036142D02*
X1908249Y1036140D01*
G01X1908248Y1031134D02*
Y1031125D01*
G01X1908249Y1031140D02*
X1908248Y1031134D01*
G01X1908251Y1031142D02*
X1908249Y1031140D01*
G01X1908248Y1026134D02*
Y1026125D01*
G01X1908249Y1026140D02*
X1908248Y1026134D01*
G01X1908251Y1026142D02*
X1908249Y1026140D01*
G01X1908248Y1021134D02*
Y1021125D01*
G01X1908249Y1021140D02*
X1908248Y1021134D01*
G01X1908251Y1021142D02*
X1908249Y1021140D01*
G01X1908248Y1016134D02*
Y1016125D01*
G01X1908249Y1016140D02*
X1908248Y1016134D01*
G01X1908251Y1016142D02*
X1908249Y1016140D01*
G01X1908248Y1011134D02*
Y1011125D01*
G01X1908249Y1011140D02*
X1908248Y1011134D01*
G01X1908251Y1011142D02*
X1908249Y1011140D01*
G01X1893838Y1009337D02*
X1893839Y1009344D01*
G01X1893837Y1009332D02*
X1893838Y1009337D01*
G01X1893836Y1009331D02*
X1893837Y1009332D01*
G01X1893838Y1006187D02*
X1893839Y1006194D01*
G01X1893837Y1006183D02*
X1893838Y1006187D01*
G01X1893836Y1006181D02*
X1893837Y1006183D01*
G01X1893838Y1003037D02*
X1893839Y1003045D01*
G01X1893837Y1003033D02*
X1893838Y1003037D01*
G01X1893836Y1003031D02*
X1893837Y1003033D01*
G01X1893838Y999888D02*
X1893839Y999895D01*
G01X1893837Y999883D02*
X1893838Y999888D01*
G01X1893836Y999882D02*
X1893837Y999883D01*
G01X1893838Y996738D02*
X1893839Y996746D01*
G01X1893837Y996734D02*
X1893838Y996738D01*
G01X1893836Y996732D02*
X1893837Y996734D01*
G01X1893838Y993589D02*
X1893839Y993596D01*
G01X1893837Y993584D02*
X1893838Y993589D01*
G01X1893836Y993583D02*
X1893837Y993584D01*
G01X1893838Y990439D02*
X1893839Y990446D01*
G01X1893837Y990435D02*
X1893838Y990439D01*
G01X1893836Y990433D02*
X1893837Y990435D01*
G01X1893839Y995620D02*
Y995616D01*
G01X1893840Y995614D02*
X1893839Y995620D01*
G01X1893852Y995599D02*
X1893840Y995614D01*
G01X1893876Y995591D02*
X1893852Y995599D01*
G01X1893839Y1001919D02*
Y1001915D01*
G01X1893840Y1001913D02*
X1893839Y1001919D01*
G01X1893852Y1001898D02*
X1893840Y1001913D01*
G01X1893876Y1001890D02*
X1893852Y1001898D01*
G01X1893839Y1005069D02*
Y1005065D01*
G01X1893840Y1005063D02*
X1893839Y1005069D01*
G01X1893852Y1005048D02*
X1893840Y1005063D01*
G01X1893876Y1005039D02*
X1893852Y1005048D01*
G01X1893839Y989321D02*
Y989317D01*
G01X1893840Y989315D02*
X1893839Y989321D01*
G01X1893852Y989300D02*
X1893840Y989315D01*
G01X1893876Y989291D02*
X1893852Y989300D01*
G01X1893839Y1008219D02*
Y1008215D01*
G01X1893840Y1008213D02*
X1893839Y1008219D01*
G01X1893852Y1008197D02*
X1893840Y1008213D01*
G01X1893876Y1008189D02*
X1893852Y1008197D01*
G01X1908235Y967511D02*
X1908246Y967496D01*
G01X1908211Y967520D02*
X1908235Y967511D01*
G01Y972511D02*
X1908246Y972496D01*
G01X1908211Y972520D02*
X1908235Y972511D01*
G01Y977511D02*
X1908246Y977496D01*
G01X1908211Y977520D02*
X1908235Y977511D01*
G01Y982511D02*
X1908246Y982496D01*
G01X1908211Y982520D02*
X1908235Y982511D01*
G01Y987511D02*
X1908246Y987496D01*
G01X1908211Y987520D02*
X1908235Y987511D01*
G01Y1012511D02*
X1908246Y1012496D01*
G01X1908211Y1012520D02*
X1908235Y1012511D01*
G01Y1017511D02*
X1908246Y1017496D01*
G01X1908211Y1017520D02*
X1908235Y1017511D01*
G01Y1022511D02*
X1908246Y1022496D01*
G01X1908211Y1022520D02*
X1908235Y1022511D01*
G01Y1027511D02*
X1908246Y1027496D01*
G01X1908211Y1027520D02*
X1908235Y1027511D01*
G01Y1032511D02*
X1908246Y1032496D01*
G01X1908211Y1032520D02*
X1908235Y1032511D01*
G01Y1037511D02*
X1908246Y1037496D01*
G01X1908211Y1037520D02*
X1908235Y1037511D01*
G01Y1042511D02*
X1908246Y1042496D01*
G01X1908211Y1042520D02*
X1908235Y1042511D01*
G01Y1047511D02*
X1908246Y1047496D01*
G01X1908211Y1047520D02*
X1908235Y1047511D01*
G01X1893839Y998770D02*
Y998766D01*
G01X1893840Y998764D02*
X1893839Y998770D01*
G01X1893850Y998750D02*
X1893840Y998764D01*
G01X1893873Y998740D02*
X1893850Y998750D01*
G01X1894783Y1009375D02*
Y1009381D01*
G01Y1009371D02*
Y1009375D01*
G01X1894782Y1009370D02*
X1894783Y1009371D01*
G01Y1006226D02*
Y1006231D01*
G01Y1006222D02*
Y1006226D01*
G01X1894782Y1006220D02*
X1894783Y1006222D01*
G01Y1003076D02*
Y1003082D01*
G01Y1003072D02*
Y1003076D01*
G01X1894782Y1003071D02*
X1894783Y1003072D01*
G01Y999926D02*
Y999932D01*
G01Y999922D02*
Y999926D01*
G01X1894782Y999921D02*
X1894783Y999922D01*
G01Y996777D02*
Y996783D01*
G01Y996773D02*
Y996777D01*
G01X1894782Y996772D02*
X1894783Y996773D01*
G01Y993627D02*
Y993633D01*
G01Y993623D02*
Y993627D01*
G01X1894782Y993622D02*
X1894783Y993623D01*
G01Y990478D02*
Y990483D01*
G01Y990474D02*
Y990478D01*
G01X1894782Y990472D02*
X1894783Y990474D01*
G01X1908248Y986134D02*
Y986125D01*
G01X1908249Y986140D02*
X1908248Y986134D01*
G01X1908251Y986142D02*
X1908249Y986140D01*
G01X1908248Y981134D02*
Y981125D01*
G01X1908249Y981140D02*
X1908248Y981134D01*
G01X1908251Y981142D02*
X1908249Y981140D01*
G01X1908248Y976134D02*
Y976125D01*
G01X1908249Y976140D02*
X1908248Y976134D01*
G01X1908251Y976142D02*
X1908249Y976140D01*
G01X1908248Y971134D02*
Y971125D01*
G01X1908249Y971140D02*
X1908248Y971134D01*
G01X1908251Y971142D02*
X1908249Y971140D01*
G01X1908248Y966134D02*
Y966125D01*
G01X1908249Y966140D02*
X1908248Y966134D01*
G01X1908251Y966142D02*
X1908249Y966140D01*
G01X1908248Y961134D02*
Y961125D01*
G01X1908249Y961140D02*
X1908248Y961134D01*
G01X1908251Y961142D02*
X1908249Y961140D01*
G01X1908248Y956134D02*
Y956125D01*
G01X1908249Y956140D02*
X1908248Y956134D01*
G01X1908251Y956142D02*
X1908249Y956140D01*
G01X1894823Y1009337D02*
Y1009344D01*
G01X1894822Y1009332D02*
X1894823Y1009337D01*
G01X1894822Y1009331D02*
Y1009332D01*
G01X1893838Y992474D02*
X1893839Y992467D01*
G01X1893837Y992479D02*
X1893838Y992474D01*
G01X1893836Y992477D02*
X1893837Y992479D01*
G01X1894791Y996770D02*
X1894782Y996772D01*
G01X1894800Y996767D02*
X1894791Y996770D01*
G01X1894808Y996762D02*
X1894800Y996767D01*
G01X1894791Y990471D02*
X1894782Y990472D01*
G01X1894800Y990468D02*
X1894791Y990471D01*
G01X1894808Y990463D02*
X1894800Y990468D01*
G01X1894791Y993621D02*
X1894782Y993622D01*
G01X1894800Y993618D02*
X1894791Y993621D01*
G01X1894808Y993612D02*
X1894800Y993618D01*
G01X1894791Y999920D02*
X1894782Y999921D01*
G01X1894800Y999917D02*
X1894791Y999920D01*
G01X1894808Y999911D02*
X1894800Y999917D01*
G01X1894791Y1003070D02*
X1894782Y1003071D01*
G01X1894800Y1003067D02*
X1894791Y1003070D01*
G01X1894808Y1003061D02*
X1894800Y1003067D01*
G01X1894791Y1006219D02*
X1894782Y1006220D01*
G01X1894800Y1006216D02*
X1894791Y1006219D01*
G01X1894808Y1006211D02*
X1894800Y1006216D01*
G01X1894791Y1009369D02*
X1894782Y1009370D01*
G01X1894800Y1009366D02*
X1894791Y1009369D01*
G01X1894808Y1009360D02*
X1894800Y1009366D01*
G01X1893852Y1009361D02*
X1893876Y1009370D01*
G01X1893841Y1009347D02*
X1893852Y1009361D01*
G01X1893839Y1009340D02*
X1893841Y1009347D01*
G01X1893852Y1006212D02*
X1893876Y1006220D01*
G01X1893841Y1006197D02*
X1893852Y1006212D01*
G01X1893839Y1006191D02*
X1893841Y1006197D01*
G01X1893852Y1003062D02*
X1893876Y1003071D01*
G01X1893841Y1003048D02*
X1893852Y1003062D01*
G01X1893839Y1003041D02*
X1893841Y1003048D01*
G01X1893852Y999913D02*
X1893876Y999921D01*
G01X1893841Y999898D02*
X1893852Y999913D01*
G01X1893839Y999891D02*
X1893841Y999898D01*
G01X1893852Y996763D02*
X1893876Y996772D01*
G01X1893841Y996748D02*
X1893852Y996763D01*
G01X1893839Y996742D02*
X1893841Y996748D01*
G01X1893852Y993613D02*
X1893876Y993622D01*
G01X1893841Y993599D02*
X1893852Y993613D01*
G01X1893839Y993592D02*
X1893841Y993599D01*
G01X1893852Y990464D02*
X1893876Y990472D01*
G01X1893841Y990449D02*
X1893852Y990464D01*
G01X1893839Y990443D02*
X1893841Y990449D01*
G01X1894823Y1006187D02*
Y1006194D01*
G01X1894822Y1006183D02*
X1894823Y1006187D01*
G01X1894822Y1006181D02*
Y1006183D01*
G01X1894823Y1003038D02*
Y1003045D01*
G01X1894822Y1003033D02*
X1894823Y1003038D01*
G01X1894822Y1003031D02*
Y1003033D01*
G01X1894823Y999888D02*
Y999895D01*
G01X1894822Y999883D02*
X1894823Y999888D01*
G01X1894822Y999882D02*
Y999883D01*
G01X1894823Y996739D02*
Y996746D01*
G01X1894822Y996734D02*
X1894823Y996739D01*
G01X1894822Y996732D02*
Y996734D01*
G01X1894823Y993589D02*
Y993596D01*
G01X1894822Y993584D02*
X1894823Y993589D01*
G01X1894822Y993583D02*
Y993584D01*
G01X1894823Y990439D02*
Y990446D01*
G01X1894822Y990435D02*
X1894823Y990439D01*
G01X1894822Y990433D02*
Y990435D01*
G01X1893838Y998774D02*
X1893839Y998766D01*
G01X1893837Y998778D02*
X1893838Y998774D01*
G01X1893836Y998775D02*
X1893837Y998778D01*
G01X1893878Y989286D02*
Y989280D01*
G01X1893877Y989290D02*
X1893878Y989286D01*
G01X1893876Y989291D02*
X1893877Y989290D01*
G01X1893878Y992436D02*
Y992430D01*
G01X1893877Y992440D02*
X1893878Y992436D01*
G01X1893876Y992441D02*
X1893877Y992440D01*
G01X1893878Y995585D02*
Y995579D01*
G01X1893877Y995589D02*
X1893878Y995585D01*
G01X1893876Y995591D02*
X1893877Y995589D01*
G01X1893878Y998735D02*
Y998729D01*
G01X1893877Y998739D02*
X1893878Y998735D01*
G01X1893876Y998740D02*
X1893877Y998739D01*
G01X1893878Y1001885D02*
Y1001878D01*
G01X1893877Y1001889D02*
X1893878Y1001885D01*
G01X1893876Y1001890D02*
X1893877Y1001889D01*
G01X1893878Y1005034D02*
Y1005028D01*
G01X1893877Y1005038D02*
X1893878Y1005034D01*
G01X1893876Y1005039D02*
X1893877Y1005038D01*
G01X1893878Y1008184D02*
Y1008178D01*
G01X1893877Y1008188D02*
X1893878Y1008184D01*
G01X1893876Y1008189D02*
X1893877Y1008188D01*
G01X1893876Y1008017D02*
X1893874Y1008031D01*
G01X1893879Y1008005D02*
X1893876Y1008017D01*
G01X1893878Y1007992D02*
X1893879Y1008005D01*
G01X1893876Y1004868D02*
X1893874Y1004881D01*
G01X1893879Y1004855D02*
X1893876Y1004868D01*
G01X1893878Y1004843D02*
X1893879Y1004855D01*
G01X1893876Y1001718D02*
X1893874Y1001732D01*
G01X1893879Y1001706D02*
X1893876Y1001718D01*
G01X1893878Y1001693D02*
X1893879Y1001706D01*
G01X1893876Y998569D02*
X1893874Y998582D01*
G01X1893879Y998556D02*
X1893876Y998569D01*
G01X1893878Y998543D02*
X1893879Y998556D01*
G01X1893876Y995419D02*
X1893874Y995433D01*
G01X1893879Y995406D02*
X1893876Y995419D01*
G01X1893878Y995394D02*
X1893879Y995406D01*
G01X1893876Y992269D02*
X1893874Y992283D01*
G01X1893879Y992257D02*
X1893876Y992269D01*
G01X1893878Y992244D02*
X1893879Y992257D01*
G01X1893876Y989120D02*
X1893874Y989133D01*
G01X1893879Y989107D02*
X1893876Y989120D01*
G01X1893878Y989094D02*
X1893879Y989107D01*
G01X1894786Y1009541D02*
X1894787Y1009528D01*
G01X1894783Y1009554D02*
X1894786Y1009541D01*
G01X1894783Y1009567D02*
Y1009554D01*
G01X1894786Y1006392D02*
X1894787Y1006378D01*
G01X1894783Y1006405D02*
X1894786Y1006392D01*
G01X1894783Y1006417D02*
Y1006405D01*
G01X1894786Y1003242D02*
X1894787Y1003228D01*
G01X1894783Y1003255D02*
X1894786Y1003242D01*
G01X1894783Y1003268D02*
Y1003255D01*
G01X1894786Y1000093D02*
X1894787Y1000079D01*
G01X1894783Y1000106D02*
X1894786Y1000093D01*
G01X1894783Y1000118D02*
Y1000106D01*
G01X1894786Y996943D02*
X1894787Y996929D01*
G01X1894783Y996956D02*
X1894786Y996943D01*
G01X1894783Y996969D02*
Y996956D01*
G01X1894786Y993793D02*
X1894787Y993780D01*
G01X1894783Y993806D02*
X1894786Y993793D01*
G01X1894783Y993819D02*
Y993806D01*
G01X1894786Y990644D02*
X1894787Y990630D01*
G01X1894783Y990657D02*
X1894786Y990644D01*
G01X1894783Y990669D02*
Y990657D01*
G01X1893838Y995624D02*
X1893839Y995617D01*
G01X1893837Y995628D02*
X1893838Y995624D01*
G01X1893837Y995621D02*
Y995628D01*
G01X1893838Y1005073D02*
X1893839Y1005065D01*
G01X1893837Y1005077D02*
X1893838Y1005073D01*
G01X1893837Y1005070D02*
Y1005077D01*
G01X1894783Y1008005D02*
Y1007992D01*
G01X1894785Y1008017D02*
X1894783Y1008005D01*
G01X1894787Y1008031D02*
X1894785Y1008017D01*
G01X1894783Y1004855D02*
Y1004843D01*
G01X1894785Y1004868D02*
X1894783Y1004855D01*
G01X1894787Y1004881D02*
X1894785Y1004868D01*
G01X1894783Y1001706D02*
Y1001693D01*
G01X1894785Y1001718D02*
X1894783Y1001706D01*
G01X1894787Y1001732D02*
X1894785Y1001718D01*
G01X1894783Y998556D02*
Y998543D01*
G01X1894785Y998569D02*
X1894783Y998556D01*
G01X1894787Y998582D02*
X1894785Y998569D01*
G01X1894783Y995406D02*
Y995394D01*
G01X1894785Y995419D02*
X1894783Y995406D01*
G01X1894787Y995433D02*
X1894785Y995419D01*
G01X1894783Y992257D02*
Y992244D01*
G01X1894785Y992269D02*
X1894783Y992257D01*
G01X1894787Y992283D02*
X1894785Y992269D01*
G01X1894783Y989107D02*
Y989094D01*
G01X1894785Y989120D02*
X1894783Y989107D01*
G01X1894787Y989133D02*
X1894785Y989120D01*
G01X1893838Y989325D02*
X1893839Y989317D01*
G01X1893837Y989329D02*
X1893838Y989325D01*
G01X1893837Y989323D02*
Y989329D01*
G01X1908248Y957487D02*
Y957494D01*
G01X1908249Y957482D02*
X1908248Y957487D01*
G01X1908250Y957480D02*
X1908249Y957482D01*
G01X1908248Y962487D02*
Y962494D01*
G01X1908249Y962482D02*
X1908248Y962487D01*
G01X1908250Y962480D02*
X1908249Y962482D01*
G01X1908248Y967487D02*
Y967494D01*
G01X1908249Y967482D02*
X1908248Y967487D01*
G01X1908250Y967480D02*
X1908249Y967482D01*
G01X1908248Y972487D02*
Y972494D01*
G01X1908249Y972482D02*
X1908248Y972487D01*
G01X1908250Y972480D02*
X1908249Y972482D01*
G01X1908248Y977487D02*
Y977494D01*
G01X1908249Y977482D02*
X1908248Y977487D01*
G01X1908250Y977480D02*
X1908249Y977482D01*
G01X1908248Y982487D02*
Y982494D01*
G01X1908249Y982482D02*
X1908248Y982487D01*
G01X1908250Y982480D02*
X1908249Y982482D01*
G01X1908248Y987487D02*
Y987494D01*
G01X1908249Y987482D02*
X1908248Y987487D01*
G01X1908250Y987480D02*
X1908249Y987482D01*
G01X1908248Y1012487D02*
Y1012494D01*
G01X1908249Y1012482D02*
X1908248Y1012487D01*
G01X1908250Y1012480D02*
X1908249Y1012482D01*
G01X1908248Y1017487D02*
Y1017494D01*
G01X1908249Y1017482D02*
X1908248Y1017487D01*
G01X1908250Y1017480D02*
X1908249Y1017482D01*
G01X1908248Y1022487D02*
Y1022494D01*
G01X1908249Y1022482D02*
X1908248Y1022487D01*
G01X1908250Y1022480D02*
X1908249Y1022482D01*
G01X1908248Y1027487D02*
Y1027494D01*
G01X1908249Y1027482D02*
X1908248Y1027487D01*
G01X1908250Y1027480D02*
X1908249Y1027482D01*
G01X1908248Y1032487D02*
Y1032494D01*
G01X1908249Y1032482D02*
X1908248Y1032487D01*
G01X1908250Y1032480D02*
X1908249Y1032482D01*
G01X1908248Y1037487D02*
Y1037494D01*
G01X1908249Y1037482D02*
X1908248Y1037487D01*
G01X1908250Y1037480D02*
X1908249Y1037482D01*
G01X1893861Y992443D02*
X1893876Y992441D01*
G01X1893850Y992450D02*
X1893861Y992443D01*
G01X1893838Y992469D02*
X1893850Y992450D01*
G01X1893861Y1001892D02*
X1893876Y1001890D01*
G01X1893850Y1001900D02*
X1893861Y1001892D01*
G01X1893838Y1001918D02*
X1893850Y1001900D01*
G01X1908215Y957618D02*
X1908219Y957717D01*
G01X1908209Y957546D02*
X1908215Y957618D01*
G01X1908211Y957520D02*
X1908209Y957546D01*
G01X1908215Y962618D02*
X1908219Y962717D01*
G01X1908209Y962546D02*
X1908215Y962618D01*
G01X1908211Y962520D02*
X1908209Y962546D01*
G01X1908215Y967618D02*
X1908219Y967717D01*
G01X1908209Y967546D02*
X1908215Y967618D01*
G01X1908211Y967520D02*
X1908209Y967546D01*
G01X1908215Y972618D02*
X1908219Y972717D01*
G01X1908209Y972546D02*
X1908215Y972618D01*
G01X1908211Y972520D02*
X1908209Y972546D01*
G01X1908215Y977618D02*
X1908219Y977717D01*
G01X1908209Y977546D02*
X1908215Y977618D01*
G01X1908211Y977520D02*
X1908209Y977546D01*
G01X1908215Y982618D02*
X1908219Y982717D01*
G01X1908209Y982546D02*
X1908215Y982618D01*
G01X1908211Y982520D02*
X1908209Y982546D01*
G01X1908215Y987618D02*
X1908219Y987717D01*
G01X1908209Y987546D02*
X1908215Y987618D01*
G01X1908211Y987520D02*
X1908209Y987546D01*
G01X1908215Y1012618D02*
X1908219Y1012717D01*
G01X1908209Y1012546D02*
X1908215Y1012618D01*
G01X1908211Y1012520D02*
X1908209Y1012546D01*
G01X1908215Y1017618D02*
X1908219Y1017717D01*
G01X1908209Y1017546D02*
X1908215Y1017618D01*
G01X1908211Y1017520D02*
X1908209Y1017546D01*
G01X1908215Y1022618D02*
X1908219Y1022717D01*
G01X1908209Y1022546D02*
X1908215Y1022618D01*
G01X1908211Y1022520D02*
X1908209Y1022546D01*
G01X1908215Y1027618D02*
X1908219Y1027717D01*
G01X1908209Y1027546D02*
X1908215Y1027618D01*
G01X1908211Y1027520D02*
X1908209Y1027546D01*
G01X1908215Y1032618D02*
X1908219Y1032717D01*
G01X1908209Y1032546D02*
X1908215Y1032618D01*
G01X1908211Y1032520D02*
X1908209Y1032546D01*
G01X1908215Y1037618D02*
X1908219Y1037717D01*
G01X1908209Y1037546D02*
X1908215Y1037618D01*
G01X1908211Y1037520D02*
X1908209Y1037546D01*
G01X1908215Y1042618D02*
X1908219Y1042717D01*
G01X1908209Y1042546D02*
X1908215Y1042618D01*
G01X1908211Y1042520D02*
X1908209Y1042546D01*
G01X1893838Y1001923D02*
X1893839Y1001916D01*
G01X1893837Y1001928D02*
X1893838Y1001923D01*
G01Y1001918D02*
X1893837Y1001928D01*
G01X1893879Y1009554D02*
X1893878Y1009567D01*
G01X1893876Y1009541D02*
X1893879Y1009554D01*
G01X1893876Y1009528D02*
Y1009541D01*
G01X1893879Y1006405D02*
X1893878Y1006417D01*
G01X1893876Y1006392D02*
X1893879Y1006405D01*
G01X1893876Y1006378D02*
Y1006392D01*
G01X1893879Y1003255D02*
X1893878Y1003268D01*
G01X1893876Y1003242D02*
X1893879Y1003255D01*
G01X1893876Y1003228D02*
Y1003242D01*
G01X1893879Y1000106D02*
X1893878Y1000118D01*
G01X1893876Y1000093D02*
X1893879Y1000106D01*
G01X1893876Y1000079D02*
Y1000093D01*
G01X1893879Y996956D02*
X1893878Y996969D01*
G01X1893876Y996943D02*
X1893879Y996956D01*
G01X1893876Y996929D02*
Y996943D01*
G01X1893879Y993806D02*
X1893878Y993819D01*
G01X1893876Y993793D02*
X1893879Y993806D01*
G01X1893876Y993780D02*
Y993793D01*
G01X1893879Y990657D02*
X1893878Y990669D01*
G01X1893876Y990644D02*
X1893879Y990657D01*
G01X1893876Y990630D02*
Y990644D01*
G01X1907265Y1046140D02*
Y1046142D01*
G01X1907264Y1046134D02*
X1907265Y1046140D01*
G01X1907264Y1046126D02*
Y1046134D01*
G01X1907265Y1041140D02*
Y1041142D01*
G01X1907264Y1041134D02*
X1907265Y1041140D01*
G01X1907264Y1041126D02*
Y1041134D01*
G01X1907265Y1036140D02*
Y1036142D01*
G01X1907264Y1036134D02*
X1907265Y1036140D01*
G01X1907264Y1036126D02*
Y1036134D01*
G01X1907265Y1031140D02*
Y1031142D01*
G01X1907264Y1031134D02*
X1907265Y1031140D01*
G01X1907264Y1031126D02*
Y1031134D01*
G01X1907265Y1026140D02*
Y1026142D01*
G01X1907264Y1026134D02*
X1907265Y1026140D01*
G01X1907264Y1026126D02*
Y1026134D01*
G01X1907265Y1021140D02*
Y1021142D01*
G01X1907264Y1021134D02*
X1907265Y1021140D01*
G01X1907264Y1021126D02*
Y1021134D01*
G01X1907265Y1016140D02*
Y1016142D01*
G01X1907264Y1016134D02*
X1907265Y1016140D01*
G01X1907264Y1016126D02*
Y1016134D01*
G01X1907265Y1011140D02*
Y1011142D01*
G01X1907264Y1011134D02*
X1907265Y1011140D01*
G01X1907264Y1011126D02*
Y1011134D01*
G01X1907265Y986140D02*
Y986142D01*
G01X1907264Y986134D02*
X1907265Y986140D01*
G01X1907264Y986126D02*
Y986134D01*
G01X1907265Y981140D02*
Y981142D01*
G01X1907264Y981134D02*
X1907265Y981140D01*
G01X1907264Y981126D02*
Y981134D01*
G01X1907265Y976140D02*
Y976142D01*
G01X1907264Y976134D02*
X1907265Y976140D01*
G01X1907264Y976126D02*
Y976134D01*
G01X1907265Y971140D02*
Y971142D01*
G01X1907264Y971134D02*
X1907265Y971140D01*
G01X1907264Y971126D02*
Y971134D01*
G01X1907265Y966140D02*
Y966142D01*
G01X1907264Y966134D02*
X1907265Y966140D01*
G01X1907264Y966126D02*
Y966134D01*
G01X1907265Y961140D02*
Y961142D01*
G01X1907264Y961134D02*
X1907265Y961140D01*
G01X1907264Y961126D02*
Y961134D01*
G01X1907265Y956140D02*
Y956142D01*
G01X1907264Y956134D02*
X1907265Y956140D01*
G01X1907264Y956126D02*
Y956134D01*
G01X1893838Y1008222D02*
X1893839Y1008215D01*
G01X1893837Y1008227D02*
X1893838Y1008222D01*
G01X1893837Y1008219D02*
Y1008227D01*
G01X1908248Y1042487D02*
Y1042494D01*
G01X1908249Y1042482D02*
X1908248Y1042487D01*
G01X1908250Y1042480D02*
X1908249Y1042482D01*
G01Y1047482D02*
X1908248Y1047487D01*
G01X1908250Y1047480D02*
X1908249Y1047482D01*
G01X1893861Y995593D02*
X1893876Y995591D01*
G01X1893849Y995601D02*
X1893861Y995593D01*
G01X1893837Y995621D02*
X1893849Y995601D01*
G01X1893861Y1005042D02*
X1893876Y1005039D01*
G01X1893849Y1005050D02*
X1893861Y1005042D01*
G01X1893837Y1005070D02*
X1893849Y1005050D01*
G01X1894823Y989325D02*
Y989317D01*
G01X1894822Y989329D02*
X1894823Y989325D01*
G01X1894821Y989331D02*
X1894822Y989329D01*
G01X1894823Y992474D02*
Y992467D01*
G01X1894822Y992479D02*
X1894823Y992474D01*
G01X1894821Y992480D02*
X1894822Y992479D01*
G01X1894823Y995624D02*
Y995616D01*
G01X1894822Y995628D02*
X1894823Y995624D01*
G01X1894821Y995630D02*
X1894822Y995628D01*
G01X1894823Y998774D02*
Y998766D01*
G01X1894822Y998778D02*
X1894823Y998774D01*
G01X1894821Y998780D02*
X1894822Y998778D01*
G01X1894823Y1001923D02*
Y1001915D01*
G01X1894822Y1001928D02*
X1894823Y1001923D01*
G01X1894821Y1001929D02*
X1894822Y1001928D01*
G01X1894823Y1005073D02*
Y1005065D01*
G01X1894822Y1005077D02*
X1894823Y1005073D01*
G01X1894821Y1005079D02*
X1894822Y1005077D01*
G01X1894823Y1008222D02*
Y1008215D01*
G01X1894822Y1008227D02*
X1894823Y1008222D01*
G01X1894821Y1008228D02*
X1894822Y1008227D01*
G01X1893861Y1008192D02*
X1893876Y1008189D01*
G01X1893848Y1008200D02*
X1893861Y1008192D01*
G01X1893837Y1008220D02*
X1893848Y1008200D01*
G01X1893861Y989294D02*
X1893876Y989291D01*
G01X1893848Y989303D02*
X1893861Y989294D01*
G01X1893837Y989323D02*
X1893848Y989303D01*
G01X1894822Y990453D02*
X1894823Y990446D01*
G01X1894820Y990459D02*
X1894822Y990453D01*
G01X1894817Y990465D02*
X1894820Y990459D01*
G01X1894822Y993603D02*
X1894823Y993596D01*
G01X1894820Y993609D02*
X1894822Y993603D01*
G01X1894817Y993615D02*
X1894820Y993609D01*
G01X1894822Y996752D02*
X1894823Y996746D01*
G01X1894820Y996759D02*
X1894822Y996752D01*
G01X1894817Y996765D02*
X1894820Y996759D01*
G01X1894822Y999902D02*
X1894823Y999895D01*
G01X1894820Y999908D02*
X1894822Y999902D01*
G01X1894817Y999914D02*
X1894820Y999908D01*
G01X1894822Y1003052D02*
X1894823Y1003045D01*
G01X1894820Y1003058D02*
X1894822Y1003052D01*
G01X1894817Y1003064D02*
X1894820Y1003058D01*
G01X1894822Y1006201D02*
X1894823Y1006194D01*
G01X1894820Y1006207D02*
X1894822Y1006201D01*
G01X1894817Y1006213D02*
X1894820Y1006207D01*
G01X1894822Y1009351D02*
X1894823Y1009344D01*
G01X1894820Y1009357D02*
X1894822Y1009351D01*
G01X1894817Y1009363D02*
X1894820Y1009357D01*
G01X1894784Y989286D02*
Y989280D01*
G01X1894783Y989290D02*
X1894784Y989286D01*
G01X1894782Y989291D02*
X1894783Y989290D01*
G01X1894784Y992436D02*
Y992430D01*
G01X1894783Y992439D02*
X1894784Y992436D01*
G01X1894782Y992441D02*
X1894783Y992439D01*
G01X1894784Y995585D02*
Y995579D01*
G01X1894783Y995589D02*
X1894784Y995585D01*
G01X1894782Y995591D02*
X1894783Y995589D01*
G01X1894784Y998735D02*
Y998729D01*
G01X1894783Y998739D02*
X1894784Y998735D01*
G01X1894782Y998740D02*
X1894783Y998739D01*
G01X1894784Y1001885D02*
Y1001878D01*
G01X1894783Y1001888D02*
X1894784Y1001885D01*
G01X1894782Y1001890D02*
X1894783Y1001888D01*
G01X1894784Y1008184D02*
Y1008178D01*
G01X1894783Y1008187D02*
X1894784Y1008184D01*
G01X1894782Y1008189D02*
X1894783Y1008187D01*
G01X1907264Y957527D02*
Y957536D01*
G01X1907265Y957521D02*
X1907264Y957527D01*
G01X1907265Y957520D02*
Y957521D01*
G01X1907264Y962527D02*
Y962536D01*
G01X1907265Y962521D02*
X1907264Y962527D01*
G01X1907265Y962520D02*
Y962521D01*
G01X1907264Y967527D02*
Y967536D01*
G01X1907265Y967521D02*
X1907264Y967527D01*
G01X1907265Y967520D02*
Y967521D01*
G01X1907264Y972527D02*
Y972536D01*
G01X1907265Y972521D02*
X1907264Y972527D01*
G01X1907265Y972520D02*
Y972521D01*
G01X1907264Y977527D02*
Y977536D01*
G01X1907265Y977521D02*
X1907264Y977527D01*
G01X1907265Y977520D02*
Y977521D01*
G01X1907264Y982527D02*
Y982536D01*
G01X1907265Y982521D02*
X1907264Y982527D01*
G01X1907265Y982520D02*
Y982521D01*
G01X1907264Y987527D02*
Y987536D01*
G01X1907265Y987521D02*
X1907264Y987527D01*
G01X1907265Y987520D02*
Y987521D01*
G01X1907264Y1012527D02*
Y1012536D01*
G01X1907265Y1012521D02*
X1907264Y1012527D01*
G01X1907265Y1012520D02*
Y1012521D01*
G01X1907264Y1017527D02*
Y1017536D01*
G01X1907265Y1017521D02*
X1907264Y1017527D01*
G01X1907265Y1017520D02*
Y1017521D01*
G01X1907264Y1022527D02*
Y1022536D01*
G01X1907265Y1022521D02*
X1907264Y1022527D01*
G01X1907265Y1022520D02*
Y1022521D01*
G01X1907264Y1027527D02*
Y1027536D01*
G01X1907265Y1027521D02*
X1907264Y1027527D01*
G01X1907265Y1027520D02*
Y1027521D01*
G01X1907264Y1032527D02*
Y1032536D01*
G01X1907265Y1032521D02*
X1907264Y1032527D01*
G01X1907265Y1032520D02*
Y1032521D01*
G01X1907264Y1037527D02*
Y1037536D01*
G01X1907265Y1037521D02*
X1907264Y1037527D01*
G01X1907265Y1037520D02*
Y1037521D01*
G01X1907264Y1042527D02*
Y1042536D01*
G01X1907265Y1042521D02*
X1907264Y1042527D01*
G01X1907265Y1042520D02*
Y1042521D01*
G01X1908240Y957663D02*
X1908248Y957637D01*
G01X1908230Y957690D02*
X1908240Y957663D01*
G01X1908219Y957717D02*
X1908230Y957690D01*
G01X1908240Y962663D02*
X1908248Y962637D01*
G01X1908230Y962690D02*
X1908240Y962663D01*
G01X1908219Y962717D02*
X1908230Y962690D01*
G01X1908240Y967663D02*
X1908248Y967637D01*
G01X1908230Y967690D02*
X1908240Y967663D01*
G01X1908219Y967717D02*
X1908230Y967690D01*
G01X1908240Y972663D02*
X1908248Y972637D01*
G01X1908230Y972690D02*
X1908240Y972663D01*
G01X1908219Y972717D02*
X1908230Y972690D01*
G01X1908240Y977663D02*
X1908248Y977637D01*
G01X1908230Y977690D02*
X1908240Y977663D01*
G01X1908219Y977717D02*
X1908230Y977690D01*
G01X1908240Y982663D02*
X1908248Y982637D01*
G01X1908230Y982690D02*
X1908240Y982663D01*
G01X1908219Y982717D02*
X1908230Y982690D01*
G01X1908240Y987663D02*
X1908248Y987637D01*
G01X1908230Y987690D02*
X1908240Y987663D01*
G01X1908219Y987717D02*
X1908230Y987690D01*
G01X1908240Y1012663D02*
X1908248Y1012637D01*
G01X1908230Y1012690D02*
X1908240Y1012663D01*
G01X1908219Y1012717D02*
X1908230Y1012690D01*
G01X1908240Y1017663D02*
X1908248Y1017637D01*
G01X1908230Y1017690D02*
X1908240Y1017663D01*
G01X1908219Y1017717D02*
X1908230Y1017690D01*
G01X1908240Y1022663D02*
X1908248Y1022637D01*
G01X1908230Y1022690D02*
X1908240Y1022663D01*
G01X1908219Y1022717D02*
X1908230Y1022690D01*
G01X1908240Y1027663D02*
X1908248Y1027637D01*
G01X1908230Y1027690D02*
X1908240Y1027663D01*
G01X1908219Y1027717D02*
X1908230Y1027690D01*
G01X1908240Y1032663D02*
X1908248Y1032637D01*
G01X1908230Y1032690D02*
X1908240Y1032663D01*
G01X1908219Y1032717D02*
X1908230Y1032690D01*
G01X1908240Y1037663D02*
X1908248Y1037637D01*
G01X1908230Y1037690D02*
X1908240Y1037663D01*
G01X1908219Y1037717D02*
X1908230Y1037690D01*
G01X1908240Y1042663D02*
X1908248Y1042637D01*
G01X1908230Y1042690D02*
X1908240Y1042663D01*
G01X1908219Y1042717D02*
X1908230Y1042690D01*
G01X1893856Y998745D02*
X1893876Y998740D01*
G01X1893843Y998757D02*
X1893856Y998745D01*
G01X1893836Y998775D02*
X1893843Y998757D01*
G01X1908231Y957515D02*
X1908211Y957520D01*
G01X1908245Y957500D02*
X1908231Y957515D01*
G01X1908250Y957480D02*
X1908245Y957500D01*
G01X1908231Y962515D02*
X1908211Y962520D01*
G01X1908245Y962500D02*
X1908231Y962515D01*
G01X1908250Y962480D02*
X1908245Y962500D01*
G01X1908231Y967515D02*
X1908211Y967520D01*
G01X1908245Y967500D02*
X1908231Y967515D01*
G01X1908250Y967480D02*
X1908245Y967500D01*
G01X1908231Y972515D02*
X1908211Y972520D01*
G01X1908245Y972500D02*
X1908231Y972515D01*
G01X1908250Y972480D02*
X1908245Y972500D01*
G01X1908231Y977515D02*
X1908211Y977520D01*
G01X1908245Y977500D02*
X1908231Y977515D01*
G01X1908250Y977480D02*
X1908245Y977500D01*
G01X1908231Y982515D02*
X1908211Y982520D01*
G01X1908245Y982500D02*
X1908231Y982515D01*
G01X1908250Y982480D02*
X1908245Y982500D01*
G01X1908231Y987515D02*
X1908211Y987520D01*
G01X1908245Y987500D02*
X1908231Y987515D01*
G01X1908250Y987480D02*
X1908245Y987500D01*
G01X1908231Y1012515D02*
X1908211Y1012520D01*
G01X1908245Y1012500D02*
X1908231Y1012515D01*
G01X1908250Y1012480D02*
X1908245Y1012500D01*
G01X1908231Y1017515D02*
X1908211Y1017520D01*
G01X1908245Y1017500D02*
X1908231Y1017515D01*
G01X1908250Y1017480D02*
X1908245Y1017500D01*
G01X1908231Y1022515D02*
X1908211Y1022520D01*
G01X1908245Y1022500D02*
X1908231Y1022515D01*
G01X1908250Y1022480D02*
X1908245Y1022500D01*
G01X1908231Y1027515D02*
X1908211Y1027520D01*
G01X1908245Y1027500D02*
X1908231Y1027515D01*
G01X1908250Y1027480D02*
X1908245Y1027500D01*
G01X1908231Y1032515D02*
X1908211Y1032520D01*
G01X1908245Y1032500D02*
X1908231Y1032515D01*
G01X1908250Y1032480D02*
X1908245Y1032500D01*
G01X1908231Y1037515D02*
X1908211Y1037520D01*
G01X1908245Y1037500D02*
X1908231Y1037515D01*
G01X1908250Y1037480D02*
X1908245Y1037500D01*
G01X1908231Y1042515D02*
X1908211Y1042520D01*
G01X1908245Y1042500D02*
X1908231Y1042515D01*
G01X1908250Y1042480D02*
X1908245Y1042500D01*
G01X1908231Y1047515D02*
X1908211Y1047520D01*
G01X1908245Y1047500D02*
X1908231Y1047515D01*
G01X1908250Y1047480D02*
X1908245Y1047500D01*
G01X1894815Y996754D02*
X1894808Y996762D01*
G01X1894820Y996743D02*
X1894815Y996754D01*
G01X1894822Y996732D02*
X1894820Y996743D01*
G01X1894815Y990454D02*
X1894808Y990463D01*
G01X1894820Y990444D02*
X1894815Y990454D01*
G01X1894822Y990433D02*
X1894820Y990444D01*
G01X1894815Y993604D02*
X1894808Y993612D01*
G01X1894820Y993594D02*
X1894815Y993604D01*
G01X1894822Y993583D02*
X1894820Y993594D01*
G01X1894815Y999903D02*
X1894808Y999911D01*
G01X1894820Y999893D02*
X1894815Y999903D01*
G01X1894822Y999882D02*
X1894820Y999893D01*
G01X1894815Y1003053D02*
X1894808Y1003061D01*
G01X1894820Y1003043D02*
X1894815Y1003053D01*
G01X1894822Y1003031D02*
X1894820Y1003043D01*
G01X1894815Y1006202D02*
X1894808Y1006211D01*
G01X1894820Y1006192D02*
X1894815Y1006202D01*
G01X1894822Y1006181D02*
X1894820Y1006192D01*
G01X1894815Y1009352D02*
X1894808Y1009360D01*
G01X1894820Y1009342D02*
X1894815Y1009352D01*
G01X1894822Y1009331D02*
X1894820Y1009342D01*
G01X1894782Y1005039D02*
X1894785Y1005028D01*
G01X1894822Y990435D02*
X1894823Y990446D01*
G01X1894822Y993585D02*
X1894823Y993596D01*
G01X1894822Y996734D02*
X1894823Y996746D01*
G01X1894822Y999884D02*
X1894823Y999895D01*
G01X1894822Y1003033D02*
X1894823Y1003045D01*
G01X1894822Y1006183D02*
X1894823Y1006194D01*
G01X1894822Y1009333D02*
X1894823Y1009344D01*
G01X1908248Y957494D02*
Y957502D01*
G01Y962494D02*
Y962502D01*
G01Y967494D02*
Y967502D01*
G01Y972494D02*
Y972502D01*
G01Y977494D02*
Y977502D01*
G01Y982494D02*
Y982502D01*
G01Y987494D02*
Y987502D01*
G01Y1012494D02*
Y1012502D01*
G01Y1017494D02*
Y1017502D01*
G01Y1022494D02*
Y1022502D01*
G01Y1027494D02*
Y1027502D01*
G01Y1032494D02*
Y1032502D01*
G01Y1037494D02*
Y1037502D01*
G01Y1042494D02*
Y1042502D01*
G01X1909429Y957520D02*
Y956142D01*
G01Y962520D02*
Y961142D01*
G01Y967520D02*
Y966142D01*
G01Y972520D02*
Y971142D01*
G01Y977520D02*
Y976142D01*
G01Y982520D02*
Y981142D01*
G01Y987520D02*
Y986142D01*
G01Y1012520D02*
Y1011142D01*
G01Y1017520D02*
Y1016142D01*
G01Y1022520D02*
Y1021142D01*
G01Y1027520D02*
Y1026142D01*
G01Y1032520D02*
Y1031142D01*
G01Y1037520D02*
Y1036142D01*
G01Y1042520D02*
Y1041142D01*
G01Y1047520D02*
Y1046142D01*
G01X1908858Y1010374D02*
Y988287D01*
G01X1908248Y1045650D02*
Y1048012D01*
G01Y1040650D02*
Y1043012D01*
G01Y1035650D02*
Y1038012D01*
G01Y1030650D02*
Y1033012D01*
G01Y1025650D02*
Y1028012D01*
G01Y1020650D02*
Y1023012D01*
G01Y1015650D02*
Y1018012D01*
G01Y1010650D02*
Y1013012D01*
G01Y985650D02*
Y988012D01*
G01Y980650D02*
Y983012D01*
G01Y975650D02*
Y978012D01*
G01Y970650D02*
Y973012D01*
G01Y965650D02*
Y968012D01*
G01Y960650D02*
Y963012D01*
G01Y955650D02*
Y958012D01*
G01Y962494D02*
Y962637D01*
G01Y957494D02*
Y957637D01*
G01Y972494D02*
Y972637D01*
G01Y967494D02*
Y967637D01*
G01Y982494D02*
Y982637D01*
G01Y977494D02*
Y977637D01*
G01Y987494D02*
Y987637D01*
G01Y1012494D02*
Y1012637D01*
G01Y1022494D02*
Y1022637D01*
G01Y1017494D02*
Y1017637D01*
G01Y1032494D02*
Y1032637D01*
G01Y1027494D02*
Y1027637D01*
G01Y1042494D02*
Y1042637D01*
G01Y1037494D02*
Y1037637D01*
G01X1907677Y1009193D02*
Y989469D01*
G01X1907264Y958012D02*
Y955650D01*
G01Y963012D02*
Y960650D01*
G01Y968012D02*
Y965650D01*
G01Y973012D02*
Y970650D01*
G01Y978012D02*
Y975650D01*
G01Y983012D02*
Y980650D01*
G01Y988012D02*
Y985650D01*
G01Y1013012D02*
Y1010650D01*
G01Y1018012D02*
Y1015650D01*
G01Y1023012D02*
Y1020650D01*
G01Y1028012D02*
Y1025650D01*
G01Y1033012D02*
Y1030650D01*
G01Y1038012D02*
Y1035650D01*
G01Y1043012D02*
Y1040650D01*
G01Y1048012D02*
Y1045650D01*
G01X1904921Y1086831D02*
Y1010374D01*
G01X1903740Y989469D02*
Y953012D01*
G01Y1085650D02*
Y1009193D01*
G01X1898228Y953012D02*
Y1085650D01*
G01X1895276Y1090571D02*
Y1011535D01*
G01X1894823Y1008031D02*
Y1009528D01*
G01Y1004881D02*
Y1006378D01*
G01Y1001732D02*
Y1003228D01*
G01Y998582D02*
Y1000079D01*
G01Y995433D02*
Y996929D01*
G01Y992283D02*
Y993780D01*
G01Y989133D02*
Y990630D01*
G01X1894783Y989280D02*
Y989133D01*
G01Y990630D02*
Y990483D01*
G01Y995579D02*
Y995432D01*
G01Y992430D02*
Y992283D01*
G01Y993780D02*
Y993633D01*
G01Y998729D02*
Y998582D01*
G01Y1000079D02*
Y999932D01*
G01Y996930D02*
Y996783D01*
G01Y1001878D02*
Y1001731D01*
G01Y1003229D02*
Y1003082D01*
G01Y1008178D02*
Y1008031D01*
G01Y1009528D02*
Y1009381D01*
G01Y1005028D02*
Y1004881D01*
G01Y1006378D02*
Y1006231D01*
G01X1893878Y1008031D02*
Y1008178D01*
G01Y1009381D02*
Y1009528D01*
G01Y1004881D02*
Y1005028D01*
G01Y1006231D02*
Y1006378D01*
G01Y1001731D02*
Y1001878D01*
G01Y1003082D02*
Y1003229D01*
G01Y998582D02*
Y998729D01*
G01Y999932D02*
Y1000079D01*
G01Y996783D02*
Y996930D01*
G01Y995432D02*
Y995579D01*
G01Y992283D02*
Y992430D01*
G01Y993633D02*
Y993780D01*
G01Y989133D02*
Y989280D01*
G01Y990483D02*
Y990630D01*
G01X1893839D02*
Y989134D01*
G01Y993780D02*
Y992283D01*
G01Y1000079D02*
Y998583D01*
G01Y996929D02*
Y995433D01*
G01Y1003228D02*
Y1001732D01*
G01Y1009528D02*
Y1008031D01*
G01Y1006378D02*
Y1004882D01*
G01X1892657Y990472D02*
Y989291D01*
G01Y996772D02*
Y995591D01*
G01Y993622D02*
Y992441D01*
G01Y999921D02*
Y998740D01*
G01Y1003071D02*
Y1001890D01*
G01Y1009370D02*
Y1008189D01*
G01Y1006220D02*
Y1005039D01*
G01X1892323Y1011535D02*
Y987126D01*
G01X1891929D02*
Y1011535D01*
G01X1888898Y1008189D02*
Y1009370D01*
G01Y1005039D02*
Y1006220D01*
G01Y1001890D02*
Y1003071D01*
G01Y998740D02*
Y999921D01*
G01Y995591D02*
Y996772D01*
G01Y992441D02*
Y993622D01*
G01Y989291D02*
Y990472D01*
G01X1894823Y1008215D02*
X1894822Y1008226D01*
G01X1894823Y1005065D02*
X1894822Y1005076D01*
G01X1894823Y1001916D02*
X1894822Y1001926D01*
G01X1894823Y998766D02*
X1894822Y998777D01*
G01X1894823Y995617D02*
X1894822Y995627D01*
G01X1894823Y992467D02*
X1894822Y992478D01*
G01X1894823Y989317D02*
X1894822Y989328D01*
G01X1907677Y989469D02*
X1908858Y988287D01*
G01X1903740Y989469D02*
X1904921Y988287D01*
G01X1907677Y1009193D02*
X1908858Y1010374D01*
G01X1903740Y1009193D02*
X1904921Y1010374D01*
G01X1893725Y1008228D02*
X1893837Y1008220D01*
G01X1893836Y998775D02*
X1893725Y998780D01*
G01X1893836Y992477D02*
X1893725Y992480D01*
G01X1893836Y1001926D02*
X1893725Y1001929D01*
G01X1912598Y1046142D02*
X1907265D01*
G01X1907264Y1045650D02*
X1908248D01*
G01Y1043012D02*
X1907264D01*
G01X1907265Y1042520D02*
X1912598D01*
G01Y1042480D02*
X1908250D01*
G01X1912598Y1041142D02*
X1907265D01*
G01X1907264Y1040650D02*
X1908248D01*
G01Y1038012D02*
X1907264D01*
G01X1907265Y1037520D02*
X1912598D01*
G01Y1037480D02*
X1908250D01*
G01X1912598Y1036142D02*
X1907265D01*
G01X1907264Y1035650D02*
X1908248D01*
G01Y1033012D02*
X1907264D01*
G01X1907265Y1032520D02*
X1912598D01*
G01Y1032480D02*
X1908250D01*
G01X1912598Y1031142D02*
X1907265D01*
G01X1907264Y1030650D02*
X1908248D01*
G01Y1028012D02*
X1907264D01*
G01X1907265Y1027520D02*
X1912598D01*
G01Y1027480D02*
X1908250D01*
G01X1912598Y1026142D02*
X1907265D01*
G01X1907264Y1025650D02*
X1908248D01*
G01Y1023012D02*
X1907264D01*
G01X1907265Y1022520D02*
X1912598D01*
G01Y1022480D02*
X1908250D01*
G01X1912598Y1021142D02*
X1907265D01*
G01X1908248Y1045946D02*
X1907264Y1045945D01*
G01Y1042715D02*
X1908219Y1042717D01*
G01X1908248Y1040946D02*
X1907264Y1040945D01*
G01Y1037715D02*
X1908219Y1037717D01*
G01X1908248Y1035946D02*
X1907264Y1035945D01*
G01Y1032715D02*
X1908219Y1032717D01*
G01X1908248Y1030946D02*
X1907264Y1030945D01*
G01Y1027715D02*
X1908219Y1027717D01*
G01X1908248Y1025946D02*
X1907264Y1025945D01*
G01Y1022715D02*
X1908219Y1022717D01*
G01X1907264Y1020650D02*
X1908248D01*
G01Y1018012D02*
X1907264D01*
G01X1907265Y1017520D02*
X1912598D01*
G01Y1017480D02*
X1908250D01*
G01X1912598Y1016142D02*
X1907265D01*
G01X1907264Y1015650D02*
X1908248D01*
G01Y1013012D02*
X1907264D01*
G01X1907265Y1012520D02*
X1912598D01*
G01Y1012480D02*
X1908250D01*
G01X1895276Y1011535D02*
X1891929D01*
G01X1912598Y1011142D02*
X1907265D01*
G01X1907264Y1010650D02*
X1908248D01*
G01X1904921Y1010374D02*
X1908858D01*
G01X1894783Y1009567D02*
X1893878D01*
G01X1894823Y1009528D02*
X1893839D01*
G01X1894782Y1009370D02*
X1888898D01*
G01Y1009331D02*
X1894822D01*
G01X1903740Y1009193D02*
X1907677D01*
G01X1894821Y1008228D02*
X1888898D01*
G01X1894782Y1008189D02*
X1888898D01*
G01X1893839Y1008031D02*
X1894823D01*
G01X1893878Y1007992D02*
X1894783D01*
G01Y1006417D02*
X1893878D01*
G01X1894823Y1006378D02*
X1893839D01*
G01X1894782Y1006220D02*
X1888898D01*
G01Y1006181D02*
X1894822D01*
G01X1894821Y1005079D02*
X1888898D01*
G01X1894782Y1005039D02*
X1888898D01*
G01X1893839Y1004882D02*
X1894823D01*
G01X1893878Y1004843D02*
X1894783D01*
G01Y1003268D02*
X1893878D01*
G01X1894823Y1003228D02*
X1893839D01*
G01X1894782Y1003071D02*
X1888898D01*
G01Y1003031D02*
X1894822D01*
G01X1893091Y1001929D02*
X1892657D01*
G01X1894821D02*
X1888898D01*
G01X1894782Y1001890D02*
X1888898D01*
G01X1893839Y1001732D02*
X1894823D01*
G01X1893878Y1001693D02*
X1894783D01*
G01Y1000118D02*
X1893878D01*
G01X1894823Y1000079D02*
X1893839D01*
G01X1894782Y999921D02*
X1888898D01*
G01Y999882D02*
X1894822D01*
G01X1893091Y998780D02*
X1892657D01*
G01X1894821D02*
X1888898D01*
G01X1894782Y998740D02*
X1888898D01*
G01X1893839Y998583D02*
X1894823D01*
G01X1893878Y998543D02*
X1894783D01*
G01Y996969D02*
X1893878D01*
G01X1894823Y996929D02*
X1893839D01*
G01X1894782Y996772D02*
X1888898D01*
G01Y996732D02*
X1894822D01*
G01X1894821Y995630D02*
X1888898D01*
G01X1894782Y995591D02*
X1888898D01*
G01X1893839Y995433D02*
X1894823D01*
G01X1893878Y995394D02*
X1894783D01*
G01Y993819D02*
X1893878D01*
G01X1894823Y993780D02*
X1893839D01*
G01X1894782Y993622D02*
X1888898D01*
G01Y993583D02*
X1894822D01*
G01X1893091Y992480D02*
X1892657D01*
G01X1894821D02*
X1888898D01*
G01X1894782Y992441D02*
X1888898D01*
G01X1893839Y992283D02*
X1894823D01*
G01X1893878Y992244D02*
X1894783D01*
G01Y990669D02*
X1893878D01*
G01X1894823Y990630D02*
X1893839D01*
G01X1894782Y990472D02*
X1888898D01*
G01Y990433D02*
X1894822D01*
G01X1907677Y989469D02*
X1903740D01*
G01X1894821Y989331D02*
X1888898D01*
G01X1894782Y989291D02*
X1888898D01*
G01X1893839Y989134D02*
X1894823D01*
G01X1893878Y989094D02*
X1894783D01*
G01X1908858Y988287D02*
X1904921D01*
G01X1908248Y988012D02*
X1907264D01*
G01X1907265Y987520D02*
X1912598D01*
G01Y987480D02*
X1908250D01*
G01X1895276Y987126D02*
X1891929D01*
G01X1912598Y986142D02*
X1907265D01*
G01X1907264Y985650D02*
X1908248D01*
G01Y983012D02*
X1907264D01*
G01X1907265Y982520D02*
X1912598D01*
G01Y982480D02*
X1908250D01*
G01X1912598Y981142D02*
X1907265D01*
G01X1907264Y980650D02*
X1908248D01*
G01Y978012D02*
X1907264D01*
G01X1907265Y977520D02*
X1912598D01*
G01Y977480D02*
X1908250D01*
G01X1912598Y976142D02*
X1907265D01*
G01X1907264Y975650D02*
X1908248D01*
G01Y973012D02*
X1907264D01*
G01X1907265Y972520D02*
X1912598D01*
G01Y972480D02*
X1908250D01*
G01X1912598Y971142D02*
X1907265D01*
G01X1907264Y970650D02*
X1908248D01*
G01Y968012D02*
X1907264D01*
G01X1907265Y967520D02*
X1912598D01*
G01Y967480D02*
X1908250D01*
G01X1912598Y966142D02*
X1907265D01*
G01X1907264Y965650D02*
X1908248D01*
G01Y963012D02*
X1907264D01*
G01X1907265Y962520D02*
X1912598D01*
G01Y962480D02*
X1908250D01*
G01X1912598Y961142D02*
X1907265D01*
G01X1907264Y960650D02*
X1908248D01*
G01Y958012D02*
X1907264D01*
G01X1907265Y957520D02*
X1912598D01*
G01Y957480D02*
X1908250D01*
G01X1912598Y956142D02*
X1907265D01*
G01X1907264Y955650D02*
X1908248D01*
G01X1903740Y953012D02*
X1898228D01*
G01X1908248Y1020946D02*
X1907264Y1020945D01*
G01Y1017715D02*
X1908219Y1017717D01*
G01X1908248Y1015946D02*
X1907264Y1015945D01*
G01Y1012715D02*
X1908219Y1012717D01*
G01X1908248Y1010946D02*
X1907264Y1010945D01*
G01Y987715D02*
X1908219Y987717D01*
G01X1908248Y985946D02*
X1907264Y985945D01*
G01Y982715D02*
X1908219Y982717D01*
G01X1908248Y980946D02*
X1907264Y980945D01*
G01Y977715D02*
X1908219Y977717D01*
G01X1908248Y975946D02*
X1907264Y975945D01*
G01Y972715D02*
X1908219Y972717D01*
G01X1908248Y970946D02*
X1907264Y970945D01*
G01Y967715D02*
X1908219Y967717D01*
G01X1908248Y965946D02*
X1907264Y965945D01*
G01Y962715D02*
X1908219Y962717D01*
G01X1908248Y960946D02*
X1907264Y960945D01*
G01Y957715D02*
X1908219Y957717D01*
G01X1908248Y955946D02*
X1907264Y955945D01*
G01X1908248Y1081134D02*
Y1081125D01*
G01X1908249Y1081140D02*
X1908248Y1081134D01*
G01X1908251Y1081142D02*
X1908249Y1081140D01*
G01X1908248Y1076134D02*
Y1076125D01*
G01X1908249Y1076140D02*
X1908248Y1076134D01*
G01X1908251Y1076142D02*
X1908249Y1076140D01*
G01X1908248Y1071134D02*
Y1071125D01*
G01X1908249Y1071140D02*
X1908248Y1071134D01*
G01X1908251Y1071142D02*
X1908249Y1071140D01*
G01X1908248Y1066134D02*
Y1066125D01*
G01X1908249Y1066140D02*
X1908248Y1066134D01*
G01X1908251Y1066142D02*
X1908249Y1066140D01*
G01X1908248Y1061134D02*
Y1061125D01*
G01X1908249Y1061140D02*
X1908248Y1061134D01*
G01X1908251Y1061142D02*
X1908249Y1061140D01*
G01X1908248Y1056134D02*
Y1056125D01*
G01X1908249Y1056140D02*
X1908248Y1056134D01*
G01X1908251Y1056142D02*
X1908249Y1056140D01*
G01X1908248Y1051134D02*
Y1051125D01*
G01X1908249Y1051140D02*
X1908248Y1051134D01*
G01X1908251Y1051142D02*
X1908249Y1051140D01*
G01X1908235Y1052511D02*
X1908246Y1052496D01*
G01X1908211Y1052520D02*
X1908235Y1052511D01*
G01Y1057511D02*
X1908246Y1057496D01*
G01X1908211Y1057520D02*
X1908235Y1057511D01*
G01Y1062511D02*
X1908246Y1062496D01*
G01X1908211Y1062520D02*
X1908235Y1062511D01*
G01Y1067511D02*
X1908246Y1067496D01*
G01X1908211Y1067520D02*
X1908235Y1067511D01*
G01Y1072511D02*
X1908246Y1072496D01*
G01X1908211Y1072520D02*
X1908235Y1072511D01*
G01Y1077511D02*
X1908246Y1077496D01*
G01X1908211Y1077520D02*
X1908235Y1077511D01*
G01Y1082511D02*
X1908246Y1082496D01*
G01X1908211Y1082520D02*
X1908235Y1082511D01*
G01X1908215Y1047618D02*
X1908219Y1047717D01*
G01X1908209Y1047546D02*
X1908215Y1047618D01*
G01X1908211Y1047520D02*
X1908209Y1047546D01*
G01X1908215Y1052618D02*
X1908219Y1052717D01*
G01X1908209Y1052546D02*
X1908215Y1052618D01*
G01X1908211Y1052520D02*
X1908209Y1052546D01*
G01X1908215Y1057618D02*
X1908219Y1057717D01*
G01X1908209Y1057546D02*
X1908215Y1057618D01*
G01X1908211Y1057520D02*
X1908209Y1057546D01*
G01X1908215Y1062618D02*
X1908219Y1062717D01*
G01X1908209Y1062546D02*
X1908215Y1062618D01*
G01X1908211Y1062520D02*
X1908209Y1062546D01*
G01X1908215Y1067618D02*
X1908219Y1067717D01*
G01X1908209Y1067546D02*
X1908215Y1067618D01*
G01X1908211Y1067520D02*
X1908209Y1067546D01*
G01X1908215Y1072618D02*
X1908219Y1072717D01*
G01X1908209Y1072546D02*
X1908215Y1072618D01*
G01X1908211Y1072520D02*
X1908209Y1072546D01*
G01X1908215Y1077618D02*
X1908219Y1077717D01*
G01X1908209Y1077546D02*
X1908215Y1077618D01*
G01X1908211Y1077520D02*
X1908209Y1077546D01*
G01X1908215Y1082618D02*
X1908219Y1082717D01*
G01X1908209Y1082546D02*
X1908215Y1082618D01*
G01X1908211Y1082520D02*
X1908209Y1082546D01*
G01X1907265Y1081140D02*
Y1081142D01*
G01X1907264Y1081134D02*
X1907265Y1081140D01*
G01X1907264Y1081126D02*
Y1081134D01*
G01X1907265Y1076140D02*
Y1076142D01*
G01X1907264Y1076134D02*
X1907265Y1076140D01*
G01X1907264Y1076126D02*
Y1076134D01*
G01X1907265Y1071140D02*
Y1071142D01*
G01X1907264Y1071134D02*
X1907265Y1071140D01*
G01X1907264Y1071126D02*
Y1071134D01*
G01X1907265Y1066140D02*
Y1066142D01*
G01X1907264Y1066134D02*
X1907265Y1066140D01*
G01X1907264Y1066126D02*
Y1066134D01*
G01X1907265Y1061140D02*
Y1061142D01*
G01X1907264Y1061134D02*
X1907265Y1061140D01*
G01X1907264Y1061126D02*
Y1061134D01*
G01X1907265Y1056140D02*
Y1056142D01*
G01X1907264Y1056134D02*
X1907265Y1056140D01*
G01X1907264Y1056126D02*
Y1056134D01*
G01X1907265Y1051140D02*
Y1051142D01*
G01X1907264Y1051134D02*
X1907265Y1051140D01*
G01X1907264Y1051126D02*
Y1051134D01*
G01X1908248Y1047487D02*
Y1047494D01*
G01Y1052487D02*
Y1052494D01*
G01X1908249Y1052482D02*
X1908248Y1052487D01*
G01X1908250Y1052480D02*
X1908249Y1052482D01*
G01X1908248Y1057487D02*
Y1057494D01*
G01X1908249Y1057482D02*
X1908248Y1057487D01*
G01X1908250Y1057480D02*
X1908249Y1057482D01*
G01X1908248Y1062487D02*
Y1062494D01*
G01X1908249Y1062482D02*
X1908248Y1062487D01*
G01X1908250Y1062480D02*
X1908249Y1062482D01*
G01X1908248Y1067487D02*
Y1067494D01*
G01X1908249Y1067482D02*
X1908248Y1067487D01*
G01X1908250Y1067480D02*
X1908249Y1067482D01*
G01X1908248Y1072487D02*
Y1072494D01*
G01X1908249Y1072482D02*
X1908248Y1072487D01*
G01X1908250Y1072480D02*
X1908249Y1072482D01*
G01X1908248Y1077487D02*
Y1077494D01*
G01X1908249Y1077482D02*
X1908248Y1077487D01*
G01X1908250Y1077480D02*
X1908249Y1077482D01*
G01X1908248Y1082487D02*
Y1082494D01*
G01X1908249Y1082482D02*
X1908248Y1082487D01*
G01X1908250Y1082480D02*
X1908249Y1082482D01*
G01X1907264Y1047527D02*
Y1047536D01*
G01X1907265Y1047521D02*
X1907264Y1047527D01*
G01X1907265Y1047520D02*
Y1047521D01*
G01X1907264Y1052527D02*
Y1052536D01*
G01X1907265Y1052521D02*
X1907264Y1052527D01*
G01X1907265Y1052520D02*
Y1052521D01*
G01X1907264Y1057527D02*
Y1057536D01*
G01X1907265Y1057521D02*
X1907264Y1057527D01*
G01X1907265Y1057520D02*
Y1057521D01*
G01X1907264Y1062527D02*
Y1062536D01*
G01X1907265Y1062521D02*
X1907264Y1062527D01*
G01X1907265Y1062520D02*
Y1062521D01*
G01X1907264Y1067527D02*
Y1067536D01*
G01X1907265Y1067521D02*
X1907264Y1067527D01*
G01X1907265Y1067520D02*
Y1067521D01*
G01X1907264Y1072527D02*
Y1072536D01*
G01X1907265Y1072521D02*
X1907264Y1072527D01*
G01X1907265Y1072520D02*
Y1072521D01*
G01X1907264Y1077527D02*
Y1077536D01*
G01X1907265Y1077521D02*
X1907264Y1077527D01*
G01X1907265Y1077520D02*
Y1077521D01*
G01X1907264Y1082527D02*
Y1082536D01*
G01X1907265Y1082521D02*
X1907264Y1082527D01*
G01X1907265Y1082520D02*
Y1082521D01*
G01X1908240Y1047663D02*
X1908248Y1047637D01*
G01X1908230Y1047690D02*
X1908240Y1047663D01*
G01X1908219Y1047717D02*
X1908230Y1047690D01*
G01X1908240Y1052663D02*
X1908248Y1052637D01*
G01X1908230Y1052690D02*
X1908240Y1052663D01*
G01X1908219Y1052717D02*
X1908230Y1052690D01*
G01X1908240Y1057663D02*
X1908248Y1057637D01*
G01X1908230Y1057690D02*
X1908240Y1057663D01*
G01X1908219Y1057717D02*
X1908230Y1057690D01*
G01X1908240Y1062663D02*
X1908248Y1062637D01*
G01X1908230Y1062690D02*
X1908240Y1062663D01*
G01X1908219Y1062717D02*
X1908230Y1062690D01*
G01X1908240Y1067663D02*
X1908248Y1067637D01*
G01X1908230Y1067690D02*
X1908240Y1067663D01*
G01X1908219Y1067717D02*
X1908230Y1067690D01*
G01X1908240Y1072663D02*
X1908248Y1072637D01*
G01X1908230Y1072690D02*
X1908240Y1072663D01*
G01X1908219Y1072717D02*
X1908230Y1072690D01*
G01X1908240Y1077663D02*
X1908248Y1077637D01*
G01X1908230Y1077690D02*
X1908240Y1077663D01*
G01X1908219Y1077717D02*
X1908230Y1077690D01*
G01X1908240Y1082663D02*
X1908248Y1082637D01*
G01X1908230Y1082690D02*
X1908240Y1082663D01*
G01X1908219Y1082717D02*
X1908230Y1082690D01*
G01X1908231Y1052515D02*
X1908211Y1052520D01*
G01X1908245Y1052500D02*
X1908231Y1052515D01*
G01X1908250Y1052480D02*
X1908245Y1052500D01*
G01X1908231Y1057515D02*
X1908211Y1057520D01*
G01X1908245Y1057500D02*
X1908231Y1057515D01*
G01X1908250Y1057480D02*
X1908245Y1057500D01*
G01X1908231Y1062515D02*
X1908211Y1062520D01*
G01X1908245Y1062500D02*
X1908231Y1062515D01*
G01X1908250Y1062480D02*
X1908245Y1062500D01*
G01X1908231Y1067515D02*
X1908211Y1067520D01*
G01X1908245Y1067500D02*
X1908231Y1067515D01*
G01X1908250Y1067480D02*
X1908245Y1067500D01*
G01X1908231Y1072515D02*
X1908211Y1072520D01*
G01X1908245Y1072500D02*
X1908231Y1072515D01*
G01X1908250Y1072480D02*
X1908245Y1072500D01*
G01X1908231Y1077515D02*
X1908211Y1077520D01*
G01X1908245Y1077500D02*
X1908231Y1077515D01*
G01X1908250Y1077480D02*
X1908245Y1077500D01*
G01X1908231Y1082515D02*
X1908211Y1082520D01*
G01X1908245Y1082500D02*
X1908231Y1082515D01*
G01X1908250Y1082480D02*
X1908245Y1082500D01*
G01X1906693Y1108012D02*
G03X1906102Y1108602I-590J0D01*
G01X1899409D02*
G03X1898819Y1108012I0J-590D01*
G01X1901575Y1106831D02*
G03Y1104862I0J-985D01*
G01X1903937D02*
G03Y1106831I0J984D01*
G01X1913583Y1107421D02*
G03X1911614Y1109390I-1969J0D01*
G01X1893898D02*
G03X1891929Y1107421I0J-1969D01*
G01X1900197Y1098917D02*
G03X1899016Y1097736I0J-1181D01*
G01X1906496D02*
G03X1905315Y1098917I-1181J0D01*
G01X1904646Y1093642D02*
G03I-1890J0D01*
G01X1905118D02*
G03I-2362J0D01*
G01X1901575Y1094232D02*
X1899265Y1098461D01*
G01X1903937Y1092539D02*
X1905241Y1090571D01*
G01X1908248Y1047494D02*
Y1047502D01*
G01Y1052494D02*
Y1052502D01*
G01Y1057494D02*
Y1057502D01*
G01Y1062494D02*
Y1062502D01*
G01Y1067494D02*
Y1067502D01*
G01Y1072494D02*
Y1072502D01*
G01Y1077494D02*
Y1077502D01*
G01Y1082494D02*
Y1082502D01*
G01X1909429Y1052520D02*
Y1051142D01*
G01Y1057520D02*
Y1056142D01*
G01Y1062520D02*
Y1061142D01*
G01Y1067520D02*
Y1066142D01*
G01Y1072520D02*
Y1071142D01*
G01Y1077520D02*
Y1076142D01*
G01Y1082520D02*
Y1081142D01*
G01X1908248Y1080650D02*
Y1083012D01*
G01Y1075650D02*
Y1078012D01*
G01Y1070650D02*
Y1073012D01*
G01Y1065650D02*
Y1068012D01*
G01Y1060650D02*
Y1063012D01*
G01Y1055650D02*
Y1058012D01*
G01Y1050650D02*
Y1053012D01*
G01Y1052494D02*
Y1052637D01*
G01Y1047494D02*
Y1047637D01*
G01Y1062494D02*
Y1062637D01*
G01Y1057494D02*
Y1057637D01*
G01Y1072494D02*
Y1072637D01*
G01Y1067494D02*
Y1067637D01*
G01Y1082494D02*
Y1082637D01*
G01Y1077494D02*
Y1077637D01*
G01X1907264Y1053012D02*
Y1050650D01*
G01Y1058012D02*
Y1055650D01*
G01Y1063012D02*
Y1060650D01*
G01Y1068012D02*
Y1065650D01*
G01Y1073012D02*
Y1070650D01*
G01Y1078012D02*
Y1075650D01*
G01Y1083012D02*
Y1080650D01*
G01X1906693Y1101909D02*
Y1108012D01*
G01X1906496Y1097736D02*
Y1089193D01*
G01X1903937Y1094232D02*
Y1092539D01*
G01X1901575D02*
Y1094232D01*
G01X1899016Y1089193D02*
Y1097736D01*
G01X1898819Y1101909D02*
Y1108012D01*
G01X1891929Y1107421D02*
Y1091673D01*
G01X1897047Y1086831D02*
X1898228Y1085650D01*
G01X1891929Y1091673D02*
X1895276Y1088327D01*
G01X1900271Y1090571D02*
X1901575Y1092539D01*
G01X1906247Y1098461D02*
X1903937Y1094232D01*
G01X1913583Y1091673D02*
X1910236Y1088327D01*
G01X1903740Y1085650D02*
X1904921Y1086831D01*
G01X1911614Y1109390D02*
X1893898D01*
G01X1906102Y1108602D02*
X1899409D01*
G01X1903937Y1106831D02*
X1901575D01*
G01Y1104862D02*
X1903937D01*
G01X1906693Y1103484D02*
X1898819D01*
G01Y1101909D02*
X1906693D01*
G01X1913583Y1098957D02*
X1891929D01*
G01X1900197Y1098917D02*
X1905315D01*
G01X1901575Y1094232D02*
X1903937D01*
G01X1901575Y1092539D02*
X1903937D01*
G01X1895276Y1090571D02*
X1909646D01*
G01X1895276Y1089193D02*
X1899016D01*
G01X1909646D02*
X1906496D01*
G01X1895276Y1088327D02*
X1910236D01*
G01X1897047Y1086831D02*
X1904921D01*
G01X1898228Y1085650D02*
X1903740D01*
G01X1908248Y1083012D02*
X1907264D01*
G01X1907265Y1082520D02*
X1912598D01*
G01Y1082480D02*
X1908250D01*
G01X1912598Y1081142D02*
X1907265D01*
G01X1907264Y1080650D02*
X1908248D01*
G01Y1078012D02*
X1907264D01*
G01X1907265Y1077520D02*
X1912598D01*
G01Y1077480D02*
X1908250D01*
G01X1912598Y1076142D02*
X1907265D01*
G01X1907264Y1075650D02*
X1908248D01*
G01Y1073012D02*
X1907264D01*
G01X1907265Y1072520D02*
X1912598D01*
G01Y1072480D02*
X1908250D01*
G01X1912598Y1071142D02*
X1907265D01*
G01X1907264Y1070650D02*
X1908248D01*
G01Y1068012D02*
X1907264D01*
G01X1907265Y1067520D02*
X1912598D01*
G01Y1067480D02*
X1908250D01*
G01X1912598Y1066142D02*
X1907265D01*
G01X1907264Y1065650D02*
X1908248D01*
G01Y1063012D02*
X1907264D01*
G01X1907265Y1062520D02*
X1912598D01*
G01Y1062480D02*
X1908250D01*
G01X1912598Y1061142D02*
X1907265D01*
G01X1907264Y1060650D02*
X1908248D01*
G01Y1058012D02*
X1907264D01*
G01X1907265Y1057520D02*
X1912598D01*
G01Y1057480D02*
X1908250D01*
G01X1912598Y1056142D02*
X1907265D01*
G01X1907264Y1055650D02*
X1908248D01*
G01Y1053012D02*
X1907264D01*
G01X1907265Y1052520D02*
X1912598D01*
G01Y1052480D02*
X1908250D01*
G01X1912598Y1051142D02*
X1907265D01*
G01X1907264Y1050650D02*
X1908248D01*
G01Y1048012D02*
X1907264D01*
G01X1907265Y1047520D02*
X1912598D01*
G01Y1047480D02*
X1908250D01*
G01X1907264Y1082715D02*
X1908219Y1082717D01*
G01X1908248Y1080946D02*
X1907264Y1080945D01*
G01Y1077715D02*
X1908219Y1077717D01*
G01X1908248Y1075946D02*
X1907264Y1075945D01*
G01Y1072715D02*
X1908219Y1072717D01*
G01X1908248Y1070946D02*
X1907264Y1070945D01*
G01Y1067715D02*
X1908219Y1067717D01*
G01X1908248Y1065946D02*
X1907264Y1065945D01*
G01Y1062715D02*
X1908219Y1062717D01*
G01X1908248Y1060946D02*
X1907264Y1060945D01*
G01Y1057715D02*
X1908219Y1057717D01*
G01X1908248Y1055946D02*
X1907264Y1055945D01*
G01Y1052715D02*
X1908219Y1052717D01*
G01X1908248Y1050946D02*
X1907264Y1050945D01*
G01Y1047715D02*
X1908219Y1047717D01*
G01X1869094Y1519685D02*
G03X1865157Y1515748I0J-3937D01*
G01X1919094Y1519685D02*
X1869094D01*
G01X1831693Y1515748D02*
G03X1827756Y1519685I-3937J0D01*
G01X1831693Y1509055D02*
Y1515748D01*
G01Y1509055D02*
G03X1835630Y1505118I3937J0D01*
G01X1861220D02*
X1835630D01*
G01X1861220D02*
G03X1865157Y1509055I0J3937D01*
G01Y1515748D02*
Y1509055D01*
G01X1861220Y1505118D02*
G03X1865157Y1509055I0J3937D01*
G01X1831693D02*
G03X1835630Y1505118I3937J0D01*
G01X1831693Y1515748D02*
G03X1827756Y1519685I-3937J0D01*
G01X1869094D02*
G03X1865157Y1515748I0J-3937D01*
G01D02*
Y1509055D01*
G01X1831693Y1515748D02*
Y1509055D01*
G01X1919094Y1519685D02*
X1869094D01*
G01X1835630Y1505118D02*
X1861220D01*
G01X1842058Y1789409D02*
X2349932D01*
G01X1913812Y-295751D02*
Y-100229D01*
G01X1934843Y3937D02*
Y1456693D01*
G01X1930906Y0D02*
G03X1934843Y3937I0J3937D01*
G01X1930906Y0D02*
G03X1934843Y3937I0J3937D01*
G01D02*
Y1456693D01*
G01X1913583Y25728D02*
Y41476D01*
G01X1912598Y80630D02*
Y82008D01*
G01Y75630D02*
Y77008D01*
G01Y70630D02*
Y72008D01*
G01Y65630D02*
Y67008D01*
G01Y60630D02*
Y62008D01*
G01Y55630D02*
Y57008D01*
G01Y50630D02*
Y52008D01*
G01X1913583Y186161D02*
Y201909D01*
G01X1912598Y175630D02*
Y177008D01*
G01Y170630D02*
Y172008D01*
G01Y165630D02*
Y167008D01*
G01Y160630D02*
Y162008D01*
G01Y155630D02*
Y157008D01*
G01Y150630D02*
Y152008D01*
G01Y145630D02*
Y147008D01*
G01Y140630D02*
Y142008D01*
G01Y135630D02*
Y137008D01*
G01Y130630D02*
Y132008D01*
G01Y125630D02*
Y127008D01*
G01Y120630D02*
Y122008D01*
G01Y115630D02*
Y117008D01*
G01Y110630D02*
Y112008D01*
G01Y105630D02*
Y107008D01*
G01X1913583Y478484D02*
Y494232D01*
G01X1912598Y568386D02*
Y569764D01*
G01Y563386D02*
Y564764D01*
G01Y558386D02*
Y559764D01*
G01Y533386D02*
Y534764D01*
G01Y528386D02*
Y529764D01*
G01Y523386D02*
Y524764D01*
G01Y518386D02*
Y519764D01*
G01Y513386D02*
Y514764D01*
G01Y508386D02*
Y509764D01*
G01Y503386D02*
Y504764D01*
G01X1913583Y638917D02*
Y654665D01*
G01X1912598Y628386D02*
Y629764D01*
G01Y623386D02*
Y624764D01*
G01Y618386D02*
Y619764D01*
G01Y613386D02*
Y614764D01*
G01Y608386D02*
Y609764D01*
G01Y603386D02*
Y604764D01*
G01Y598386D02*
Y599764D01*
G01Y593386D02*
Y594764D01*
G01Y588386D02*
Y589764D01*
G01Y583386D02*
Y584764D01*
G01Y578386D02*
Y579764D01*
G01Y573386D02*
Y574764D01*
G01X1913583Y931240D02*
Y946988D01*
G01X1912598Y1046142D02*
Y1047520D01*
G01Y1041142D02*
Y1042520D01*
G01Y1036142D02*
Y1037520D01*
G01Y1031142D02*
Y1032520D01*
G01Y1026142D02*
Y1027520D01*
G01Y1021142D02*
Y1022520D01*
G01Y1016142D02*
Y1017520D01*
G01Y1011142D02*
Y1012520D01*
G01Y986142D02*
Y987520D01*
G01Y981142D02*
Y982520D01*
G01Y976142D02*
Y977520D01*
G01Y971142D02*
Y972520D01*
G01Y966142D02*
Y967520D01*
G01Y961142D02*
Y962520D01*
G01Y956142D02*
Y957520D01*
G01X1913583Y1091673D02*
Y1107421D01*
G01X1912598Y1081142D02*
Y1082520D01*
G01Y1076142D02*
Y1077520D01*
G01Y1071142D02*
Y1072520D01*
G01Y1066142D02*
Y1067520D01*
G01Y1061142D02*
Y1062520D01*
G01Y1056142D02*
Y1057520D01*
G01Y1051142D02*
Y1052520D01*
G01X1934843Y1460630D02*
Y1603810D01*
G01X1923031Y1515748D02*
G03X1919094Y1519685I-3937J0D01*
G01X1923031Y1464567D02*
Y1515748D01*
G01Y1464567D02*
G03X1926969Y1460630I3937J0D01*
G01X1930906D02*
X1926969D01*
G01X1934843Y1456693D02*
G03X1930906Y1460630I-3937J0D01*
G01X1923031Y1464567D02*
G03X1926969Y1460630I3937J0D01*
G01X1923031Y1515748D02*
G03X1919094Y1519685I-3937J0D01*
G01X1934843Y1456693D02*
G03X1930906Y1460630I-3937J0D01*
G01X1923031Y1515748D02*
Y1464567D01*
G01X1930906Y1460630D02*
X1926969D01*
G01X2015005Y-369410D02*
Y-388347D01*
G01X2030207Y-369410D02*
X2680641D01*
G01X2015951Y1808346D02*
Y1789409D01*
G01X2235621Y-369410D02*
Y-388347D01*
G01X2252395Y-205306D02*
Y-295436D01*
G01X2256063Y-250625D02*
X2669718D01*
G01X2235621Y1808346D02*
Y1789409D01*
G01X2349932D02*
X2680640D01*
G01X2455290Y-369410D02*
Y-388347D01*
G01X2441372Y-205306D02*
Y-295436D01*
G01X2455290Y1808346D02*
Y1789409D01*
G01X2669718Y-356015D02*
Y-100229D01*
G01X2699577Y1808346D02*
Y-388347D01*
G01X2680640Y1789409D02*
Y-369410D01*
G01X2680641Y-224725D02*
Y-369410D01*
G01X2680640Y-153528D02*
X2699577D01*
G01X2680640Y62354D02*
X2699577D01*
G01X2680640Y278236D02*
X2699577D01*
G01X2680640Y494118D02*
X2699577D01*
G01X2680640Y710000D02*
X2699577D01*
G01X2680640Y925881D02*
X2699577D01*
G01X2680640Y1141763D02*
X2699577D01*
G01X2680640Y1357645D02*
X2699577D01*
G01X2680451Y1573527D02*
X2699388D01*
G01X2680640Y1789409D02*
Y1694921D01*
M02*
